(kicad_pcb (version 20221018) (generator pcbnew)

  (general
    (thickness 1.7403)
  )

  (paper "A4")
  (title_block
    (title "Data Center RDIMM DDR4 Tester")
    (date "2024-09-30")
    (rev "1.2.4")
  )

  (layers
    (0 "F.Cu" signal)
    (1 "In1.Cu" power)
    (2 "In2.Cu" signal)
    (3 "In3.Cu" power)
    (4 "In4.Cu" power)
    (5 "In5.Cu" signal)
    (6 "In6.Cu" power)
    (7 "In7.Cu" signal)
    (8 "In8.Cu" power)
    (9 "In9.Cu" signal)
    (10 "In10.Cu" power)
    (31 "B.Cu" signal)
    (32 "B.Adhes" user "B.Adhesive")
    (33 "F.Adhes" user "F.Adhesive")
    (34 "B.Paste" user)
    (35 "F.Paste" user)
    (36 "B.SilkS" user "B.Silkscreen")
    (37 "F.SilkS" user "F.Silkscreen")
    (38 "B.Mask" user)
    (39 "F.Mask" user)
    (40 "Dwgs.User" user "User.Drawings")
    (41 "Cmts.User" user "User.Comments")
    (42 "Eco1.User" user "User.Eco1")
    (43 "Eco2.User" user "User.Eco2")
    (44 "Edge.Cuts" user)
    (45 "Margin" user)
    (46 "B.CrtYd" user "B.Courtyard")
    (47 "F.CrtYd" user "F.Courtyard")
    (48 "B.Fab" user)
    (49 "F.Fab" user)
  )

  (setup
    (stackup
      (layer "F.SilkS" (type "Top Silk Screen") (color "White"))
      (layer "F.Paste" (type "Top Solder Paste"))
      (layer "F.Mask" (type "Top Solder Mask") (color "Black") (thickness 0.01))
      (layer "F.Cu" (type "copper") (thickness 0.035))
      (layer "dielectric 1" (type "prepreg") (thickness 0.074) (material "1080(69%)+106(74%)S1000-2MB") (epsilon_r 3.9) (loss_tangent 0.009))
      (layer "In1.Cu" (type "copper") (thickness 0.035))
      (layer "dielectric 2" (type "prepreg") (thickness 0.112) (material "1080(69%)+106(74%)S1000-2MB") (epsilon_r 3.9) (loss_tangent 0.009))
      (layer "In2.Cu" (type "copper") (thickness 0.035))
      (layer "dielectric 3" (type "prepreg") (thickness 0.126) (material "1080(69%)+106(74%)S1000-2MB") (epsilon_r 3.9) (loss_tangent 0.009))
      (layer "In3.Cu" (type "copper") (thickness 0.035))
      (layer "dielectric 4" (type "prepreg") (thickness 0.126) (material "1080(69%)+106(74%)S1000-2MB") (epsilon_r 3.9) (loss_tangent 0.009))
      (layer "In4.Cu" (type "copper") (thickness 0.035))
      (layer "dielectric 5" (type "core") (thickness 0.13) (material "S1000-2M") (epsilon_r 4.9) (loss_tangent 0.009))
      (layer "In5.Cu" (type "copper") (thickness 0.035))
      (layer "dielectric 6" (type "prepreg") (thickness 0.106) (material "1080(69%)+106(74%)S1000-2MB") (epsilon_r 3.9) (loss_tangent 0.009))
      (layer "In6.Cu" (type "copper") (thickness 0.035))
      (layer "dielectric 7" (type "prepreg") (thickness 0.2) (material "S1000-2M") (epsilon_r 4.9) (loss_tangent 0.009))
      (layer "In7.Cu" (type "copper") (thickness 0.035))
      (layer "dielectric 8" (type "core") (thickness 0.114) (material "106(74%)+1080(69%)S1000-2MB") (epsilon_r 3.9) (loss_tangent 0.009))
      (layer "In8.Cu" (type "copper") (thickness 0.035))
      (layer "dielectric 9" (type "prepreg") (thickness 0.1263) (material "106(74%)+1080(69%)S1000-2MB") (epsilon_r 3.9) (loss_tangent 0.009))
      (layer "In9.Cu" (type "copper") (thickness 0.035))
      (layer "dielectric 10" (type "core") (thickness 0.112) (material "106(74%)+1080(69%)S1000-2MB") (epsilon_r 3.9) (loss_tangent 0.009))
      (layer "In10.Cu" (type "copper") (thickness 0.035))
      (layer "dielectric 11" (type "prepreg") (thickness 0.074) (material "106(74%)+1080(69%)S1000-2MB") (epsilon_r 3.9) (loss_tangent 0.009))
      (layer "B.Cu" (type "copper") (thickness 0.035))
      (layer "B.Mask" (type "Bottom Solder Mask") (color "Black") (thickness 0.01))
      (layer "B.Paste" (type "Bottom Solder Paste"))
      (layer "B.SilkS" (type "Bottom Silk Screen") (color "White"))
      (copper_finish "ENIG")
      (dielectric_constraints no)
    )
    (pad_to_mask_clearance 0)
    (aux_axis_origin 251.9 83.2)
    (pcbplotparams
      (layerselection 0x0001000_7ffff801)
      (plot_on_all_layers_selection 0x0000000_00000000)
      (disableapertmacros false)
      (usegerberextensions false)
      (usegerberattributes false)
      (usegerberadvancedattributes false)
      (creategerberjobfile false)
      (dashed_line_dash_ratio 12.000000)
      (dashed_line_gap_ratio 3.000000)
      (svgprecision 6)
      (plotframeref false)
      (viasonmask false)
      (mode 1)
      (useauxorigin false)
      (hpglpennumber 1)
      (hpglpenspeed 20)
      (hpglpendiameter 15.000000)
      (dxfpolygonmode true)
      (dxfimperialunits true)
      (dxfusepcbnewfont true)
      (psnegative false)
      (psa4output false)
      (plotreference true)
      (plotvalue true)
      (plotinvisibletext false)
      (sketchpadsonfab false)
      (subtractmaskfromsilk false)
      (outputformat 1)
      (mirror false)
      (drillshape 0)
      (scaleselection 1)
      (outputdirectory "./fab")
    )
  )

  (net 0 "")
  (net 1 "Net-(U2-SW)")
  (net 2 "Net-(U4-BST)")
  (net 3 "Net-(U4-SW)")
  (net 4 "Net-(U10-TADJ)")
  (net 5 "Net-(U6-XO)")
  (net 6 "Net-(U6-XI)")
  (net 7 "Net-(U5-BST)")
  (net 8 "Net-(U5-SW)")
  (net 9 "GND")
  (net 10 "DBG_USB_P")
  (net 11 "DBG_USB_N")
  (net 12 "TCK_JTAG")
  (net 13 "TMS_JTAG")
  (net 14 "TDI_JTAG")
  (net 15 "TDO_JTAG")
  (net 16 "LED_LINK")
  (net 17 "LED_SPD")
  (net 18 "MODE2")
  (net 19 "QSPI_DQ0")
  (net 20 "QSPI_DQ1")
  (net 21 "QSPI_DQ2")
  (net 22 "QSPI_DQ3")
  (net 23 "MODE0")
  (net 24 "MODE1")
  (net 25 "DONE")
  (net 26 "ETH_RXD0")
  (net 27 "ETH_RXD1")
  (net 28 "ETH_RSTN")
  (net 29 "ETH_MDIO")
  (net 30 "ETH_REF_CLK")
  (net 31 "ETH_TXD1")
  (net 32 "ETH_TXD2")
  (net 33 "ETH_TXD3")
  (net 34 "ETH_TX_CLK")
  (net 35 "ETH_TX_EN")
  (net 36 "ETH_TXD0")
  (net 37 "ETH_RXD3")
  (net 38 "ETH_RX_DV")
  (net 39 "ETH_MDC")
  (net 40 "ETH_RX_CLK")
  (net 41 "ETH_RXD2")
  (net 42 "C_TMDS_CLK_P")
  (net 43 "C_TMDS_CLK_N")
  (net 44 "C_TMDS_D0_N")
  (net 45 "C_TMDS_D0_P")
  (net 46 "C_TMDS_D1_P")
  (net 47 "C_TMDS_D2_N")
  (net 48 "C_TMDS_D2_P")
  (net 49 "Net-(U9-BST)")
  (net 50 "Net-(U9-SW)")
  (net 51 "Net-(U12-BST)")
  (net 52 "Net-(U12-SW)")
  (net 53 "Net-(IC1-SS{slash}TR)")
  (net 54 "C_TMDS_D1_N")
  (net 55 "TMDS_CLK_P")
  (net 56 "TMDS_CLK_N")
  (net 57 "TMDS_D0_P")
  (net 58 "TMDS_D0_N")
  (net 59 "TMDS_D1_P")
  (net 60 "TMDS_D1_N")
  (net 61 "TMDS_D2_P")
  (net 62 "TMDS_D2_N")
  (net 63 "Net-(D5-Pad2)")
  (net 64 "Net-(D6-Pad2)")
  (net 65 "Net-(D7-Pad2)")
  (net 66 "Net-(D8-Pad2)")
  (net 67 "USR_LED1")
  (net 68 "USR_LED3")
  (net 69 "Net-(IC1-COMP)")
  (net 70 "USR_LED2")
  (net 71 "Net-(IC1-BOOT)")
  (net 72 "USR_LED4")
  (net 73 "Net-(IC1-SW)")
  (net 74 "USR_LED5")
  (net 75 "Net-(U7-V_{PLL})")
  (net 76 "Net-(U7-V_{PHY})")
  (net 77 "VDDQ")
  (net 78 "Net-(D9-Pad2)")
  (net 79 "PUDC_B")
  (net 80 "Net-(U7-OSCI)")
  (net 81 "Net-(U7-OSCO)")
  (net 82 "SD_DAT1")
  (net 83 "SD_DAT0")
  (net 84 "SD_CLK")
  (net 85 "SD_CMD")
  (net 86 "SD_DAT3")
  (net 87 "SD_DAT2")
  (net 88 "SD_CD")
  (net 89 "Net-(D1-Pad2)")
  (net 90 "Net-(D10-Pad2)")
  (net 91 "PROGRAM_B")
  (net 92 "Net-(J2-P4)")
  (net 93 "INIT_B")
  (net 94 "Net-(J2-P5)")
  (net 95 "FCS_B")
  (net 96 "CCLK")
  (net 97 "unconnected-(D4-D2+-Pad12)")
  (net 98 "unconnected-(D4-D2--Pad11)")
  (net 99 "EMCCLK")
  (net 100 "CFGBVS")
  (net 101 "Net-(D17-C_{R})")
  (net 102 "Net-(D17-C_{G})")
  (net 103 "VIN")
  (net 104 "VCC5V0")
  (net 105 "Net-(C35-Pad1)")
  (net 106 "Net-(D17-C_{Y})")
  (net 107 "Net-(C172-Pad1)")
  (net 108 "Net-(U27-~{OE})")
  (net 109 "Net-(IC1-RT{slash}CLK)")
  (net 110 "Net-(IC1-FB)")
  (net 111 "unconnected-(IC3-NC-Pad14)")
  (net 112 "Net-(J2-LED_GRN+)")
  (net 113 "Net-(J2-LED_YEL+)")
  (net 114 "unconnected-(J5E-DP9_{M2C}+-PadB4)")
  (net 115 "Net-(PWR1-Pad2)")
  (net 116 "unconnected-(J5E-DP9_{M2C}--PadB5)")
  (net 117 "unconnected-(J5E-DP8_{M2C}+-PadB8)")
  (net 118 "Net-(R126-Pad2)")
  (net 119 "/Supply/~{INT}")
  (net 120 "~{PERST}")
  (net 121 "unconnected-(J5E-DP8_{M2C}--PadB9)")
  (net 122 "unconnected-(J5E-DP9_{C2M}+-PadB24)")
  (net 123 "unconnected-(J5E-DP9_{C2M}--PadB25)")
  (net 124 "unconnected-(J5E-DP8_{C2M}+-PadB28)")
  (net 125 "unconnected-(J5E-DP8_{C2M}--PadB29)")
  (net 126 "AUX_JTAG_TCK")
  (net 127 "unconnected-(J5E-RES0-PadB40)")
  (net 128 "AUX_JTAG_TDI")
  (net 129 "unconnected-(J5D-LA06+-PadC10)")
  (net 130 "unconnected-(J5D-LA06--PadC11)")
  (net 131 "AUX_JTAG_TMS")
  (net 132 "unconnected-(J5D-LA10+-PadC14)")
  (net 133 "AUX_JTAG_RST")
  (net 134 "unconnected-(J5D-LA10--PadC15)")
  (net 135 "UART0_RX")
  (net 136 "unconnected-(J5D-LA14+-PadC18)")
  (net 137 "UART0_TX")
  (net 138 "unconnected-(J5D-LA14--PadC19)")
  (net 139 "UART1_RX")
  (net 140 "unconnected-(J5D-LA18_{CC}+-PadC22)")
  (net 141 "UART1_TX")
  (net 142 "unconnected-(J5D-LA18_{CC}--PadC23)")
  (net 143 "3V3_SYS")
  (net 144 "1V8_SYS")
  (net 145 "1V8_FT")
  (net 146 "AUX_JTAG_TDO")
  (net 147 "1V0_SYS")
  (net 148 "unconnected-(J5D-LA27+-PadC26)")
  (net 149 "HOT_SWAP_BUTTON")
  (net 150 "unconnected-(J5D-LA27--PadC27)")
  (net 151 "/Supply/VCC_INT_EN")
  (net 152 "/Supply/VCC_AUX_EN")
  (net 153 "/Supply/VCC_IO_EN")
  (net 154 "HR_RST")
  (net 155 "HR_CS")
  (net 156 "HR_DQ1")
  (net 157 "HR_DQ0")
  (net 158 "HR_RW")
  (net 159 "HR_CKN")
  (net 160 "HR_DQ5")
  (net 161 "HR_DQ4")
  (net 162 "HR_DQ7")
  (net 163 "HR_DQ6")
  (net 164 "HR_CKP")
  (net 165 "HR_DQ3")
  (net 166 "HR_DQ2")
  (net 167 "/Supply/SYS_EN")
  (net 168 "/Ethernet/ETH3_P")
  (net 169 "/Ethernet/ETH2_P")
  (net 170 "/Ethernet/ETH1_P")
  (net 171 "/Ethernet/ETH4_P")
  (net 172 "/Ethernet/ETH2_N")
  (net 173 "/Ethernet/ETH1_N")
  (net 174 "/Ethernet/ETH3_N")
  (net 175 "/Ethernet/ETH4_N")
  (net 176 "VCC1V2")
  (net 177 "/Ethernet/AVDDL")
  (net 178 "/Ethernet/AVDDL_PLL")
  (net 179 "/Ethernet/AVDDH")
  (net 180 "unconnected-(J5D-GA0-PadC34)")
  (net 181 "Net-(J5D-PG_{C2M})")
  (net 182 "unconnected-(J5D-LA01_{CC}--PadD9)")
  (net 183 "ETH_INT_N")
  (net 184 "VPP")
  (net 185 "VDDSPD")
  (net 186 "VTT")
  (net 187 "~{EVENT}")
  (net 188 "DQ43")
  (net 189 "DQ41")
  (net 190 "DQ49")
  (net 191 "DQ61")
  (net 192 "DQ57")
  (net 193 "DQ51")
  (net 194 "DQ33")
  (net 195 "SA2")
  (net 196 "DQ59")
  (net 197 "DQ63")
  (net 198 "~{CS3}\\C1,NC")
  (net 199 "PARITY")
  (net 200 "A17")
  (net 201 "NC\\C2")
  (net 202 "DQ39")
  (net 203 "DQ45")
  (net 204 "DQ53")
  (net 205 "DQ47")
  (net 206 "DQ55")
  (net 207 "A13")
  (net 208 "A10\\AP")
  (net 209 "~{SAVE}")
  (net 210 "~{WE}\\A14")
  (net 211 "BA1")
  (net 212 "DQ37")
  (net 213 "DQ35")
  (net 214 "SA1")
  (net 215 "DQ56")
  (net 216 "DQ58")
  (net 217 "DQ62")
  (net 218 "SA0")
  (net 219 "DQ50")
  (net 220 "DQ54")
  (net 221 "DQ60")
  (net 222 "DQ46")
  (net 223 "DQ52")
  (net 224 "DQ42")
  (net 225 "DQ48")
  (net 226 "DQ44")
  (net 227 "DQ34")
  (net 228 "DQ38")
  (net 229 "DQ40")
  (net 230 "~{CS2}\\C0")
  (net 231 "ODT1\\NC")
  (net 232 "DQ32")
  (net 233 "DQ36")
  (net 234 "~{CS1}\\NC")
  (net 235 "ODT0")
  (net 236 "~{CAS}\\A15")
  (net 237 "~{CS0}")
  (net 238 "~{RAS}\\A16")
  (net 239 "BA0")
  (net 240 "A0")
  (net 241 "DQ4")
  (net 242 "DQ0")
  (net 243 "DQ2")
  (net 244 "DQ6")
  (net 245 "DQ12")
  (net 246 "DQ8")
  (net 247 "DQ14")
  (net 248 "DQ10")
  (net 249 "DQ20")
  (net 250 "DQ16")
  (net 251 "DQ22")
  (net 252 "DQ28")
  (net 253 "DQ18")
  (net 254 "DQ24")
  (net 255 "DQ30")
  (net 256 "DQ26")
  (net 257 "CB4")
  (net 258 "CB0")
  (net 259 "CB6")
  (net 260 "CB2")
  (net 261 "CKE0")
  (net 262 "~{RESET}")
  (net 263 "BG0")
  (net 264 "~{ACT}")
  (net 265 "A12\\~{BC}")
  (net 266 "A9")
  (net 267 "A6")
  (net 268 "A8")
  (net 269 "A3")
  (net 270 "A1")
  (net 271 "DQ25")
  (net 272 "CB1")
  (net 273 "DQ15")
  (net 274 "DQ11")
  (net 275 "DQ13")
  (net 276 "A5")
  (net 277 "DQ23")
  (net 278 "CB5")
  (net 279 "DQ31")
  (net 280 "BG1")
  (net 281 "DQ17")
  (net 282 "CB7")
  (net 283 "A11")
  (net 284 "A7")
  (net 285 "DQ29")
  (net 286 "DQ19")
  (net 287 "DQ27")
  (net 288 "DQ1")
  (net 289 "A4")
  (net 290 "CKE1\\NC")
  (net 291 "A2")
  (net 292 "DQ3")
  (net 293 "DQ9")
  (net 294 "DQ21")
  (net 295 "CB3")
  (net 296 "~{ALERT}")
  (net 297 "DQ7")
  (net 298 "DQ5")
  (net 299 "VCC0V6")
  (net 300 "VCC1V0")
  (net 301 "VDD1V2")
  (net 302 "VCC1V8")
  (net 303 "VCC2V5")
  (net 304 "VCC3V3")
  (net 305 "/Supply/VTTREF")
  (net 306 "1V2_SYS")
  (net 307 "5V0_SYS")
  (net 308 "NC")
  (net 309 "VRN")
  (net 310 "VRP")
  (net 311 "GCLK100")
  (net 312 "VREF_33")
  (net 313 "unconnected-(J5D-LA05+-PadD11)")
  (net 314 "DQS0_P")
  (net 315 "DQS0_N")
  (net 316 "DQS9_P")
  (net 317 "DQS9_N")
  (net 318 "DQS1_P")
  (net 319 "DQS10_P")
  (net 320 "DQS1_N")
  (net 321 "DQS10_N")
  (net 322 "DQS2_P")
  (net 323 "DQS11_P")
  (net 324 "DQS2_N")
  (net 325 "DQS11_N")
  (net 326 "DQS3_P")
  (net 327 "DQS12_P")
  (net 328 "DQS3_N")
  (net 329 "DQS12_N")
  (net 330 "DQS4_P")
  (net 331 "DQS13_P")
  (net 332 "DQS4_N")
  (net 333 "DQS13_N")
  (net 334 "DQS5_P")
  (net 335 "DQS14_P")
  (net 336 "DQS5_N")
  (net 337 "DQS14_N")
  (net 338 "DQS6_P")
  (net 339 "DQS15_P")
  (net 340 "DQS6_N")
  (net 341 "DQS15_N")
  (net 342 "DQS7_P")
  (net 343 "DQS16_P")
  (net 344 "DQS7_N")
  (net 345 "DQS16_N")
  (net 346 "DQS8_P")
  (net 347 "DQS17_P")
  (net 348 "DQS8_N")
  (net 349 "DQS17_N")
  (net 350 "SDA_2V5")
  (net 351 "SCL_2V5")
  (net 352 "unconnected-(J5D-LA05--PadD12)")
  (net 353 "CK1_P")
  (net 354 "CK1_N")
  (net 355 "CK0_P")
  (net 356 "CK0_N")
  (net 357 "SDA_3V3")
  (net 358 "SCL_3V3")
  (net 359 "unconnected-(J5D-LA09+-PadD14)")
  (net 360 "/Ethernet/VDD")
  (net 361 "unconnected-(J5D-LA09--PadD15)")
  (net 362 "unconnected-(J5D-LA13+-PadD17)")
  (net 363 "unconnected-(J5D-LA13--PadD18)")
  (net 364 "unconnected-(J5D-LA17_{CC}+-PadD20)")
  (net 365 "unconnected-(J5D-LA17_{CC}--PadD21)")
  (net 366 "unconnected-(J5D-LA23+-PadD23)")
  (net 367 "unconnected-(J5D-LA23--PadD24)")
  (net 368 "unconnected-(J5D-LA26+-PadD26)")
  (net 369 "unconnected-(J5D-LA26--PadD27)")
  (net 370 "Net-(R39-Pad2)")
  (net 371 "unconnected-(J5D-3P3VAUX-PadD32)")
  (net 372 "unconnected-(J5D-GA1-PadD35)")
  (net 373 "unconnected-(J5C-HA01_{CC}+-PadE2)")
  (net 374 "unconnected-(J5C-HA01_{CC}--PadE3)")
  (net 375 "unconnected-(J5C-HA05+-PadE6)")
  (net 376 "unconnected-(J5C-HA05--PadE7)")
  (net 377 "unconnected-(J5C-HA09+-PadE9)")
  (net 378 "unconnected-(J5C-HA09--PadE10)")
  (net 379 "unconnected-(J1-Pad14)")
  (net 380 "unconnected-(J1-Pad12)")
  (net 381 "/Ethernet/VSS")
  (net 382 "unconnected-(J5C-HA13+-PadE12)")
  (net 383 "unconnected-(J8-Pad2)")
  (net 384 "unconnected-(J5C-HA13--PadE13)")
  (net 385 "unconnected-(J5C-HA16+-PadE15)")
  (net 386 "unconnected-(J5C-HA16--PadE16)")
  (net 387 "unconnected-(J5C-HA20+-PadE18)")
  (net 388 "unconnected-(J5C-HA20--PadE19)")
  (net 389 "unconnected-(J5C-HB03+-PadE21)")
  (net 390 "unconnected-(J5C-HB03--PadE22)")
  (net 391 "unconnected-(J5C-HB05+-PadE24)")
  (net 392 "unconnected-(J5C-HB05--PadE25)")
  (net 393 "unconnected-(J5C-HB09+-PadE27)")
  (net 394 "unconnected-(J5C-HB09--PadE28)")
  (net 395 "unconnected-(J5C-HB13+-PadE30)")
  (net 396 "unconnected-(J5C-HB13--PadE31)")
  (net 397 "unconnected-(J5C-HB19+-PadE33)")
  (net 398 "unconnected-(J5C-HB19--PadE34)")
  (net 399 "unconnected-(J5C-HB21+-PadE36)")
  (net 400 "VREFCA")
  (net 401 "unconnected-(J5C-HB21--PadE37)")
  (net 402 "unconnected-(J5C-VADJ-PadE39)")
  (net 403 "GTR_REFCLK0_C_P")
  (net 404 "/FPGA banks 115-116/GTR_REFCLK0_P")
  (net 405 "Net-(J5C-PG_{M2C})")
  (net 406 "FMC_IO_3_N")
  (net 407 "FMC_IO_2_P")
  (net 408 "GTR_REFCLK0_C_N")
  (net 409 "/FPGA banks 115-116/GTR_REFCLK0_N")
  (net 410 "/FMC HPC/GTX_TX0_C_P")
  (net 411 "GTX_TX0_P")
  (net 412 "/FMC HPC/GTX_TX0_C_N")
  (net 413 "unconnected-(J5C-HA00_{CC}+-PadF4)")
  (net 414 "unconnected-(J5C-HA00_{CC}--PadF5)")
  (net 415 "unconnected-(J5C-HA04+-PadF7)")
  (net 416 "FMC_IO_2_N")
  (net 417 "FMC_IO_1_N")
  (net 418 "GTX_TX0_N")
  (net 419 "/FMC HPC/GTX_TX1_C_P")
  (net 420 "GTX_TX1_P")
  (net 421 "/FMC HPC/GTX_TX1_C_N")
  (net 422 "unconnected-(J5C-HA04--PadF8)")
  (net 423 "unconnected-(J5C-HA08+-PadF10)")
  (net 424 "unconnected-(J5C-HA08--PadF11)")
  (net 425 "FMC_IO_3_P")
  (net 426 "FMC_IO_4_N")
  (net 427 "FMC_IO_1_P")
  (net 428 "FMC_IO_5_P")
  (net 429 "GTX_TX1_N")
  (net 430 "/FMC HPC/GTX_TX2_C_P")
  (net 431 "GTX_TX2_P")
  (net 432 "unconnected-(J5C-HA12+-PadF13)")
  (net 433 "unconnected-(J5C-HA12--PadF14)")
  (net 434 "unconnected-(J5C-HA15+-PadF16)")
  (net 435 "FMC_IO_5_N")
  (net 436 "FMC_IO_4_P")
  (net 437 "FMC_IO_6_P")
  (net 438 "/FMC HPC/GTX_TX2_C_N")
  (net 439 "GTX_TX2_N")
  (net 440 "/FMC HPC/GTX_TX3_C_P")
  (net 441 "unconnected-(J5C-HA15--PadF17)")
  (net 442 "unconnected-(J5C-HA19+-PadF19)")
  (net 443 "unconnected-(J5C-HA19--PadF20)")
  (net 444 "FMC_IO_6_N")
  (net 445 "FMC_IO_13_N")
  (net 446 "FMC_IO_15_P")
  (net 447 "FMC_IO_15_N")
  (net 448 "FMC_IO_10_P")
  (net 449 "CLK_DIR")
  (net 450 "GTX_TX3_P")
  (net 451 "/FMC HPC/GTX_TX3_C_N")
  (net 452 "unconnected-(J5C-HB02+-PadF22)")
  (net 453 "unconnected-(J5C-HB02--PadF23)")
  (net 454 "unconnected-(J5C-HB04+-PadF25)")
  (net 455 "unconnected-(J5C-HB04--PadF26)")
  (net 456 "FMC_IO_10_N")
  (net 457 "FMC_IO_12_N")
  (net 458 "FMC_IO_13_P")
  (net 459 "FMC_IO_17_N")
  (net 460 "FMC_IO_8_N")
  (net 461 "unconnected-(J5C-HB08+-PadF28)")
  (net 462 "unconnected-(J5C-HB08--PadF29)")
  (net 463 "GTX_TX3_N")
  (net 464 "/FMC HPC/GTX_TX4_C_P")
  (net 465 "GTX_TX4_P")
  (net 466 "/FMC HPC/GTX_TX4_C_N")
  (net 467 "unconnected-(J5C-HB12+-PadF31)")
  (net 468 "unconnected-(J5C-HB12--PadF32)")
  (net 469 "unconnected-(J5C-HB16+-PadF34)")
  (net 470 "unconnected-(J5C-HB16--PadF35)")
  (net 471 "unconnected-(J5C-HB20+-PadF37)")
  (net 472 "FMC_IO_12_P")
  (net 473 "FMC_IO_11_N")
  (net 474 "FMC_IO_17_P")
  (net 475 "FMC_IO_16_N")
  (net 476 "FMC_IO_8_P")
  (net 477 "unconnected-(J5C-HB20--PadF38)")
  (net 478 "unconnected-(J5C-VADJ-PadF40)")
  (net 479 "GTX_TX4_N")
  (net 480 "/FMC HPC/GTX_TX5_C_P")
  (net 481 "GTX_TX5_P")
  (net 482 "/FMC HPC/GTX_TX5_C_N")
  (net 483 "GTX_TX5_N")
  (net 484 "unconnected-(J5B-CLK1_{M2C}+-PadG2)")
  (net 485 "unconnected-(J5B-CLK1_{M2C}--PadG3)")
  (net 486 "unconnected-(J5B-LA12+-PadG15)")
  (net 487 "unconnected-(J5B-LA12--PadG16)")
  (net 488 "unconnected-(J5B-LA31--PadG34)")
  (net 489 "unconnected-(J5B-LA33+-PadG36)")
  (net 490 "FMC_IO_7_N")
  (net 491 "FMC_IO_11_P")
  (net 492 "FMC_IO_16_P")
  (net 493 "FMC_IO_18_N")
  (net 494 "unconnected-(J5B-LA33--PadG37)")
  (net 495 "unconnected-(J5B-VADJ-PadG39)")
  (net 496 "Net-(J5B-VREF_{A_M2C})")
  (net 497 "/FMC HPC/GTX_TX6_C_P")
  (net 498 "GTX_TX6_P")
  (net 499 "/FMC HPC/GTX_TX6_C_N")
  (net 500 "unconnected-(J5B-CLK0_{M2C}+-PadH4)")
  (net 501 "unconnected-(J5B-CLK0_{M2C}--PadH5)")
  (net 502 "unconnected-(J5B-LA07+-PadH13)")
  (net 503 "unconnected-(J5B-LA07--PadH14)")
  (net 504 "unconnected-(J5B-LA28+-PadH31)")
  (net 505 "FMC_IO_7_P")
  (net 506 "FMC_IO_14_P")
  (net 507 "FMC_IO_14_N")
  (net 508 "unconnected-(J5B-LA28--PadH32)")
  (net 509 "unconnected-(J5B-LA30+-PadH34)")
  (net 510 "unconnected-(J5B-LA30--PadH35)")
  (net 511 "unconnected-(J5B-LA32+-PadH37)")
  (net 512 "GTX_TX6_N")
  (net 513 "/FMC HPC/GTX_TX7_C_P")
  (net 514 "FMC_IO_18_P")
  (net 515 "FMC_IO_9_P")
  (net 516 "FMC_IO_9_N")
  (net 517 "FMC_IO_20_P")
  (net 518 "FMC_IO_20_N")
  (net 519 "unconnected-(J5B-LA32--PadH38)")
  (net 520 "unconnected-(J5B-VADJ-PadH40)")
  (net 521 "unconnected-(J5A-HA03+-PadJ6)")
  (net 522 "unconnected-(J5A-HA03--PadJ7)")
  (net 523 "unconnected-(J5A-HA14+-PadJ15)")
  (net 524 "GTX_TX7_P")
  (net 525 "/FMC HPC/GTX_TX7_C_N")
  (net 526 "GTX_TX7_N")
  (net 527 "unconnected-(J5A-HA14--PadJ16)")
  (net 528 "FMC_IO_19_N")
  (net 529 "FMC_IO_0")
  (net 530 "unconnected-(J5A-HB11+-PadJ30)")
  (net 531 "unconnected-(J5A-HB11--PadJ31)")
  (net 532 "unconnected-(J5A-HB15+-PadJ33)")
  (net 533 "unconnected-(J5A-HB15--PadJ34)")
  (net 534 "unconnected-(J5A-HB18+-PadJ36)")
  (net 535 "12P0V")
  (net 536 "/Supply/SYS_PWR_GOOD")
  (net 537 "INT_LED_LINK")
  (net 538 "FMC_IO_22_P")
  (net 539 "FMC_IO_22_N")
  (net 540 "unconnected-(J5A-HB18--PadJ37)")
  (net 541 "unconnected-(J5A-VIO_{B_M2C}-PadJ39)")
  (net 542 "Net-(J5A-VREF_{B_M2C})")
  (net 543 "unconnected-(J5A-HA10+-PadK13)")
  (net 544 "unconnected-(J5A-HA10--PadK14)")
  (net 545 "unconnected-(J5A-HB06_{CC}--PadK29)")
  (net 546 "INT_LED_SPD")
  (net 547 "/Ethernet/INT_ETH4_N")
  (net 548 "/Ethernet/INT_ETH4_P")
  (net 549 "unconnected-(J5A-HB10+-PadK31)")
  (net 550 "unconnected-(J5A-HB10--PadK32)")
  (net 551 "unconnected-(J5A-HB14+-PadK34)")
  (net 552 "unconnected-(J5A-HB14--PadK35)")
  (net 553 "unconnected-(J5A-HB17_{CC}+-PadK37)")
  (net 554 "unconnected-(J5A-HB17_{CC}--PadK38)")
  (net 555 "unconnected-(J5A-VIO_{B_M2C}-PadK40)")
  (net 556 "Net-(J6-CEC)")
  (net 557 "unconnected-(J6-UTILITY{slash}HEAC+-Pad14)")
  (net 558 "/Ethernet/INT_ETH3_N")
  (net 559 "/Ethernet/INT_ETH3_P")
  (net 560 "Net-(J6-SCL)")
  (net 561 "Net-(J6-SDA)")
  (net 562 "Net-(J6-+5V)")
  (net 563 "Net-(J6-HPD{slash}HEAC-)")
  (net 564 "Net-(J7-CD_SW1)")
  (net 565 "Net-(J9-CC1)")
  (net 566 "unconnected-(J9-SBU1-PadA8)")
  (net 567 "/Ethernet/INT_ETH2_N")
  (net 568 "/Ethernet/INT_ETH2_P")
  (net 569 "Net-(J9-CC2)")
  (net 570 "unconnected-(J9-SBU2-PadB8)")
  (net 571 "Net-(U2-SW_VPP)")
  (net 572 "unconnected-(PS1-TRIM-Pad5)")
  (net 573 "Net-(Q1-D)")
  (net 574 "Net-(Q2-D)")
  (net 575 "Net-(Q3-D)")
  (net 576 "Net-(Q4-D)")
  (net 577 "Net-(Q5-D)")
  (net 578 "Net-(Q6-D)")
  (net 579 "Net-(Q7-D)")
  (net 580 "Net-(Q8-D)")
  (net 581 "Net-(Q9-D)")
  (net 582 "Net-(Q10-D)")
  (net 583 "Net-(Q11-D)")
  (net 584 "Net-(Q12-G)")
  (net 585 "Net-(U7-BDBUS0)")
  (net 586 "Net-(U7-BDBUS1)")
  (net 587 "Net-(U7-BDBUS2)")
  (net 588 "Net-(U7-BDBUS3)")
  (net 589 "Net-(U7-BDBUS5)")
  (net 590 "Net-(U7-CDBUS0)")
  (net 591 "Net-(U7-CDBUS1)")
  (net 592 "Net-(U7-DDBUS0)")
  (net 593 "Net-(U7-ADBUS0)")
  (net 594 "Net-(U7-ADBUS1)")
  (net 595 "Net-(U7-ADBUS2)")
  (net 596 "Net-(U3-~{CS})")
  (net 597 "Net-(U3-SCK)")
  (net 598 "Net-(U7-ADBUS3)")
  (net 599 "Net-(U3-~{HOLD}{slash}IO3)")
  (net 600 "Net-(U3-~{WP}{slash}IO2)")
  (net 601 "Net-(U2-BST)")
  (net 602 "Net-(U7-DDBUS1)")
  (net 603 "Net-(U4-EN)")
  (net 604 "GNDD")
  (net 605 "/Ethernet/PAIR_12")
  (net 606 "/Ethernet/PAIR_36")
  (net 607 "/Ethernet/PAIR_78")
  (net 608 "/Ethernet/PAIR_910")
  (net 609 "Net-(D15-Pad1)")
  (net 610 "/Ethernet/DEN")
  (net 611 "/Ethernet/CLSA")
  (net 612 "/Ethernet/AMPS_CTL")
  (net 613 "Net-(U2-PGOOD)")
  (net 614 "Net-(U4-FB)")
  (net 615 "/Ethernet/POE_ACTIVE")
  (net 616 "Net-(U2-VTTSNS)")
  (net 617 "/Ethernet/REF")
  (net 618 "/Ethernet/CLSB")
  (net 619 "/Ethernet/TPH")
  (net 620 "/Ethernet/PG")
  (net 621 "/Ethernet/IRSHDL_EN")
  (net 622 "/Ethernet/TPL")
  (net 623 "unconnected-(D19-Pad2)")
  (net 624 "Net-(U5-EN)")
  (net 625 "Net-(U5-FB)")
  (net 626 "VIN_RAW")
  (net 627 "Net-(IC2-Pad3)")
  (net 628 "Net-(IC2-Pad2)")
  (net 629 "/Ethernet/MPS_DUTY")
  (net 630 "/Ethernet/INT_ETH1_N")
  (net 631 "/Ethernet/INT_ETH1_P")
  (net 632 "GTX_RX1_P")
  (net 633 "GTX_RX1_N")
  (net 634 "GTX_RX2_P")
  (net 635 "GTX_RX2_N")
  (net 636 "GTX_RX3_P")
  (net 637 "GTX_RX3_N")
  (net 638 "GTX_RX4_P")
  (net 639 "GTX_RX4_N")
  (net 640 "GTX_RX5_P")
  (net 641 "GTX_RX5_N")
  (net 642 "Net-(U9-EN)")
  (net 643 "Net-(U12-EN)")
  (net 644 "Net-(U9-FB)")
  (net 645 "GTX_RX7_P")
  (net 646 "GTX_RX7_N")
  (net 647 "GTX_RX6_P")
  (net 648 "GTX_RX6_N")
  (net 649 "Net-(U10-INV)")
  (net 650 "Net-(U3-SI{slash}IO0)")
  (net 651 "Net-(U3-SO{slash}IO1)")
  (net 652 "Net-(U6-ISET)")
  (net 653 "Net-(U12-FB)")
  (net 654 "Net-(U7-REF)")
  (net 655 "GTX_RX0_P")
  (net 656 "GTX_RX0_N")
  (net 657 "Net-(U7-~{RESET})")
  (net 658 "Net-(U15G-IO_L4N_T0_33)")
  (net 659 "Net-(U13-~{BT})")
  (net 660 "Net-(U19-~{PWRDN})")
  (net 661 "Net-(U20-~{PWRDN})")
  (net 662 "Net-(U16-SEL)")
  (net 663 "Net-(U15J-MGTRREF_115)")
  (net 664 "Net-(U26-~{PB_IN})")
  (net 665 "Net-(U7-ADBUS5)")
  (net 666 "Net-(U8-EN)")
  (net 667 "unconnected-(U3-EP-Pad9)")
  (net 668 "/FMC HPC/GTR_REFCLK0_R_P")
  (net 669 "/FMC HPC/GTR_REFCLK0_R_N")
  (net 670 "unconnected-(U6-NC-Pad13)")
  (net 671 "unconnected-(U6-LDO_O-Pad43)")
  (net 672 "unconnected-(U6-NC-Pad47)")
  (net 673 "unconnected-(U7-EECS-Pad1)")
  (net 674 "unconnected-(U7-ADBUS4-Pad17)")
  (net 675 "unconnected-(U7-ADBUS6-Pad19)")
  (net 676 "unconnected-(U7-ADBUS7-Pad20)")
  (net 677 "unconnected-(U7-BDBUS4-Pad26)")
  (net 678 "unconnected-(U7-BDBUS6-Pad28)")
  (net 679 "unconnected-(U7-BDBUS7-Pad29)")
  (net 680 "unconnected-(U7-~{SUSPEND}-Pad30)")
  (net 681 "unconnected-(U7-CDBUS2-Pad34)")
  (net 682 "unconnected-(U7-CDBUS3-Pad35)")
  (net 683 "unconnected-(U7-CDBUS4-Pad37)")
  (net 684 "unconnected-(U7-CDBUS5-Pad38)")
  (net 685 "unconnected-(U7-CDBUS6-Pad39)")
  (net 686 "unconnected-(U7-CDBUS7-Pad40)")
  (net 687 "unconnected-(U7-DDBUS2-Pad47)")
  (net 688 "unconnected-(U7-DDBUS3-Pad48)")
  (net 689 "unconnected-(U7-DDBUS4-Pad49)")
  (net 690 "unconnected-(U7-DDBUS5-Pad51)")
  (net 691 "unconnected-(U7-DDBUS6-Pad52)")
  (net 692 "unconnected-(U7-DDBUS7-Pad53)")
  (net 693 "unconnected-(U7-~{PWR_{EN}}-Pad54)")
  (net 694 "unconnected-(U7-EEDATA-Pad55)")
  (net 695 "unconnected-(U7-EECLK-Pad56)")
  (net 696 "unconnected-(U11-NC-PadA2)")
  (net 697 "unconnected-(U11-NC-PadA5)")
  (net 698 "unconnected-(U11-NC-PadB5)")
  (net 699 "unconnected-(U11-NC-PadC2)")
  (net 700 "unconnected-(U11-NC-PadC5)")
  (net 701 "unconnected-(U13-~{AUTCLS}-Pad10)")
  (net 702 "unconnected-(U13-NC-Pad14)")
  (net 703 "unconnected-(U13-NC-Pad15)")
  (net 704 "unconnected-(U13-NC-Pad20)")
  (net 705 "unconnected-(U14B-RFU-Pad144)")
  (net 706 "unconnected-(U14B-RFU-Pad205)")
  (net 707 "unconnected-(U14B-RFU-Pad227)")
  (net 708 "unconnected-(U14B-MP-PadMP1)")
  (net 709 "unconnected-(U14B-MP-PadMP2)")
  (net 710 "unconnected-(U14B-MP-PadMP3)")
  (net 711 "unconnected-(U15E-IO_L9P_T1_DQS_16-PadA9)")
  (net 712 "unconnected-(U15G-IO_L14P_T2_SRCC_33-PadAA10)")
  (net 713 "unconnected-(U15A-IO_L18P_T2_12-PadAB21)")
  (net 714 "unconnected-(U15A-IO_L17P_T2_12-PadAB22)")
  (net 715 "unconnected-(U15A-IO_L11N_T1_SRCC_12-PadAB24)")
  (net 716 "unconnected-(U15A-IO_L7N_T1_12-PadAB25)")
  (net 717 "unconnected-(U15G-IO_L9P_T1_DQS_33-PadAC8)")
  (net 718 "unconnected-(U15A-IO_L18N_T2_12-PadAC21)")
  (net 719 "unconnected-(U15A-IO_L17N_T2_12-PadAC22)")
  (net 720 "unconnected-(U15A-IO_L14P_T2_SRCC_12-PadAC23)")
  (net 721 "unconnected-(U15G-IO_L9N_T1_DQS_33-PadAD8)")
  (net 722 "unconnected-(U15A-IO_L19P_T3_12-PadAD21)")
  (net 723 "unconnected-(U15A-IO_L19N_T3_VREF_12-PadAE21)")
  (net 724 "unconnected-(U15E-IO_L10N_T1_16-PadB9)")
  (net 725 "unconnected-(U15E-IO_L20N_T3_16-PadB11)")
  (net 726 "unconnected-(U15E-IO_L20P_T3_16-PadB12)")
  (net 727 "unconnected-(U15E-IO_L13N_T2_MRCC_16-PadC11)")
  (net 728 "unconnected-(U15E-IO_L19N_T3_VREF_16-PadC13)")
  (net 729 "unconnected-(U15E-IO_L19P_T3_16-PadC14)")
  (net 730 "unconnected-(U15E-IO_L14N_T2_SRCC_16-PadD11)")
  (net 731 "unconnected-(U15E-IO_L17N_T2_16-PadD13)")
  (net 732 "unconnected-(U15E-IO_L17P_T2_16-PadD14)")
  (net 733 "unconnected-(U15E-IO_L14P_T2_SRCC_16-PadE11)")
  (net 734 "unconnected-(U15E-IO_L18N_T2_16-PadE12)")
  (net 735 "unconnected-(U15E-IO_L18P_T2_16-PadE13)")
  (net 736 "EXT_LED_LINK")
  (net 737 "EXT_LED_SPD")
  (net 738 "EXT_ETH2_P")
  (net 739 "EXT_ETH2_N")
  (net 740 "EXT_ETH4_P")
  (net 741 "EXT_ETH4_N")
  (net 742 "unconnected-(U15E-IO_L11N_T1_SRCC_16-PadF10)")
  (net 743 "unconnected-(U15E-IO_L16N_T2_16-PadF12)")
  (net 744 "unconnected-(U15E-IO_L15N_T2_DQS_16-PadF13)")
  (net 745 "unconnected-(U15E-IO_L15P_T2_DQS_16-PadF14)")
  (net 746 "unconnected-(U15C-IO_L12P_T1_MRCC_14-PadF22)")
  (net 747 "unconnected-(U15C-IO_L13N_T2_MRCC_14-PadF23)")
  (net 748 "unconnected-(U15E-IO_L2N_T0_16-PadG9)")
  (net 749 "unconnected-(U15E-IO_L2P_T0_16-PadG10)")
  (net 750 "unconnected-(U15E-IO_L11P_T1_SRCC_16-PadG11)")
  (net 751 "PRSNT_M2C")
  (net 752 "unconnected-(U15E-IO_L16P_T2_16-PadG12)")
  (net 753 "unconnected-(U15E-IO_L5N_T0_16-PadG14)")
  (net 754 "EXT_ETH1_P")
  (net 755 "EXT_ETH1_N")
  (net 756 "EXT_ETH3_P")
  (net 757 "EXT_ETH3_N")
  (net 758 "unconnected-(U15C-IO_L19N_T3_A09_D25_VREF_14-PadG21)")
  (net 759 "unconnected-(U15C-IO_L13P_T2_MRCC_14-PadG22)")
  (net 760 "unconnected-(U15E-IO_L1N_T0_16-PadH8)")
  (net 761 "unconnected-(U15E-IO_L1P_T0_16-PadH9)")
  (net 762 "unconnected-(U15E-IO_L6N_T0_VREF_16-PadH11)")
  (net 763 "unconnected-(U15E-IO_L6P_T0_16-PadH12)")
  (net 764 "unconnected-(U15E-IO_L3N_T0_DQS_16-PadH13)")
  (net 765 "unconnected-(U15E-IO_L5P_T0_16-PadH14)")
  (net 766 "unconnected-(U15C-IO_L19P_T3_A10_D26_14-PadH21)")
  (net 767 "unconnected-(U15C-IO_L20P_T3_A08_D24_14-PadH23)")
  (net 768 "unconnected-(U15C-IO_L20N_T3_A07_D23_14-PadH24)")
  (net 769 "unconnected-(U15E-IO_0_16-PadJ8)")
  (net 770 "unconnected-(U15E-IO_L4N_T0_16-PadJ10)")
  (net 771 "unconnected-(U15E-IO_L4P_T0_16-PadJ11)")
  (net 772 "unconnected-(U15E-IO_L3P_T0_DQS_16-PadJ13)")
  (net 773 "unconnected-(U15E-IO_25_16-PadJ14)")
  (net 774 "unconnected-(U15C-IO_L21P_T3_DQS_14-PadJ21)")
  (net 775 "unconnected-(U15C-IO_L24N_T3_A00_D16_14-PadJ23)")
  (net 776 "unconnected-(U15C-IO_L22P_T3_A05_D21_14-PadJ24)")
  (net 777 "unconnected-(U15C-IO_L22N_T3_A04_D20_14-PadJ25)")
  (net 778 "unconnected-(U15C-IO_0_14-PadK21)")
  (net 779 "unconnected-(U15C-IO_L23N_T3_A02_D18_14-PadK22)")
  (net 780 "unconnected-(U15C-IO_L24P_T3_A01_D17_14-PadK23)")
  (net 781 "unconnected-(U15B-IO_L1P_T0_13-PadK25)")
  (net 782 "unconnected-(U15B-IO_L1N_T0_13-PadK26)")
  (net 783 "unconnected-(U15C-IO_L23P_T3_A03_D19_14-PadL22)")
  (net 784 "HOT_SWAP_YELLOW")
  (net 785 "unconnected-(U15C-IO_25_14-PadL23)")
  (net 786 "HOT_SWAP_GREEN")
  (net 787 "unconnected-(U15B-IO_L8N_T1_13-PadL24)")
  (net 788 "HOT_SWAP_RED")
  (net 789 "DDR_PRESENCE")
  (net 790 "/Supply/PWR_SEQ_EN")
  (net 791 "unconnected-(U15B-IO_L3N_T0_DQS_13-PadL25)")
  (net 792 "unconnected-(U15B-IO_L22N_T3_13-PadM19)")
  (net 793 "/Supply/VTT_CNTL")
  (net 794 "/Supply/SLP_S4")
  (net 795 "unconnected-(U15B-IO_L7N_T1_13-PadM20)")
  (net 796 "ETH_SEL")
  (net 797 "unconnected-(U15B-IO_L10P_T1_13-PadM21)")
  (net 798 "/Supply/FPGA_PWR_DIS")
  (net 799 "FPGA_SLP_S4")
  (net 800 "FPGA_VTT_CNTL")
  (net 801 "unconnected-(U15B-IO_L10N_T1_13-PadM22)")
  (net 802 "unconnected-(U15B-IO_L8P_T1_13-PadM24)")
  (net 803 "unconnected-(U15B-IO_L3P_T0_DQS_13-PadM25)")
  (net 804 "FPGA_POWER_CYCLE")
  (net 805 "/Supply/VCC1V2_SEN_+")
  (net 806 "/Supply/VCC1V2_SEN_-")
  (net 807 "/Ethernet/VSS_RAW")
  (net 808 "/Ethernet/VDD_RAW")
  (net 809 "FMC_IO_24_N")
  (net 810 "FMC_IO_19_P")
  (net 811 "FMC_IO_24_P")
  (net 812 "FMC_IO_23_N")
  (net 813 "FMC_IO_21_P")
  (net 814 "FMC_IO_21_N")
  (net 815 "FMC_IO_25")
  (net 816 "FMC_IO_23_P")
  (net 817 "unconnected-(U15B-IO_L5N_T0_13-PadM26)")
  (net 818 "unconnected-(U15B-IO_0_13-PadN16)")
  (net 819 "unconnected-(U15B-IO_L20N_T3_13-PadN17)")
  (net 820 "unconnected-(U15B-IO_L22P_T3_13-PadN18)")
  (net 821 "unconnected-(U15B-IO_L7P_T1_13-PadN19)")
  (net 822 "unconnected-(U15B-IO_L12P_T1_MRCC_13-PadN21)")
  (net 823 "unconnected-(U15B-IO_L12N_T1_MRCC_13-PadN22)")
  (net 824 "/Ethernet/ETH1_BP_P")
  (net 825 "/Ethernet/ETH1_BP_N")
  (net 826 "/Ethernet/ETH2_BP_P")
  (net 827 "/Ethernet/ETH2_BP_N")
  (net 828 "/Ethernet/ETH3_BP_P")
  (net 829 "/Ethernet/ETH3_BP_N")
  (net 830 "/Ethernet/ETH4_BP_P")
  (net 831 "/Ethernet/ETH4_BP_N")
  (net 832 "/Supply/VPP_SEN_+")
  (net 833 "/Supply/VDDQ_SEN_+")
  (net 834 "/Supply/VTT_SEN_+")
  (net 835 "/Supply/VDDQ_SEN_-")
  (net 836 "/Supply/VPP_SEN_-")
  (net 837 "/Supply/VTT_SEN_-")
  (net 838 "/Supply/5V0_SEN_+")
  (net 839 "/Supply/3V3_SEN_+")
  (net 840 "/Supply/1V8_SEN_+")
  (net 841 "/Supply/1V0_SEN_+")
  (net 842 "/Supply/5V0_SEN_-")
  (net 843 "/Supply/3V3_SEN_-")
  (net 844 "/Supply/1V8_SEN_-")
  (net 845 "/Supply/1V0_SEN_-")
  (net 846 "5V_ON_OFF")
  (net 847 "unconnected-(U15B-IO_L11N_T1_SRCC_13-PadN23)")
  (net 848 "unconnected-(U15B-IO_L4N_T0_13-PadN24)")
  (net 849 "unconnected-(U15B-IO_L5P_T0_13-PadN26)")
  (net 850 "unconnected-(U15B-IO_L20P_T3_13-PadP16)")
  (net 851 "unconnected-(U15B-IO_L24N_T3_13-PadP18)")
  (net 852 "unconnected-(U15B-IO_L13N_T2_MRCC_13-PadP21)")
  (net 853 "VBUS")
  (net 854 "Net-(R17-Pad1)")
  (net 855 "Net-(R29-Pad1)")
  (net 856 "Net-(R113-Pad1)")
  (net 857 "Net-(R114-Pad1)")
  (net 858 "unconnected-(U15B-IO_L11P_T1_SRCC_13-PadP23)")
  (net 859 "/Supply/OUT")
  (net 860 "/Supply/~{CLR}")
  (net 861 "unconnected-(U15B-IO_L4P_T0_13-PadP24)")
  (net 862 "GNDS")
  (net 863 "GND1")
  (net 864 "VIN_POE")
  (net 865 "unconnected-(U15B-IO_L6N_T0_VREF_13-PadP25)")
  (net 866 "unconnected-(U15B-IO_L2N_T0_13-PadP26)")
  (net 867 "unconnected-(U15B-IO_L24P_T3_13-PadR18)")
  (net 868 "unconnected-(U15B-IO_L16N_T2_13-PadR20)")
  (net 869 "unconnected-(U15B-IO_L14N_T2_SRCC_13-PadR23)")
  (net 870 "unconnected-(U15B-IO_L6P_T0_13-PadR25)")
  (net 871 "unconnected-(U15B-IO_L2P_T0_13-PadR26)")
  (net 872 "unconnected-(U15H-IO_25_VRP_34-PadT7)")
  (net 873 "unconnected-(U15B-IO_L19N_T3_VREF_13-PadT19)")
  (net 874 "unconnected-(U15B-IO_L16P_T2_13-PadT20)")
  (net 875 "unconnected-(U15B-IO_L15P_T2_DQS_13-PadT24)")
  (net 876 "unconnected-(U15B-IO_L15N_T2_DQS_13-PadT25)")
  (net 877 "unconnected-(U15H-IO_0_VRN_34-PadU4)")
  (net 878 "unconnected-(U15B-IO_L18P_T2_13-PadU19)")
  (net 879 "unconnected-(U15B-IO_L18N_T2_13-PadU20)")
  (net 880 "unconnected-(U15A-IO_0_12-PadU21)")
  (net 881 "unconnected-(U15A-IO_L1P_T0_12-PadU22)")
  (net 882 "unconnected-(U15G-IO_L2N_T0_33-PadV7)")
  (net 883 "/FPGA banks 115-116/GTR_REFCLK1_P")
  (net 884 "/FPGA banks 115-116/GTR_REFCLK1_N")
  (net 885 "/FPGA banks 115-116/GTR_REFCLK2_P")
  (net 886 "/FPGA banks 115-116/GTR_REFCLK2_N")
  (net 887 "/FPGA banks 115-116/GTR_REFCLK3_P")
  (net 888 "/FPGA banks 115-116/GTR_REFCLK3_N")
  (net 889 "unconnected-(U15G-IO_L2P_T0_33-PadV8)")
  (net 890 "unconnected-(U15F-IO_0_VRN_32-PadV13)")
  (net 891 "GTR_REFCLK1_C_P")
  (net 892 "GTR_REFCLK1_C_N")
  (net 893 "GTR_REFCLK2_C_P")
  (net 894 "GTR_REFCLK2_C_N")
  (net 895 "GTR_REFCLK3_C_P")
  (net 896 "GTR_REFCLK3_C_N")
  (net 897 "/FMC HPC/GTR_REFCLK1_R_P")
  (net 898 "/FMC HPC/GTR_REFCLK1_R_N")
  (net 899 "/FMC HPC/GTR_REFCLK3_R_P")
  (net 900 "/FMC HPC/GTR_REFCLK3_R_N")
  (net 901 "unconnected-(U15A-IO_L6P_T0_12-PadV21)")
  (net 902 "unconnected-(U15A-IO_L1N_T0_12-PadV22)")
  (net 903 "/FMC HPC/GTR_REFCLK2_R_P")
  (net 904 "/FMC HPC/GTR_REFCLK2_R_N")
  (net 905 "unconnected-(U15A-IO_L3P_T0_DQS_12-PadV23)")
  (net 906 "unconnected-(U15A-IO_L3N_T0_DQS_12-PadV24)")
  (net 907 "FMC_SCL_3V3")
  (net 908 "FMC_SDA_3V3")
  (net 909 "unconnected-(U15G-IO_L6N_T0_VREF_33-PadW8)")
  (net 910 "unconnected-(U15F-IO_25_VRP_32-PadW13)")
  (net 911 "unconnected-(U15A-IO_L15P_T2_DQS_12-PadW20)")
  (net 912 "unconnected-(U15A-IO_L6N_T0_VREF_12-PadW21)")
  (net 913 "unconnected-(U15A-IO_L8P_T1_12-PadW23)")
  (net 914 "unconnected-(U16-NC-Pad5)")
  (net 915 "unconnected-(U16-0LED1-Pad22)")
  (net 916 "unconnected-(U16-0LED2-Pad25)")
  (net 917 "unconnected-(U19-EP-Pad17)")
  (net 918 "unconnected-(U20-EP-Pad17)")
  (net 919 "unconnected-(U25-NC-Pad4)")

  (footprint "data-center-rdimm-ddr4-tester-footprints:R_0402_1005Metric" (layer "F.Cu")
    (at 238.434 118.271 180)
    (descr "Resistor SMD 0402")
    (tags "resistor SMD 0402")
    (property "Author" "Antmicro")
    (property "DNP" "DNP")
    (property "License" "Apache-2.0")
    (property "MPN" "CR0402-FX-1000GLF")
    (property "Manufacturer" "Bourns")
    (property "Sheetfile" "config-spi.kicad_sch")
    (property "Sheetname" "Config SPI flash")
    (property "Tolerance" "1%")
    (property "Val" "100R")
    (property "dnp" "")
    (property "exclude_from_bom" "")
    (property "ki_description" "100R resistor in 0402 package with 1% tolerance")
    (attr exclude_from_pos_files exclude_from_bom)
    (fp_text reference "R33" (at -0.786 -0.369 180) (layer "F.SilkS")
        (effects (font (size 0.7 0.7) (thickness 0.15)) (justify left bottom))
    )
    (fp_text value "R_100R_0402" (at 0 1.4 180) (layer "F.Fab") hide
        (effects (font (size 0.7 0.7) (thickness 0.15)) (justify left bottom))
    )
    (fp_text user "${REFERENCE}" (at -0.95 3.168 180) (layer "F.Fab") hide
        (effects (font (size 0.7 0.7) (thickness 0.15)) (justify left bottom))
    )
    (fp_text user "License: Apache-2.0" (at -0.95 5.169 180) (layer "F.Fab") hide
        (effects (font (size 0.7 0.7) (thickness 0.15)) (justify left bottom))
    )
    (fp_text user "Author: Antmicro" (at -0.95 4.169 180) (layer "F.Fab") hide
        (effects (font (size 0.7 0.7) (thickness 0.15)) (justify left bottom))
    )
    (fp_rect (start -0.93 -0.47) (end 0.93 0.47)
      (stroke (width 0.05) (type solid)) (fill none) (layer "F.CrtYd"))
    (fp_rect (start -0.5 -0.25) (end 0.5 0.25)
      (stroke (width 0.15) (type solid)) (fill none) (layer "F.Fab"))
    (pad "1" smd roundrect (at -0.485 0 180) (size 0.59 0.64) (layers "F.Cu" "F.Paste" "F.Mask") (roundrect_rratio 0.25)
      (net 143 "3V3_SYS") (pintype "passive"))
    (pad "2" smd roundrect (at 0.485 0 180) (size 0.59 0.64) (layers "F.Cu" "F.Paste" "F.Mask") (roundrect_rratio 0.25)
      (net 96 "CCLK") (pintype "passive"))
  )

  (footprint "data-center-rdimm-ddr4-tester-footprints:R_0402_1005Metric" (layer "F.Cu")
    (at 238.478 119.375)
    (descr "Resistor SMD 0402")
    (tags "resistor SMD 0402")
    (property "Author" "Antmicro")
    (property "DNP" "DNP")
    (property "License" "Apache-2.0")
    (property "MPN" "CR0402-FX-1000GLF")
    (property "Manufacturer" "Bourns")
    (property "Sheetfile" "config-spi.kicad_sch")
    (property "Sheetname" "Config SPI flash")
    (property "Tolerance" "1%")
    (property "Val" "100R")
    (property "dnp" "")
    (property "exclude_from_bom" "")
    (property "ki_description" "100R resistor in 0402 package with 1% tolerance")
    (attr exclude_from_pos_files exclude_from_bom)
    (fp_text reference "R34" (at 0.772 0.225) (layer "F.SilkS")
        (effects (font (size 0.7 0.7) (thickness 0.15)) (justify left bottom))
    )
    (fp_text value "R_100R_0402" (at 0 1.4) (layer "F.Fab") hide
        (effects (font (size 0.7 0.7) (thickness 0.15)) (justify left bottom))
    )
    (fp_text user "Author: Antmicro" (at -0.95 4.169) (layer "F.Fab") hide
        (effects (font (size 0.7 0.7) (thickness 0.15)) (justify left bottom))
    )
    (fp_text user "License: Apache-2.0" (at -0.95 5.169) (layer "F.Fab") hide
        (effects (font (size 0.7 0.7) (thickness 0.15)) (justify left bottom))
    )
    (fp_text user "${REFERENCE}" (at -0.95 3.168) (layer "F.Fab") hide
        (effects (font (size 0.7 0.7) (thickness 0.15)) (justify left bottom))
    )
    (fp_rect (start -0.93 -0.47) (end 0.93 0.47)
      (stroke (width 0.05) (type solid)) (fill none) (layer "F.CrtYd"))
    (fp_rect (start -0.5 -0.25) (end 0.5 0.25)
      (stroke (width 0.15) (type solid)) (fill none) (layer "F.Fab"))
    (pad "1" smd roundrect (at -0.485 0) (size 0.59 0.64) (layers "F.Cu" "F.Paste" "F.Mask") (roundrect_rratio 0.25)
      (net 96 "CCLK") (pintype "passive"))
    (pad "2" smd roundrect (at 0.485 0) (size 0.59 0.64) (layers "F.Cu" "F.Paste" "F.Mask") (roundrect_rratio 0.25)
      (net 9 "GND") (pintype "passive"))
  )

  (footprint "data-center-rdimm-ddr4-tester-footprints:C_0402_1005Metric" (layer "F.Cu")
    (at 235.767 115.731)
    (descr "Capacitor SMD 0402")
    (tags "capacitor SMD 0402")
    (property "Author" "Antmicro")
    (property "Dielectric" "X5R")
    (property "License" "Apache-2.0")
    (property "MPN" "GRM155R61H104KE14D")
    (property "Manufacturer" "Murata")
    (property "Sheetfile" "config-spi.kicad_sch")
    (property "Sheetname" "Config SPI flash")
    (property "Val" "100n")
    (property "Voltage" "50V")
    (property "ki_description" " ")
    (attr smd)
    (fp_text reference "C5" (at -1.037 -3.281) (layer "F.SilkS")
        (effects (font (size 0.7 0.7) (thickness 0.15)) (justify left bottom))
    )
    (fp_text value "C_100n_0402" (at 0 1.4) (layer "F.Fab") hide
        (effects (font (size 0.7 0.7) (thickness 0.15)) (justify left bottom))
    )
    (fp_text user "Author: Antmicro" (at -0.932 4.17) (layer "F.Fab") hide
        (effects (font (size 0.7 0.7) (thickness 0.15)) (justify left bottom))
    )
    (fp_text user "${REFERENCE}" (at -0.932 3.168) (layer "F.Fab") hide
        (effects (font (size 0.7 0.7) (thickness 0.15)) (justify left bottom))
    )
    (fp_text user "License: Apache-2.0" (at -0.932 5.17) (layer "F.Fab") hide
        (effects (font (size 0.7 0.7) (thickness 0.15)) (justify left bottom))
    )
    (fp_rect (start -0.94 -0.47) (end 0.94 0.47)
      (stroke (width 0.05) (type solid)) (fill none) (layer "F.CrtYd"))
    (fp_rect (start -0.499 -0.249) (end 0.499 0.249)
      (stroke (width 0.15) (type solid)) (fill none) (layer "F.Fab"))
    (pad "1" smd roundrect (at -0.484 0) (size 0.59 0.64) (layers "F.Cu" "F.Paste" "F.Mask") (roundrect_rratio 0.25)
      (net 143 "3V3_SYS") (pintype "passive"))
    (pad "2" smd roundrect (at 0.484 0) (size 0.59 0.64) (layers "F.Cu" "F.Paste" "F.Mask") (roundrect_rratio 0.25)
      (net 9 "GND") (pintype "passive"))
  )

  (footprint "data-center-rdimm-ddr4-tester-footprints:C_0402_1005Metric" (layer "F.Cu")
    (at 138.286328 115.108157 180)
    (descr "Capacitor SMD 0402")
    (tags "capacitor SMD 0402")
    (property "Author" "Antmicro")
    (property "Dielectric" "")
    (property "License" "Apache-2.0")
    (property "MPN" "GRM155R61A475MEAAD")
    (property "Manufacturer" "Murata")
    (property "Sheetfile" "interfaces.kicad_sch")
    (property "Sheetname" "Interfaces")
    (property "Val" "4u7")
    (property "Voltage" "")
    (property "ki_description" " ")
    (attr smd)
    (fp_text reference "C189" (at 1.926328 1.709157 180) (layer "F.SilkS")
        (effects (font (size 0.7 0.7) (thickness 0.15)) (justify left bottom))
    )
    (fp_text value "C_4u7_0402" (at 0 1.4 180) (layer "F.Fab") hide
        (effects (font (size 0.7 0.7) (thickness 0.15)) (justify left bottom))
    )
    (fp_text user "${REFERENCE}" (at -0.932 3.168 180) (layer "F.Fab") hide
        (effects (font (size 0.7 0.7) (thickness 0.15)) (justify left bottom))
    )
    (fp_text user "License: Apache-2.0" (at -0.932 5.17 180) (layer "F.Fab") hide
        (effects (font (size 0.7 0.7) (thickness 0.15)) (justify left bottom))
    )
    (fp_text user "Author: Antmicro" (at -0.932 4.17 180) (layer "F.Fab") hide
        (effects (font (size 0.7 0.7) (thickness 0.15)) (justify left bottom))
    )
    (fp_rect (start -0.94 -0.47) (end 0.94 0.47)
      (stroke (width 0.05) (type solid)) (fill none) (layer "F.CrtYd"))
    (fp_rect (start -0.499 -0.249) (end 0.499 0.249)
      (stroke (width 0.15) (type solid)) (fill none) (layer "F.Fab"))
    (pad "1" smd roundrect (at -0.484 0 180) (size 0.59 0.64) (layers "F.Cu" "F.Paste" "F.Mask") (roundrect_rratio 0.25)
      (net 76 "Net-(U7-V_{PHY})") (pintype "passive"))
    (pad "2" smd roundrect (at 0.484 0 180) (size 0.59 0.64) (layers "F.Cu" "F.Paste" "F.Mask") (roundrect_rratio 0.25)
      (net 9 "GND") (pintype "passive"))
  )

  (footprint "data-center-rdimm-ddr4-tester-footprints:C_0402_1005Metric" (layer "F.Cu")
    (at 134.236328 111.897157 -90)
    (descr "Capacitor SMD 0402")
    (tags "capacitor SMD 0402")
    (property "Author" "Antmicro")
    (property "Dielectric" "X5R")
    (property "License" "Apache-2.0")
    (property "MPN" "GRM155R61H104KE14D")
    (property "Manufacturer" "Murata")
    (property "Sheetfile" "interfaces.kicad_sch")
    (property "Sheetname" "Interfaces")
    (property "Val" "100n")
    (property "Voltage" "50V")
    (property "ki_description" " ")
    (attr smd)
    (fp_text reference "C196" (at 1.342843 -1.233672 -90) (layer "F.SilkS")
        (effects (font (size 0.7 0.7) (thickness 0.15)) (justify left bottom))
    )
    (fp_text value "C_100n_0402" (at 0 1.4 -90) (layer "F.Fab") hide
        (effects (font (size 0.7 0.7) (thickness 0.15)) (justify left bottom))
    )
    (fp_text user "${REFERENCE}" (at -0.932 3.168 -90) (layer "F.Fab") hide
        (effects (font (size 0.7 0.7) (thickness 0.15)) (justify left bottom))
    )
    (fp_text user "License: Apache-2.0" (at -0.932 5.17 -90) (layer "F.Fab") hide
        (effects (font (size 0.7 0.7) (thickness 0.15)) (justify left bottom))
    )
    (fp_text user "Author: Antmicro" (at -0.932 4.17 -90) (layer "F.Fab") hide
        (effects (font (size 0.7 0.7) (thickness 0.15)) (justify left bottom))
    )
    (fp_rect (start -0.94 -0.47) (end 0.94 0.47)
      (stroke (width 0.05) (type solid)) (fill none) (layer "F.CrtYd"))
    (fp_rect (start -0.499 -0.249) (end 0.499 0.249)
      (stroke (width 0.15) (type solid)) (fill none) (layer "F.Fab"))
    (pad "1" smd roundrect (at -0.484 0 270) (size 0.59 0.64) (layers "F.Cu" "F.Paste" "F.Mask") (roundrect_rratio 0.25)
      (net 145 "1V8_FT") (pintype "passive"))
    (pad "2" smd roundrect (at 0.484 0 270) (size 0.59 0.64) (layers "F.Cu" "F.Paste" "F.Mask") (roundrect_rratio 0.25)
      (net 9 "GND") (pintype "passive"))
  )

  (footprint "data-center-rdimm-ddr4-tester-footprints:Oscillator_SMD_Geyer_KX-7-4Pin_3.2x2.5mm" (layer "F.Cu")
    (at 135.161328 116.622157 -90)
    (property "Author" "Antmicro")
    (property "License" "Apache-2.0")
    (property "MPN" "ABM8G-12.000MHZ-18-D2Y-T ")
    (property "Manufacturer" "Abracon")
    (property "Sheetfile" "interfaces.kicad_sch")
    (property "Sheetname" "Interfaces")
    (property "Val" "12MHz")
    (attr smd)
    (fp_text reference "Y2" (at 2.797843 1.931328 180) (layer "F.SilkS")
        (effects (font (size 0.7 0.7) (thickness 0.15)) (justify left bottom))
    )
    (fp_text value "Oscillator_SMD_12MHz_KX-7" (at -1.75 2.548 -90) (layer "F.Fab") hide
        (effects (font (size 0.7 0.7) (thickness 0.15)) (justify left bottom))
    )
    (fp_text user "${REFERENCE}" (at -1.75 3.75 -90) (layer "F.Fab") hide
        (effects (font (size 0.7 0.7) (thickness 0.15)) (justify left bottom))
    )
    (fp_text user "Author: Antmicro" (at -1.75 5 -90) (layer "F.Fab") hide
        (effects (font (size 0.7 0.7) (thickness 0.15)) (justify left bottom))
    )
    (fp_text user "License: Apache-2.0" (at -1.75 6.5 -90) (layer "F.Fab") hide
        (effects (font (size 0.7 0.7) (thickness 0.15)) (justify left bottom))
    )
    (fp_line (start -1.6 0.3) (end -1.6 -0.2)
      (stroke (width 0.15) (type solid)) (layer "F.SilkS"))
    (fp_line (start -0.35 -1.25) (end 0.45 -1.25)
      (stroke (width 0.15) (type solid)) (layer "F.SilkS"))
    (fp_line (start -0.35 1.25) (end 0.45 1.25)
      (stroke (width 0.15) (type solid)) (layer "F.SilkS"))
    (fp_line (start 1.6 0.3) (end 1.6 -0.2)
      (stroke (width 0.15) (type solid)) (layer "F.SilkS"))
    (fp_circle (center -1.75 1.5) (end -1.7 1.5)
      (stroke (width 0.15) (type solid)) (fill none) (layer "F.SilkS"))
    (fp_rect (start -1.907 -1.55) (end 2.006 1.649)
      (stroke (width 0.05) (type solid)) (fill none) (layer "F.CrtYd"))
    (pad "1" smd roundrect (at -1.101 0.949 270) (size 1.3 1.1) (layers "F.Cu" "F.Paste" "F.Mask") (roundrect_rratio 0)
      (chamfer_ratio 0.2) (chamfer bottom_left)
      (net 80 "Net-(U7-OSCI)") (pintype "passive"))
    (pad "2" smd rect (at 1.199 0.949 270) (size 1.3 1.1) (layers "F.Cu" "F.Paste" "F.Mask")
      (net 9 "GND") (pinfunction "SH") (pintype "passive"))
    (pad "3" smd rect (at 1.199 -0.85 270) (size 1.3 1.1) (layers "F.Cu" "F.Paste" "F.Mask")
      (net 81 "Net-(U7-OSCO)") (pintype "passive"))
    (pad "4" smd rect (at -1.101 -0.85 270) (size 1.3 1.1) (layers "F.Cu" "F.Paste" "F.Mask")
      (net 9 "GND") (pinfunction "SH") (pintype "passive"))
  )

  (footprint "data-center-rdimm-ddr4-tester-footprints:R_0402_1005Metric" (layer "F.Cu")
    (at 148.051328 107.747157)
    (descr "Resistor SMD 0402")
    (tags "resistor SMD 0402")
    (property "Author" "Antmicro")
    (property "License" "Apache-2.0")
    (property "MPN" "CR0402-FX-22R0GLF")
    (property "Manufacturer" "Bourns")
    (property "Sheetfile" "interfaces.kicad_sch")
    (property "Sheetname" "Interfaces")
    (property "Tolerance" "1%")
    (property "Val" "22R")
    (property "ki_description" "22R resistor in 0402 package with 1% tolerance")
    (attr smd)
    (fp_text reference "R1" (at 0.863672 0.367843) (layer "F.SilkS")
        (effects (font (size 0.7 0.7) (thickness 0.15)) (justify left bottom))
    )
    (fp_text value "R_22R_0402" (at 0 1.4) (layer "F.Fab") hide
        (effects (font (size 0.7 0.7) (thickness 0.15)) (justify left bottom))
    )
    (fp_text user "${REFERENCE}" (at -0.95 3.168) (layer "F.Fab") hide
        (effects (font (size 0.7 0.7) (thickness 0.15)) (justify left bottom))
    )
    (fp_text user "License: Apache-2.0" (at -0.95 5.169) (layer "F.Fab") hide
        (effects (font (size 0.7 0.7) (thickness 0.15)) (justify left bottom))
    )
    (fp_text user "Author: Antmicro" (at -0.95 4.169) (layer "F.Fab") hide
        (effects (font (size 0.7 0.7) (thickness 0.15)) (justify left bottom))
    )
    (fp_rect (start -0.93 -0.47) (end 0.93 0.47)
      (stroke (width 0.05) (type solid)) (fill none) (layer "F.CrtYd"))
    (fp_rect (start -0.5 -0.25) (end 0.5 0.25)
      (stroke (width 0.15) (type solid)) (fill none) (layer "F.Fab"))
    (pad "1" smd roundrect (at -0.485 0) (size 0.59 0.64) (layers "F.Cu" "F.Paste" "F.Mask") (roundrect_rratio 0.25)
      (net 585 "Net-(U7-BDBUS0)") (pintype "passive"))
    (pad "2" smd roundrect (at 0.485 0) (size 0.59 0.64) (layers "F.Cu" "F.Paste" "F.Mask") (roundrect_rratio 0.25)
      (net 126 "AUX_JTAG_TCK") (pintype "passive"))
  )

  (footprint "data-center-rdimm-ddr4-tester-footprints:R_0402_1005Metric" (layer "F.Cu")
    (at 148.036328 106.622157)
    (descr "Resistor SMD 0402")
    (tags "resistor SMD 0402")
    (property "Author" "Antmicro")
    (property "License" "Apache-2.0")
    (property "MPN" "CR0402-FX-22R0GLF")
    (property "Manufacturer" "Bourns")
    (property "Sheetfile" "interfaces.kicad_sch")
    (property "Sheetname" "Interfaces")
    (property "Tolerance" "1%")
    (property "Val" "22R")
    (property "ki_description" "22R resistor in 0402 package with 1% tolerance")
    (attr smd)
    (fp_text reference "R2" (at 0.863672 0.367843) (layer "F.SilkS")
        (effects (font (size 0.7 0.7) (thickness 0.15)) (justify left bottom))
    )
    (fp_text value "R_22R_0402" (at 0 1.4) (layer "F.Fab") hide
        (effects (font (size 0.7 0.7) (thickness 0.15)) (justify left bottom))
    )
    (fp_text user "License: Apache-2.0" (at -0.95 5.169) (layer "F.Fab") hide
        (effects (font (size 0.7 0.7) (thickness 0.15)) (justify left bottom))
    )
    (fp_text user "Author: Antmicro" (at -0.95 4.169) (layer "F.Fab") hide
        (effects (font (size 0.7 0.7) (thickness 0.15)) (justify left bottom))
    )
    (fp_text user "${REFERENCE}" (at -0.95 3.168) (layer "F.Fab") hide
        (effects (font (size 0.7 0.7) (thickness 0.15)) (justify left bottom))
    )
    (fp_rect (start -0.93 -0.47) (end 0.93 0.47)
      (stroke (width 0.05) (type solid)) (fill none) (layer "F.CrtYd"))
    (fp_rect (start -0.5 -0.25) (end 0.5 0.25)
      (stroke (width 0.15) (type solid)) (fill none) (layer "F.Fab"))
    (pad "1" smd roundrect (at -0.485 0) (size 0.59 0.64) (layers "F.Cu" "F.Paste" "F.Mask") (roundrect_rratio 0.25)
      (net 586 "Net-(U7-BDBUS1)") (pintype "passive"))
    (pad "2" smd roundrect (at 0.485 0) (size 0.59 0.64) (layers "F.Cu" "F.Paste" "F.Mask") (roundrect_rratio 0.25)
      (net 128 "AUX_JTAG_TDI") (pintype "passive"))
  )

  (footprint "data-center-rdimm-ddr4-tester-footprints:R_0402_1005Metric" (layer "F.Cu")
    (at 148.036328 105.497157)
    (descr "Resistor SMD 0402")
    (tags "resistor SMD 0402")
    (property "Author" "Antmicro")
    (property "License" "Apache-2.0")
    (property "MPN" "CR0402-FX-22R0GLF")
    (property "Manufacturer" "Bourns")
    (property "Sheetfile" "interfaces.kicad_sch")
    (property "Sheetname" "Interfaces")
    (property "Tolerance" "1%")
    (property "Val" "22R")
    (property "ki_description" "22R resistor in 0402 package with 1% tolerance")
    (attr smd)
    (fp_text reference "R3" (at 0.863672 0.367843) (layer "F.SilkS")
        (effects (font (size 0.7 0.7) (thickness 0.15)) (justify left bottom))
    )
    (fp_text value "R_22R_0402" (at 0 1.4) (layer "F.Fab") hide
        (effects (font (size 0.7 0.7) (thickness 0.15)) (justify left bottom))
    )
    (fp_text user "${REFERENCE}" (at -0.95 3.168) (layer "F.Fab") hide
        (effects (font (size 0.7 0.7) (thickness 0.15)) (justify left bottom))
    )
    (fp_text user "Author: Antmicro" (at -0.95 4.169) (layer "F.Fab") hide
        (effects (font (size 0.7 0.7) (thickness 0.15)) (justify left bottom))
    )
    (fp_text user "License: Apache-2.0" (at -0.95 5.169) (layer "F.Fab") hide
        (effects (font (size 0.7 0.7) (thickness 0.15)) (justify left bottom))
    )
    (fp_rect (start -0.93 -0.47) (end 0.93 0.47)
      (stroke (width 0.05) (type solid)) (fill none) (layer "F.CrtYd"))
    (fp_rect (start -0.5 -0.25) (end 0.5 0.25)
      (stroke (width 0.15) (type solid)) (fill none) (layer "F.Fab"))
    (pad "1" smd roundrect (at -0.485 0) (size 0.59 0.64) (layers "F.Cu" "F.Paste" "F.Mask") (roundrect_rratio 0.25)
      (net 587 "Net-(U7-BDBUS2)") (pintype "passive"))
    (pad "2" smd roundrect (at 0.485 0) (size 0.59 0.64) (layers "F.Cu" "F.Paste" "F.Mask") (roundrect_rratio 0.25)
      (net 146 "AUX_JTAG_TDO") (pintype "passive"))
  )

  (footprint "data-center-rdimm-ddr4-tester-footprints:R_0402_1005Metric" (layer "F.Cu")
    (at 148.036328 102.122157)
    (descr "Resistor SMD 0402")
    (tags "resistor SMD 0402")
    (property "Author" "Antmicro")
    (property "License" "Apache-2.0")
    (property "MPN" "CR0402-FX-22R0GLF")
    (property "Manufacturer" "Bourns")
    (property "Sheetfile" "interfaces.kicad_sch")
    (property "Sheetname" "Interfaces")
    (property "Tolerance" "1%")
    (property "Val" "22R")
    (property "ki_description" "22R resistor in 0402 package with 1% tolerance")
    (attr smd)
    (fp_text reference "R5" (at -0.796328 1.357843) (layer "F.SilkS")
        (effects (font (size 0.7 0.7) (thickness 0.15)) (justify left bottom))
    )
    (fp_text value "R_22R_0402" (at 0 1.4) (layer "F.Fab") hide
        (effects (font (size 0.7 0.7) (thickness 0.15)) (justify left bottom))
    )
    (fp_text user "License: Apache-2.0" (at -0.95 5.169) (layer "F.Fab") hide
        (effects (font (size 0.7 0.7) (thickness 0.15)) (justify left bottom))
    )
    (fp_text user "Author: Antmicro" (at -0.95 4.169) (layer "F.Fab") hide
        (effects (font (size 0.7 0.7) (thickness 0.15)) (justify left bottom))
    )
    (fp_text user "${REFERENCE}" (at -0.95 3.168) (layer "F.Fab") hide
        (effects (font (size 0.7 0.7) (thickness 0.15)) (justify left bottom))
    )
    (fp_rect (start -0.93 -0.47) (end 0.93 0.47)
      (stroke (width 0.05) (type solid)) (fill none) (layer "F.CrtYd"))
    (fp_rect (start -0.5 -0.25) (end 0.5 0.25)
      (stroke (width 0.15) (type solid)) (fill none) (layer "F.Fab"))
    (pad "1" smd roundrect (at -0.485 0) (size 0.59 0.64) (layers "F.Cu" "F.Paste" "F.Mask") (roundrect_rratio 0.25)
      (net 589 "Net-(U7-BDBUS5)") (pintype "passive"))
    (pad "2" smd roundrect (at 0.485 0) (size 0.59 0.64) (layers "F.Cu" "F.Paste" "F.Mask") (roundrect_rratio 0.25)
      (net 133 "AUX_JTAG_RST") (pintype "passive"))
  )

  (footprint "data-center-rdimm-ddr4-tester-footprints:R_0402_1005Metric" (layer "F.Cu")
    (at 142.536328 100.247157 90)
    (descr "Resistor SMD 0402")
    (tags "resistor SMD 0402")
    (property "Author" "Antmicro")
    (property "License" "Apache-2.0")
    (property "MPN" "CR0402-FX-22R0GLF")
    (property "Manufacturer" "Bourns")
    (property "Sheetfile" "interfaces.kicad_sch")
    (property "Sheetname" "Interfaces")
    (property "Tolerance" "1%")
    (property "Val" "22R")
    (property "ki_description" "22R resistor in 0402 package with 1% tolerance")
    (attr smd)
    (fp_text reference "R6" (at -1.098843 2.438672 90) (layer "F.SilkS")
        (effects (font (size 0.7 0.7) (thickness 0.15)) (justify left bottom))
    )
    (fp_text value "R_22R_0402" (at 0 1.4 90) (layer "F.Fab") hide
        (effects (font (size 0.7 0.7) (thickness 0.15)) (justify left bottom))
    )
    (fp_text user "${REFERENCE}" (at -0.95 3.168 90) (layer "F.Fab") hide
        (effects (font (size 0.7 0.7) (thickness 0.15)) (justify left bottom))
    )
    (fp_text user "License: Apache-2.0" (at -0.95 5.169 90) (layer "F.Fab") hide
        (effects (font (size 0.7 0.7) (thickness 0.15)) (justify left bottom))
    )
    (fp_text user "Author: Antmicro" (at -0.95 4.169 90) (layer "F.Fab") hide
        (effects (font (size 0.7 0.7) (thickness 0.15)) (justify left bottom))
    )
    (fp_rect (start -0.93 -0.47) (end 0.93 0.47)
      (stroke (width 0.05) (type solid)) (fill none) (layer "F.CrtYd"))
    (fp_rect (start -0.5 -0.25) (end 0.5 0.25)
      (stroke (width 0.15) (type solid)) (fill none) (layer "F.Fab"))
    (pad "1" smd roundrect (at -0.485 0 90) (size 0.59 0.64) (layers "F.Cu" "F.Paste" "F.Mask") (roundrect_rratio 0.25)
      (net 590 "Net-(U7-CDBUS0)") (pintype "passive"))
    (pad "2" smd roundrect (at 0.485 0 90) (size 0.59 0.64) (layers "F.Cu" "F.Paste" "F.Mask") (roundrect_rratio 0.25)
      (net 135 "UART0_RX") (pintype "passive"))
  )

  (footprint "data-center-rdimm-ddr4-tester-footprints:R_0402_1005Metric" (layer "F.Cu")
    (at 141.411328 100.247157 90)
    (descr "Resistor SMD 0402")
    (tags "resistor SMD 0402")
    (property "Author" "Antmicro")
    (property "License" "Apache-2.0")
    (property "MPN" "CR0402-FX-22R0GLF")
    (property "Manufacturer" "Bourns")
    (property "Sheetfile" "interfaces.kicad_sch")
    (property "Sheetname" "Interfaces")
    (property "Tolerance" "1%")
    (property "Val" "22R")
    (property "ki_description" "22R resistor in 0402 package with 1% tolerance")
    (attr smd)
    (fp_text reference "R7" (at -1.192843 -1.781328 90) (layer "F.SilkS")
        (effects (font (size 0.7 0.7) (thickness 0.15)) (justify left bottom))
    )
    (fp_text value "R_22R_0402" (at 0 1.4 90) (layer "F.Fab") hide
        (effects (font (size 0.7 0.7) (thickness 0.15)) (justify left bottom))
    )
    (fp_text user "License: Apache-2.0" (at -0.95 5.169 90) (layer "F.Fab") hide
        (effects (font (size 0.7 0.7) (thickness 0.15)) (justify left bottom))
    )
    (fp_text user "Author: Antmicro" (at -0.95 4.169 90) (layer "F.Fab") hide
        (effects (font (size 0.7 0.7) (thickness 0.15)) (justify left bottom))
    )
    (fp_text user "${REFERENCE}" (at -0.95 3.168 90) (layer "F.Fab") hide
        (effects (font (size 0.7 0.7) (thickness 0.15)) (justify left bottom))
    )
    (fp_rect (start -0.93 -0.47) (end 0.93 0.47)
      (stroke (width 0.05) (type solid)) (fill none) (layer "F.CrtYd"))
    (fp_rect (start -0.5 -0.25) (end 0.5 0.25)
      (stroke (width 0.15) (type solid)) (fill none) (layer "F.Fab"))
    (pad "1" smd roundrect (at -0.485 0 90) (size 0.59 0.64) (layers "F.Cu" "F.Paste" "F.Mask") (roundrect_rratio 0.25)
      (net 591 "Net-(U7-CDBUS1)") (pintype "passive"))
    (pad "2" smd roundrect (at 0.485 0 90) (size 0.59 0.64) (layers "F.Cu" "F.Paste" "F.Mask") (roundrect_rratio 0.25)
      (net 137 "UART0_TX") (pintype "passive"))
  )

  (footprint "data-center-rdimm-ddr4-tester-footprints:R_0402_1005Metric" (layer "F.Cu")
    (at 133.911328 102.622157 180)
    (descr "Resistor SMD 0402")
    (tags "resistor SMD 0402")
    (property "Author" "Antmicro")
    (property "License" "Apache-2.0")
    (property "MPN" "CR0402-FX-22R0GLF")
    (property "Manufacturer" "Bourns")
    (property "Sheetfile" "interfaces.kicad_sch")
    (property "Sheetname" "Interfaces")
    (property "Tolerance" "1%")
    (property "Val" "22R")
    (property "ki_description" "22R resistor in 0402 package with 1% tolerance")
    (attr smd)
    (fp_text reference "R8" (at 2.591328 -0.377843 180) (layer "F.SilkS")
        (effects (font (size 0.7 0.7) (thickness 0.15)) (justify left bottom))
    )
    (fp_text value "R_22R_0402" (at 0 1.4 180) (layer "F.Fab") hide
        (effects (font (size 0.7 0.7) (thickness 0.15)) (justify left bottom))
    )
    (fp_text user "License: Apache-2.0" (at -0.95 5.169 180) (layer "F.Fab") hide
        (effects (font (size 0.7 0.7) (thickness 0.15)) (justify left bottom))
    )
    (fp_text user "Author: Antmicro" (at -0.95 4.169 180) (layer "F.Fab") hide
        (effects (font (size 0.7 0.7) (thickness 0.15)) (justify left bottom))
    )
    (fp_text user "${REFERENCE}" (at -0.95 3.168 180) (layer "F.Fab") hide
        (effects (font (size 0.7 0.7) (thickness 0.15)) (justify left bottom))
    )
    (fp_rect (start -0.93 -0.47) (end 0.93 0.47)
      (stroke (width 0.05) (type solid)) (fill none) (layer "F.CrtYd"))
    (fp_rect (start -0.5 -0.25) (end 0.5 0.25)
      (stroke (width 0.15) (type solid)) (fill none) (layer "F.Fab"))
    (pad "1" smd roundrect (at -0.485 0 180) (size 0.59 0.64) (layers "F.Cu" "F.Paste" "F.Mask") (roundrect_rratio 0.25)
      (net 592 "Net-(U7-DDBUS0)") (pintype "passive"))
    (pad "2" smd roundrect (at 0.485 0 180) (size 0.59 0.64) (layers "F.Cu" "F.Paste" "F.Mask") (roundrect_rratio 0.25)
      (net 139 "UART1_RX") (pintype "passive"))
  )

  (footprint "data-center-rdimm-ddr4-tester-footprints:R_0402_1005Metric" (layer "F.Cu")
    (at 133.911328 105.872157 180)
    (descr "Resistor SMD 0402")
    (tags "resistor SMD 0402")
    (property "Author" "Antmicro")
    (property "License" "Apache-2.0")
    (property "MPN" "CR0402-FX-22R0GLF")
    (property "Manufacturer" "Bourns")
    (property "Sheetfile" "interfaces.kicad_sch")
    (property "Sheetname" "Interfaces")
    (property "Tolerance" "1%")
    (property "Val" "22R")
    (property "ki_description" "22R resistor in 0402 package with 1% tolerance")
    (attr smd)
    (fp_text reference "R37" (at 3.061328 -0.387843 180) (layer "F.SilkS")
        (effects (font (size 0.7 0.7) (thickness 0.15)) (justify left bottom))
    )
    (fp_text value "R_22R_0402" (at 0 1.4 180) (layer "F.Fab") hide
        (effects (font (size 0.7 0.7) (thickness 0.15)) (justify left bottom))
    )
    (fp_text user "License: Apache-2.0" (at -0.95 5.169 180) (layer "F.Fab") hide
        (effects (font (size 0.7 0.7) (thickness 0.15)) (justify left bottom))
    )
    (fp_text user "${REFERENCE}" (at -0.95 3.168 180) (layer "F.Fab") hide
        (effects (font (size 0.7 0.7) (thickness 0.15)) (justify left bottom))
    )
    (fp_text user "Author: Antmicro" (at -0.95 4.169 180) (layer "F.Fab") hide
        (effects (font (size 0.7 0.7) (thickness 0.15)) (justify left bottom))
    )
    (fp_rect (start -0.93 -0.47) (end 0.93 0.47)
      (stroke (width 0.05) (type solid)) (fill none) (layer "F.CrtYd"))
    (fp_rect (start -0.5 -0.25) (end 0.5 0.25)
      (stroke (width 0.15) (type solid)) (fill none) (layer "F.Fab"))
    (pad "1" smd roundrect (at -0.485 0 180) (size 0.59 0.64) (layers "F.Cu" "F.Paste" "F.Mask") (roundrect_rratio 0.25)
      (net 602 "Net-(U7-DDBUS1)") (pintype "passive"))
    (pad "2" smd roundrect (at 0.485 0 180) (size 0.59 0.64) (layers "F.Cu" "F.Paste" "F.Mask") (roundrect_rratio 0.25)
      (net 141 "UART1_TX") (pintype "passive"))
  )

  (footprint "data-center-rdimm-ddr4-tester-footprints:C_0402_1005Metric" (layer "F.Cu")
    (at 115.286328 99.122157 -90)
    (descr "Capacitor SMD 0402")
    (tags "capacitor SMD 0402")
    (property "Author" "Antmicro")
    (property "Dielectric" "")
    (property "License" "Apache-2.0")
    (property "MPN" "CC0402MRX5R5BB106")
    (property "Manufacturer" "Yaego")
    (property "Sheetfile" "supply.kicad_sch")
    (property "Sheetname" "Supply")
    (property "Val" "10u")
    (property "Voltage" "")
    (property "ki_description" " ")
    (attr smd)
    (fp_text reference "C38" (at -0.112157 1.426328 -90) (layer "F.SilkS")
        (effects (font (size 0.7 0.7) (thickness 0.15)) (justify left bottom))
    )
    (fp_text value "C_10u_0402" (at 0 1.4 -90) (layer "F.Fab") hide
        (effects (font (size 0.7 0.7) (thickness 0.15)) (justify left bottom))
    )
    (fp_text user "${REFERENCE}" (at -0.932 3.168 -90) (layer "F.Fab") hide
        (effects (font (size 0.7 0.7) (thickness 0.15)) (justify left bottom))
    )
    (fp_text user "License: Apache-2.0" (at -0.932 5.17 -90) (layer "F.Fab") hide
        (effects (font (size 0.7 0.7) (thickness 0.15)) (justify left bottom))
    )
    (fp_text user "Author: Antmicro" (at -0.932 4.17 -90) (layer "F.Fab") hide
        (effects (font (size 0.7 0.7) (thickness 0.15)) (justify left bottom))
    )
    (fp_rect (start -0.94 -0.47) (end 0.94 0.47)
      (stroke (width 0.05) (type solid)) (fill none) (layer "F.CrtYd"))
    (fp_rect (start -0.499 -0.249) (end 0.499 0.249)
      (stroke (width 0.15) (type solid)) (fill none) (layer "F.Fab"))
    (pad "1" smd roundrect (at -0.484 0 270) (size 0.59 0.64) (layers "F.Cu" "F.Paste" "F.Mask") (roundrect_rratio 0.25)
      (net 299 "VCC0V6") (pintype "passive"))
    (pad "2" smd roundrect (at 0.484 0 270) (size 0.59 0.64) (layers "F.Cu" "F.Paste" "F.Mask") (roundrect_rratio 0.25)
      (net 9 "GND") (pintype "passive"))
  )

  (footprint "data-center-rdimm-ddr4-tester-footprints:R_0402_1005Metric" (layer "F.Cu")
    (at 110.286328 115.997157)
    (descr "Resistor SMD 0402")
    (tags "resistor SMD 0402")
    (property "Author" "Antmicro")
    (property "License" "Apache-2.0")
    (property "MPN" "CR0402-FX-2433GLF")
    (property "Manufacturer" "Bourns")
    (property "Sheetfile" "supply.kicad_sch")
    (property "Sheetname" "Supply")
    (property "Tolerance" "1%")
    (property "Val" "243k")
    (property "ki_description" "243k resistor in 0402 package with 1% tolerance")
    (attr smd)
    (fp_text reference "R116" (at -1.447328 2.467843) (layer "F.SilkS")
        (effects (font (size 0.7 0.7) (thickness 0.15)) (justify left bottom))
    )
    (fp_text value "R_243k_0402" (at 0 1.4) (layer "F.Fab") hide
        (effects (font (size 0.7 0.7) (thickness 0.15)) (justify left bottom))
    )
    (fp_text user "License: Apache-2.0" (at -0.95 5.169) (layer "F.Fab") hide
        (effects (font (size 0.7 0.7) (thickness 0.15)) (justify left bottom))
    )
    (fp_text user "${REFERENCE}" (at -0.95 3.168) (layer "F.Fab") hide
        (effects (font (size 0.7 0.7) (thickness 0.15)) (justify left bottom))
    )
    (fp_text user "Author: Antmicro" (at -0.95 4.169) (layer "F.Fab") hide
        (effects (font (size 0.7 0.7) (thickness 0.15)) (justify left bottom))
    )
    (fp_rect (start -0.93 -0.47) (end 0.93 0.47)
      (stroke (width 0.05) (type solid)) (fill none) (layer "F.CrtYd"))
    (fp_rect (start -0.5 -0.25) (end 0.5 0.25)
      (stroke (width 0.15) (type solid)) (fill none) (layer "F.Fab"))
    (pad "1" smd roundrect (at -0.485 0) (size 0.59 0.64) (layers "F.Cu" "F.Paste" "F.Mask") (roundrect_rratio 0.25)
      (net 9 "GND") (pintype "passive"))
    (pad "2" smd roundrect (at 0.485 0) (size 0.59 0.64) (layers "F.Cu" "F.Paste" "F.Mask") (roundrect_rratio 0.25)
      (net 109 "Net-(IC1-RT{slash}CLK)") (pintype "passive"))
  )

  (footprint "data-center-rdimm-ddr4-tester-footprints:R_0402_1005Metric" (layer "F.Cu")
    (at 120.315 116.622157 180)
    (descr "Resistor SMD 0402")
    (tags "resistor SMD 0402")
    (property "Author" "Antmicro")
    (property "License" "Apache-2.0")
    (property "MPN" "CR0402-FX-49R9GLF")
    (property "Manufacturer" "Bourns")
    (property "Sheetfile" "supply.kicad_sch")
    (property "Sheetname" "Supply")
    (property "Tolerance" "1%")
    (property "Val" "49R9")
    (property "ki_description" "49R9 resistor in 0402 package with 1% tolerance")
    (attr smd)
    (fp_text reference "R126" (at 4.315 -3.607843 180) (layer "F.SilkS")
        (effects (font (size 0.7 0.7) (thickness 0.15)) (justify left bottom))
    )
    (fp_text value "R_49R9_0402" (at 0 1.4 180) (layer "F.Fab") hide
        (effects (font (size 0.7 0.7) (thickness 0.15)) (justify left bottom))
    )
    (fp_text user "${REFERENCE}" (at -0.95 3.168 180) (layer "F.Fab") hide
        (effects (font (size 0.7 0.7) (thickness 0.15)) (justify left bottom))
    )
    (fp_text user "Author: Antmicro" (at -0.95 4.169 180) (layer "F.Fab") hide
        (effects (font (size 0.7 0.7) (thickness 0.15)) (justify left bottom))
    )
    (fp_text user "License: Apache-2.0" (at -0.95 5.169 180) (layer "F.Fab") hide
        (effects (font (size 0.7 0.7) (thickness 0.15)) (justify left bottom))
    )
    (fp_rect (start -0.93 -0.47) (end 0.93 0.47)
      (stroke (width 0.05) (type solid)) (fill none) (layer "F.CrtYd"))
    (fp_rect (start -0.5 -0.25) (end 0.5 0.25)
      (stroke (width 0.15) (type solid)) (fill none) (layer "F.Fab"))
    (pad "1" smd roundrect (at -0.485 0 180) (size 0.59 0.64) (layers "F.Cu" "F.Paste" "F.Mask") (roundrect_rratio 0.25)
      (net 104 "VCC5V0") (pintype "passive"))
    (pad "2" smd roundrect (at 0.485 0 180) (size 0.59 0.64) (layers "F.Cu" "F.Paste" "F.Mask") (roundrect_rratio 0.25)
      (net 118 "Net-(R126-Pad2)") (pintype "passive"))
  )

  (footprint "data-center-rdimm-ddr4-tester-footprints:C_0603_1608Metric" (layer "F.Cu")
    (at 116.036328 86.160008 180)
    (descr "Capacitor SMD 0603")
    (tags "capacitor 0603")
    (property "Author" "Antmicro")
    (property "Dielectric" "")
    (property "License" "Apache-2.0")
    (property "MPN" "GRM188R60J226MEA0D")
    (property "Manufacturer" "Murata")
    (property "Sheetfile" "supply.kicad_sch")
    (property "Sheetname" "Supply")
    (property "Val" "22u")
    (property "Voltage" "")
    (property "ki_description" " ")
    (attr smd)
    (fp_text reference "C39" (at 1.666328 12.380008 180) (layer "F.SilkS")
        (effects (font (size 0.7 0.7) (thickness 0.15)) (justify left bottom))
    )
    (fp_text value "C_22u_0603" (at 0 1.6 180) (layer "F.Fab") hide
        (effects (font (size 0.7 0.7) (thickness 0.15)) (justify left bottom))
    )
    (fp_text user "License: Apache-2.0" (at -1.682 5.895 180) (layer "F.Fab") hide
        (effects (font (size 0.7 0.7) (thickness 0.15)) (justify left bottom))
    )
    (fp_text user "Author: Antmicro" (at -1.682 4.894 180) (layer "F.Fab") hide
        (effects (font (size 0.7 0.7) (thickness 0.15)) (justify left bottom))
    )
    (fp_text user "${REFERENCE}" (at -1.682 3.895 180) (layer "F.Fab") hide
        (effects (font (size 0.7 0.7) (thickness 0.15)) (justify left bottom))
    )
    (fp_line (start -0.3 -0.3) (end 0.3 -0.3)
      (stroke (width 0.15) (type solid)) (layer "F.SilkS"))
    (fp_line (start -0.3 0.3) (end 0.3 0.3)
      (stroke (width 0.15) (type solid)) (layer "F.SilkS"))
    (fp_rect (start -1.24 -0.7) (end 1.24 0.7)
      (stroke (width 0.05) (type solid)) (fill none) (layer "F.CrtYd"))
    (fp_rect (start -0.8 -0.4) (end 0.8 0.4)
      (stroke (width 0.15) (type solid)) (fill none) (layer "F.Fab"))
    (pad "1" smd roundrect (at -0.7 0 180) (size 0.6 0.8) (layers "F.Cu" "F.Paste" "F.Mask") (roundrect_rratio 0.2)
      (net 301 "VDD1V2") (pintype "passive"))
    (pad "2" smd roundrect (at 0.7 0 180) (size 0.6 0.8) (layers "F.Cu" "F.Paste" "F.Mask") (roundrect_rratio 0.2)
      (net 9 "GND") (pintype "passive"))
  )

  (footprint "data-center-rdimm-ddr4-tester-footprints:L_2020_5252Metric" (layer "F.Cu")
    (at 125.661328 94.497157)
    (property "Author" "Antmicro")
    (property "IMax" "")
    (property "ISat" "")
    (property "License" "Apache-2.0")
    (property "MPN" "IHLP2020BZER4R7M01")
    (property "Manufacturer" "Vishay")
    (property "Sheetfile" "supply.kicad_sch")
    (property "Sheetname" "Supply")
    (property "Size" "5.18x5.18")
    (property "Val" "4u7/2.8A")
    (attr smd)
    (fp_text reference "L1" (at 0 -3.3) (layer "F.SilkS")
        (effects (font (size 0.7 0.7) (thickness 0.15)) (justify left bottom))
    )
    (fp_text value "L_4u7_2.8A_2020" (at 0 4) (layer "F.Fab") hide
        (effects (font (size 0.7 0.7) (thickness 0.15)) (justify left bottom))
    )
    (fp_text user "License: Apache-2.0" (at -3.29 7.2) (layer "F.Fab") hide
        (effects (font (size 0.7 0.7) (thickness 0.15)) (justify left bottom))
    )
    (fp_text user "Author: Antmicro" (at -3.29 8.4) (layer "F.Fab") hide
        (effects (font (size 0.7 0.7) (thickness 0.15)) (justify left bottom))
    )
    (fp_text user "${REFERENCE}" (at -3.29 6) (layer "F.Fab") hide
        (effects (font (size 0.7 0.7) (thickness 0.15)) (justify left bottom))
    )
    (fp_line (start -2.999 -2.846) (end -2.999 -1.73)
      (stroke (width 0.15) (type solid)) (layer "F.SilkS"))
    (fp_line (start -2.999 1.729) (end -2.999 2.843)
      (stroke (width 0.15) (type solid)) (layer "F.SilkS"))
    (fp_line (start -2.999 2.843) (end 2.996 2.843)
      (stroke (width 0.15) (type solid)) (layer "F.SilkS"))
    (fp_line (start 2.996 -2.846) (end -2.999 -2.846)
      (stroke (width 0.15) (type solid)) (layer "F.SilkS"))
    (fp_line (start 2.996 -1.73) (end 2.996 -2.846)
      (stroke (width 0.15) (type solid)) (layer "F.SilkS"))
    (fp_line (start 2.996 2.843) (end 2.996 1.729)
      (stroke (width 0.15) (type solid)) (layer "F.SilkS"))
    (fp_line (start -3.29 -1.67) (end -3.13 -1.67)
      (stroke (width 0.05) (type solid)) (layer "F.CrtYd"))
    (fp_line (start -3.29 1.65) (end -3.29 -1.67)
      (stroke (width 0.05) (type solid)) (layer "F.CrtYd"))
    (fp_line (start -3.13 -2.98) (end 3.12 -2.98)
      (stroke (width 0.05) (type solid)) (layer "F.CrtYd"))
    (fp_line (start -3.13 -1.67) (end -3.13 -2.98)
      (stroke (width 0.05) (type solid)) (layer "F.CrtYd"))
    (fp_line (start -3.13 1.65) (end -3.29 1.65)
      (stroke (width 0.05) (type solid)) (layer "F.CrtYd"))
    (fp_line (start -3.13 2.97) (end -3.13 1.65)
      (stroke (width 0.05) (type solid)) (layer "F.CrtYd"))
    (fp_line (start 3.12 -2.98) (end 3.12 -1.67)
      (stroke (width 0.05) (type solid)) (layer "F.CrtYd"))
    (fp_line (start 3.12 -1.67) (end 3.26 -1.67)
      (stroke (width 0.05) (type solid)) (layer "F.CrtYd"))
    (fp_line (start 3.12 1.65) (end 3.12 2.97)
      (stroke (width 0.05) (type solid)) (layer "F.CrtYd"))
    (fp_line (start 3.12 2.97) (end -3.13 2.97)
      (stroke (width 0.05) (type solid)) (layer "F.CrtYd"))
    (fp_line (start 3.26 -1.67) (end 3.26 1.65)
      (stroke (width 0.05) (type solid)) (layer "F.CrtYd"))
    (fp_line (start 3.26 1.65) (end 3.12 1.65)
      (stroke (width 0.05) (type solid)) (layer "F.CrtYd"))
    (fp_line (start -2.871 -2.718) (end -2.871 2.717)
      (stroke (width 0.15) (type solid)) (layer "F.Fab"))
    (fp_line (start -2.871 2.717) (end 2.87 2.717)
      (stroke (width 0.15) (type solid)) (layer "F.Fab"))
    (fp_line (start 2.87 -2.718) (end -2.871 -2.718)
      (stroke (width 0.15) (type solid)) (layer "F.Fab"))
    (fp_line (start 2.87 2.717) (end 2.87 -2.718)
      (stroke (width 0.15) (type solid)) (layer "F.Fab"))
    (pad "1" smd rect (at -2.032 0 90) (size 2.794 1.9812) (layers "F.Cu" "F.Paste" "F.Mask")
      (net 571 "Net-(U2-SW_VPP)") (pintype "passive"))
    (pad "2" smd rect (at 2.031 0 90) (size 2.794 1.9812) (layers "F.Cu" "F.Paste" "F.Mask")
      (net 303 "VCC2V5") (pintype "passive"))
  )

  (footprint "data-center-rdimm-ddr4-tester-footprints:PowerDI5" (layer "F.Cu")
    (at 127.4 123.9 90)
    (property "Author" "Antmicro")
    (property "License" "Apache-2.0")
    (property "MPN" "PDS760-13")
    (property "Manufacturer" "Diodes Incorporated")
    (property "Sheetfile" "supply.kicad_sch")
    (property "Sheetname" "Supply")
    (property "ki_description" "PDS760 Series 60 V 7 A Surface Mount Schottky Barrier Rectifier - PowerDI-5")
    (property "ki_keywords" "PDS760 Series 60 V 7 A Surface Mount Schottky Barrier Rectifier - PowerDI-5")
    (attr smd)
    (fp_text reference "D2" (at -3.72 1.71 180) (layer "F.SilkS")
        (effects (font (size 0.7 0.7) (thickness 0.15)) (justify left bottom))
    )
    (fp_text value "PDS760" (at 0 3.4 90) (layer "F.Fab") hide
        (effects (font (size 0.7 0.7) (thickness 0.15)) (justify right bottom))
    )
    (fp_text user "${REFERENCE}" (at -3.302 18.527 90) (layer "F.Fab") hide
        (effects (font (size 0.7 0.7) (thickness 0.15)) (justify left bottom))
    )
    (fp_text user "License: Apache-2.0" (at -3.302 20.928 90) (layer "F.Fab") hide
        (effects (font (size 0.7 0.7) (thickness 0.15)) (justify left bottom))
    )
    (fp_text user "Author: Antmicro" (at -3.302 19.728 90) (layer "F.Fab") hide
        (effects (font (size 0.7 0.7) (thickness 0.15)) (justify left bottom))
    )
    (fp_line (start -2.7 -2) (end 2.7 -2)
      (stroke (width 0.12) (type solid)) (layer "F.SilkS"))
    (fp_line (start -2.7 -1.8) (end -2.7 -2)
      (stroke (width 0.12) (type solid)) (layer "F.SilkS"))
    (fp_line (start -2.7 2.023) (end -2.7 1.823)
      (stroke (width 0.12) (type solid)) (layer "F.SilkS"))
    (fp_line (start 2.7 -2) (end 2.7 -1.8)
      (stroke (width 0.12) (type solid)) (layer "F.SilkS"))
    (fp_line (start 2.7 1.823) (end 2.7 2.023)
      (stroke (width 0.12) (type solid)) (layer "F.SilkS"))
    (fp_line (start 2.7 2.023) (end -2.7 2.023)
      (stroke (width 0.12) (type solid)) (layer "F.SilkS"))
    (fp_rect (start -3.702 -2.3) (end 3.7 2.3)
      (stroke (width 0.05) (type solid)) (fill none) (layer "F.CrtYd"))
    (pad "A" smd roundrect (at -2.862 -0.94 180) (size 1.39 1.4) (layers "F.Cu" "F.Paste" "F.Mask") (roundrect_rratio 0.25)
      (net 9 "GND") (pinfunction "A") (pintype "passive"))
    (pad "A" smd roundrect (at -2.862 0.941) (size 1.39 1.4) (layers "F.Cu" "F.Paste" "F.Mask") (roundrect_rratio 0.25)
      (net 9 "GND") (pinfunction "A") (pintype "passive"))
    (pad "C" smd roundrect (at 1.1 0) (size 3.36 4.86) (layers "F.Cu" "F.Paste" "F.Mask") (roundrect_rratio 0.05)
      (net 73 "Net-(IC1-SW)") (pinfunction "C") (pintype "passive"))
  )

  (footprint "data-center-rdimm-ddr4-tester-footprints:L_WE-PDF" (layer "F.Cu")
    (at 126.911328 113.872157 90)
    (property "Author" "Antmicro")
    (property "IMax" "")
    (property "ISat" "")
    (property "License" "Apache-2.0")
    (property "MPN" "7447798720")
    (property "Manufacturer" "Würth Elektronik")
    (property "Sheetfile" "supply.kicad_sch")
    (property "Sheetname" "Supply")
    (property "Size" "10.2x10.2")
    (property "Val" "7u2/7.9A")
    (attr smd)
    (fp_text reference "L6" (at -6.157843 3.928672) (layer "F.SilkS")
        (effects (font (size 0.7 0.7) (thickness 0.15)) (justify left bottom))
    )
    (fp_text value "L_7u2_7.9A_WE-PDF" (at 0 6.6 270) (layer "F.Fab") hide
        (effects (font (size 0.7 0.7) (thickness 0.15)) (justify left bottom))
    )
    (fp_text user "License: Apache-2.0" (at -5.601 8.6 90) (layer "F.Fab") hide
        (effects (font (size 0.7 0.7) (thickness 0.15)) (justify left bottom))
    )
    (fp_text user "Author: Antmicro" (at -5.601 9.8 90) (layer "F.Fab") hide
        (effects (font (size 0.7 0.7) (thickness 0.15)) (justify left bottom))
    )
    (fp_text user "${REFERENCE}" (at -5.601 11 90) (layer "F.Fab") hide
        (effects (font (size 0.7 0.7) (thickness 0.15)) (justify left bottom))
    )
    (fp_line (start -5.202 -5.202) (end 4.099 -5.202)
      (stroke (width 0.15) (type solid)) (layer "F.SilkS"))
    (fp_line (start -5.202 -2) (end -5.202 -5.202)
      (stroke (width 0.15) (type solid)) (layer "F.SilkS"))
    (fp_line (start -5.202 5.2) (end -5.202 1.999)
      (stroke (width 0.15) (type solid)) (layer "F.SilkS"))
    (fp_line (start 4.099 -5.202) (end 5.2 -4.1)
      (stroke (width 0.15) (type solid)) (layer "F.SilkS"))
    (fp_line (start 5.2 -4.1) (end 5.2 -2)
      (stroke (width 0.15) (type solid)) (layer "F.SilkS"))
    (fp_line (start 5.2 1.999) (end 5.2 4.2)
      (stroke (width 0.15) (type solid)) (layer "F.SilkS"))
    (fp_line (start 5.2 4.2) (end 5.2 5.2)
      (stroke (width 0.15) (type solid)) (layer "F.SilkS"))
    (fp_line (start 5.2 5.2) (end -5.202 5.2)
      (stroke (width 0.15) (type solid)) (layer "F.SilkS"))
    (fp_rect (start -5.601 -5.601) (end 5.599 5.599)
      (stroke (width 0.05) (type solid)) (fill none) (layer "F.CrtYd"))
    (pad "1" smd rect (at -4.1 0 180) (size 3.4 2.4) (layers "F.Cu" "F.Paste" "F.Mask")
      (net 73 "Net-(IC1-SW)") (pintype "passive"))
    (pad "2" smd rect (at 4.099 0 180) (size 3.4 2.4) (layers "F.Cu" "F.Paste" "F.Mask")
      (net 104 "VCC5V0") (pintype "passive"))
  )

  (footprint "data-center-rdimm-ddr4-tester-footprints:Testpoint_smd_1mm" (layer "F.Cu")
    (at 109.966328 92.580008 90)
    (property "Author" "Antmicro")
    (property "License" "Apache-2.0")
    (property "MPN" "")
    (property "Manufacturer" "")
    (property "Sheetfile" "supply.kicad_sch")
    (property "Sheetname" "Supply")
    (property "ki_description" "Test Point 1mm")
    (attr exclude_from_pos_files)
    (fp_text reference "0V6" (at 0.660008 -1.726328 180) (layer "F.SilkS")
        (effects (font (size 0.7 0.7) (thickness 0.15)) (justify left bottom))
    )
    (fp_text value "TP_1mm_SMD" (at 0 1.4 90) (layer "F.Fab") hide
        (effects (font (size 0.7 0.7) (thickness 0.15)) (justify left bottom))
    )
    (fp_text user "${REFERENCE}" (at -0.5 2.8 90) (layer "F.Fab") hide
        (effects (font (size 0.7 0.7) (thickness 0.15)) (justify left bottom))
    )
    (fp_text user "License: Apache-2.0" (at -0.5 5.2 90) (layer "F.Fab") hide
        (effects (font (size 0.7 0.7) (thickness 0.15)) (justify left bottom))
    )
    (fp_text user "Author: Antmicro" (at -0.5 4 90) (layer "F.Fab") hide
        (effects (font (size 0.7 0.7) (thickness 0.15)) (justify left bottom))
    )
    (pad "1" smd circle (at 0 0 90) (size 1 1) (layers "F.Cu" "F.Mask")
      (net 299 "VCC0V6") (pinfunction "1") (pintype "passive"))
  )

  (footprint "data-center-rdimm-ddr4-tester-footprints:Testpoint_smd_1mm" (layer "F.Cu")
    (at 129.5 97.5 180)
    (property "Author" "Antmicro")
    (property "License" "Apache-2.0")
    (property "MPN" "")
    (property "Manufacturer" "")
    (property "Sheetfile" "supply.kicad_sch")
    (property "Sheetname" "Supply")
    (property "ki_description" "Test Point 1mm")
    (attr exclude_from_pos_files)
    (fp_text reference "2V5" (at 1.05 -1.41 180) (layer "F.SilkS")
        (effects (font (size 0.7 0.7) (thickness 0.15)) (justify left bottom))
    )
    (fp_text value "TP_1mm_SMD" (at 0 1.4 180) (layer "F.Fab") hide
        (effects (font (size 0.7 0.7) (thickness 0.15)) (justify left bottom))
    )
    (fp_text user "${REFERENCE}" (at -0.5 2.8 180) (layer "F.Fab") hide
        (effects (font (size 0.7 0.7) (thickness 0.15)) (justify left bottom))
    )
    (fp_text user "Author: Antmicro" (at -0.5 4 180) (layer "F.Fab") hide
        (effects (font (size 0.7 0.7) (thickness 0.15)) (justify left bottom))
    )
    (fp_text user "License: Apache-2.0" (at -0.5 5.2 180) (layer "F.Fab") hide
        (effects (font (size 0.7 0.7) (thickness 0.15)) (justify left bottom))
    )
    (pad "1" smd circle (at 0 0 180) (size 1 1) (layers "F.Cu" "F.Mask")
      (net 303 "VCC2V5") (pinfunction "1") (pintype "passive"))
  )

  (footprint "data-center-rdimm-ddr4-tester-footprints:L_1210_3225Metric" (layer "F.Cu")
    (at 119.036328 93.247157 180)
    (property "Author" "Antmicro")
    (property "IMax" "")
    (property "ISat" "")
    (property "License" "Apache-2.0")
    (property "MPN" "DFE322512F-R68M=P2")
    (property "Manufacturer" "Murata")
    (property "Sheetfile" "supply.kicad_sch")
    (property "Sheetname" "Supply")
    (property "Size" "3.2x2.5")
    (property "Val" "680n/6.1A")
    (attr smd)
    (fp_text reference "L2" (at 2.056328 1.587157 180) (layer "F.SilkS")
        (effects (font (size 0.7 0.7) (thickness 0.15)) (justify left bottom))
    )
    (fp_text value "L_680n_6.1A_1210" (at 0 2.4 180) (layer "F.Fab") hide
        (effects (font (size 0.7 0.7) (thickness 0.15)) (justify left bottom))
    )
    (fp_text user "Author: Antmicro" (at -2.1 5.15 180) (layer "F.Fab") hide
        (effects (font (size 0.7 0.7) (thickness 0.15)) (justify left bottom))
    )
    (fp_text user "${REFERENCE}" (at -2.1 3.95 180) (layer "F.Fab") hide
        (effects (font (size 0.7 0.7) (thickness 0.15)) (justify left bottom))
    )
    (fp_text user "License: Apache-2.0" (at -2.1 6.35 180) (layer "F.Fab") hide
        (effects (font (size 0.7 0.7) (thickness 0.15)) (justify left bottom))
    )
    (fp_line (start -0.7 -1.4) (end 0.7 -1.4)
      (stroke (width 0.15) (type solid)) (layer "F.SilkS"))
    (fp_line (start -0.7 1.4) (end 0.7 1.4)
      (stroke (width 0.15) (type solid)) (layer "F.SilkS"))
    (fp_rect (start -2.1 -1.5) (end 2.09 1.5)
      (stroke (width 0.05) (type solid)) (fill none) (layer "F.CrtYd"))
    (fp_line (start -1.701 1.35) (end -1.701 -1.351)
      (stroke (width 0.15) (type solid)) (layer "F.Fab"))
    (fp_line (start 1.7 -1.351) (end -1.701 -1.351)
      (stroke (width 0.15) (type solid)) (layer "F.Fab"))
    (fp_line (start 1.7 1.35) (end -1.701 1.35)
      (stroke (width 0.15) (type solid)) (layer "F.Fab"))
    (fp_line (start 1.7 1.35) (end 1.7 -1.351)
      (stroke (width 0.15) (type solid)) (layer "F.Fab"))
    (pad "1" smd rect (at -1.439 0 180) (size 1.24 2.72) (layers "F.Cu" "F.Paste" "F.Mask")
      (net 1 "Net-(U2-SW)") (pintype "passive"))
    (pad "2" smd rect (at 1.439 0 180) (size 1.24 2.72) (layers "F.Cu" "F.Paste" "F.Mask")
      (net 301 "VDD1V2") (pintype "passive"))
  )

  (footprint "data-center-rdimm-ddr4-tester-footprints:Testpoint_smd_1mm" (layer "F.Cu")
    (at 123.136328 80.360008)
    (property "Author" "Antmicro")
    (property "License" "Apache-2.0")
    (property "MPN" "")
    (property "Manufacturer" "")
    (property "Sheetfile" "supply.kicad_sch")
    (property "Sheetname" "Supply")
    (property "ki_description" "Test Point 1mm")
    (attr exclude_from_pos_files)
    (fp_text reference "1V2" (at -1.056328 -0.740008) (layer "F.SilkS")
        (effects (font (size 0.7 0.7) (thickness 0.15)) (justify left bottom))
    )
    (fp_text value "TP_1mm_SMD" (at 0 1.4) (layer "F.Fab") hide
        (effects (font (size 0.7 0.7) (thickness 0.15)) (justify left bottom))
    )
    (fp_text user "License: Apache-2.0" (at -0.5 5.2) (layer "F.Fab") hide
        (effects (font (size 0.7 0.7) (thickness 0.15)) (justify left bottom))
    )
    (fp_text user "Author: Antmicro" (at -0.5 4) (layer "F.Fab") hide
        (effects (font (size 0.7 0.7) (thickness 0.15)) (justify left bottom))
    )
    (fp_text user "${REFERENCE}" (at -0.5 2.8) (layer "F.Fab") hide
        (effects (font (size 0.7 0.7) (thickness 0.15)) (justify left bottom))
    )
    (pad "1" smd circle (at 0 0) (size 1 1) (layers "F.Cu" "F.Mask")
      (net 301 "VDD1V2") (pinfunction "1") (pintype "passive"))
  )

  (footprint "data-center-rdimm-ddr4-tester-footprints:WSON-10_4x4" (layer "F.Cu")
    (at 114.286328 114.422157)
    (property "Author" "Antmicro")
    (property "License" "Apache-2.0")
    (property "MPN" "TPS54561QDPRRQ1")
    (property "Manufacturer" "Texas Instruments")
    (property "Sheetfile" "supply.kicad_sch")
    (property "Sheetname" "Supply")
    (property "ki_description" " 4.5-V to 60-V Input, 5-A, Step-Down DC-DC Converter")
    (attr smd)
    (fp_text reference "IC1" (at 2.423672 -0.712157 180) (layer "F.SilkS")
        (effects (font (size 0.7 0.7) (thickness 0.15)) (justify left bottom))
    )
    (fp_text value "TPS54561QDPRRQ1" (at 0 3.4 180) (layer "F.Fab") hide
        (effects (font (size 0.7 0.7) (thickness 0.15)) (justify left bottom))
    )
    (fp_text user "${REFERENCE}" (at -2.52 5.4) (layer "F.Fab") hide
        (effects (font (size 0.7 0.7) (thickness 0.15)) (justify left bottom))
    )
    (fp_text user "License: Apache-2.0" (at -2.52 7.8) (layer "F.Fab") hide
        (effects (font (size 0.7 0.7) (thickness 0.15)) (justify left bottom))
    )
    (fp_text user "Author: Antmicro" (at -2.52 6.6) (layer "F.Fab") hide
        (effects (font (size 0.7 0.7) (thickness 0.15)) (justify left bottom))
    )
    (fp_line (start -2.1 -2.123) (end -2.1 -1.877)
      (stroke (width 0.15) (type solid)) (layer "F.SilkS"))
    (fp_line (start -2.1 -2.123) (end 2.1 -2.123)
      (stroke (width 0.15) (type solid)) (layer "F.SilkS"))
    (fp_line (start -2.1 2.096) (end -2.1 1.85)
      (stroke (width 0.15) (type solid)) (layer "F.SilkS"))
    (fp_line (start 2.1 -2.123) (end 2.1 -1.877)
      (stroke (width 0.15) (type solid)) (layer "F.SilkS"))
    (fp_line (start 2.1 2.122) (end -2.1 2.122)
      (stroke (width 0.15) (type solid)) (layer "F.SilkS"))
    (fp_line (start 2.1 2.122) (end 2.1 1.876)
      (stroke (width 0.15) (type solid)) (layer "F.SilkS"))
    (fp_circle (center -2.4 -2) (end -2.35 -2)
      (stroke (width 0.15) (type solid)) (fill solid) (layer "F.SilkS"))
    (fp_rect (start -2.57 -2.2) (end 2.469 2.2)
      (stroke (width 0.05) (type solid)) (fill none) (layer "F.CrtYd"))
    (fp_line (start -1.7 -2) (end -2 -1.7)
      (stroke (width 0.15) (type solid)) (layer "F.Fab"))
    (fp_rect (start -2.02 -2) (end 2.02 2)
      (stroke (width 0.15) (type solid)) (fill none) (layer "F.Fab"))
    (pad "1" smd roundrect (at -2.039 -1.603 90) (size 0.356 0.85) (layers "F.Cu" "F.Paste" "F.Mask") (roundrect_rratio 0.25)
      (net 71 "Net-(IC1-BOOT)") (pinfunction "BOOT") (pintype "passive"))
    (pad "2" smd roundrect (at -2.039 -0.804 90) (size 0.356 0.85) (layers "F.Cu" "F.Paste" "F.Mask") (roundrect_rratio 0.25)
      (net 103 "VIN") (pinfunction "VDD") (pintype "passive"))
    (pad "3" smd roundrect (at -2.039 -0.003 90) (size 0.356 0.85) (layers "F.Cu" "F.Paste" "F.Mask") (roundrect_rratio 0.25)
      (net 167 "/Supply/SYS_EN") (pinfunction "EN") (pintype "passive"))
    (pad "4" smd roundrect (at -2.039 0.797 90) (size 0.356 0.85) (layers "F.Cu" "F.Paste" "F.Mask") (roundrect_rratio 0.25)
      (net 53 "Net-(IC1-SS{slash}TR)") (pinfunction "SS/TR") (pintype "passive"))
    (pad "5" smd roundrect (at -2.039 1.596 90) (size 0.356 0.85) (layers "F.Cu" "F.Paste" "F.Mask") (roundrect_rratio 0.25)
      (net 109 "Net-(IC1-RT{slash}CLK)") (pinfunction "RT/CLK") (pintype "passive"))
    (pad "6" smd roundrect (at 1.961 1.596 90) (size 0.356 0.85) (layers "F.Cu" "F.Paste" "F.Mask") (roundrect_rratio 0.25)
      (net 110 "Net-(IC1-FB)") (pinfunction "FB") (pintype "passive"))
    (pad "7" smd roundrect (at 1.961 0.797 90) (size 0.356 0.85) (layers "F.Cu" "F.Paste" "F.Mask") (roundrect_rratio 0.25)
      (net 69 "Net-(IC1-COMP)") (pinfunction "COMP") (pintype "passive"))
    (pad "8" smd roundrect (at 1.961 -0.003 90) (size 0.356 0.85) (layers "F.Cu" "F.Paste" "F.Mask") (roundrect_rratio 0.25)
      (net 9 "GND") (pinfunction "GND") (pintype "power_in"))
    (pad "9" smd roundrect (at 1.961 -0.804 90) (size 0.356 0.85) (layers "F.Cu" "F.Paste" "F.Mask") (roundrect_rratio 0.25)
      (net 73 "Net-(IC1-SW)") (pinfunction "SW") (pintype "passive"))
    (pad "10" smd roundrect (at 1.961 -1.603 90) (size 0.356 0.85) (layers "F.Cu" "F.Paste" "F.Mask") (roundrect_rratio 0.25)
      (net 536 "/Supply/SYS_PWR_GOOD") (pinfunction "PWRGD") (pintype "passive"))
    (pad "11" smd roundrect (at -0.038 -0.003 180) (size 2.6 3) (layers "F.Cu" "F.Paste" "F.Mask") (roundrect_rratio 0.05)
      (net 9 "GND") (pinfunction "GND") (pintype "passive"))
  )

  (footprint "data-center-rdimm-ddr4-tester-footprints:R_0402_1005Metric" (layer "F.Cu")
    (at 116.4 99.1 90)
    (descr "Resistor SMD 0402")
    (tags "resistor SMD 0402")
    (property "Author" "Antmicro")
    (property "Current" "1A")
    (property "License" "Apache-2.0")
    (property "MPN" "ERJ2GE0R00X")
    (property "Manufacturer" "Panasonic")
    (property "Sheetfile" "supply.kicad_sch")
    (property "Sheetname" "Supply")
    (property "Tolerance" "")
    (property "Val" "0R")
    (property "ki_description" "0R resistor in 0402 package with unspecified tolerance")
    (attr smd)
    (fp_text reference "R42" (at 0.09 -1.6 90) (layer "F.SilkS")
        (effects (font (size 0.7 0.7) (thickness 0.15)) (justify left bottom))
    )
    (fp_text value "R_0R_0402" (at 0 1.4 90) (layer "F.Fab") hide
        (effects (font (size 0.7 0.7) (thickness 0.15)) (justify left bottom))
    )
    (fp_text user "License: Apache-2.0" (at -0.95 5.169 90) (layer "F.Fab") hide
        (effects (font (size 0.7 0.7) (thickness 0.15)) (justify left bottom))
    )
    (fp_text user "${REFERENCE}" (at -0.95 3.168 90) (layer "F.Fab") hide
        (effects (font (size 0.7 0.7) (thickness 0.15)) (justify left bottom))
    )
    (fp_text user "Author: Antmicro" (at -0.95 4.169 90) (layer "F.Fab") hide
        (effects (font (size 0.7 0.7) (thickness 0.15)) (justify left bottom))
    )
    (fp_rect (start -0.93 -0.47) (end 0.93 0.47)
      (stroke (width 0.05) (type solid)) (fill none) (layer "F.CrtYd"))
    (fp_rect (start -0.5 -0.25) (end 0.5 0.25)
      (stroke (width 0.15) (type solid)) (fill none) (layer "F.Fab"))
    (pad "1" smd roundrect (at -0.485 0 90) (size 0.59 0.64) (layers "F.Cu" "F.Paste" "F.Mask") (roundrect_rratio 0.25)
      (net 616 "Net-(U2-VTTSNS)") (pintype "passive"))
    (pad "2" smd roundrect (at 0.485 0 90) (size 0.59 0.64) (layers "F.Cu" "F.Paste" "F.Mask") (roundrect_rratio 0.25)
      (net 299 "VCC0V6") (pintype "passive"))
  )

  (footprint "data-center-rdimm-ddr4-tester-footprints:BarrelJack_3167288_Horizontal" (layer "F.Cu")
    (at 118.35 124.3)
    (property "Author" "Antmicro")
    (property "License" "Apache-2.0")
    (property "MPN" "MJ-179PH")
    (property "Manufacturer" "Multicomp Pro")
    (property "Sheetfile" "supply.kicad_sch")
    (property "Sheetname" "Supply")
    (property "ki_description" "DC Power Connector, Jack, 4 A, 1.95 mm, PCB Mount, Through Hole")
    (property "ki_keywords" "HORIZONTAL, THT, JACK, CONNECTOR, POWER")
    (attr through_hole)
    (fp_text reference "J3" (at 0 -1.4) (layer "F.SilkS")
        (effects (font (size 0.7 0.7) (thickness 0.15)) (justify left bottom))
    )
    (fp_text value "BarrelJack_3167288" (at 0 15.4) (layer "F.Fab")
        (effects (font (size 0.7 0.7) (thickness 0.15)) (justify left bottom))
    )
    (fp_text user "License: Apache-2.0" (at -5.1 18.802) (layer "F.Fab") hide
        (effects (font (size 0.7 0.7) (thickness 0.15)) (justify left bottom))
    )
    (fp_text user "${REFERENCE}" (at -5.1 16.4) (layer "F.Fab") hide
        (effects (font (size 0.7 0.7) (thickness 0.15)) (justify left bottom))
    )
    (fp_text user "Author: Antmicro" (at -5.1 17.601) (layer "F.Fab") hide
        (effects (font (size 0.7 0.7) (thickness 0.15)) (justify left bottom))
    )
    (fp_line (start -4.8 -0.1) (end -2.4 -0.1)
      (stroke (width 0.15) (type solid)) (layer "F.SilkS"))
    (fp_line (start -4.8 10.1) (end 4.8 10.1)
      (stroke (width 0.15) (type solid)) (layer "F.SilkS"))
    (fp_line (start -4.8 14) (end -4.8 -0.1)
      (stroke (width 0.15) (type solid)) (layer "F.SilkS"))
    (fp_line (start -4.8 14) (end 4.8 14)
      (stroke (width 0.15) (type solid)) (layer "F.SilkS"))
    (fp_line (start 2.4 -0.1) (end 4.8 -0.1)
      (stroke (width 0.15) (type solid)) (layer "F.SilkS"))
    (fp_line (start 4.8 -0.1) (end 4.8 0.8255)
      (stroke (width 0.15) (type solid)) (layer "F.SilkS"))
    (fp_line (start 4.8 14) (end 4.8 5.1)
      (stroke (width 0.15) (type solid)) (layer "F.SilkS"))
    (fp_line (start -5.1 -0.4) (end -5.1 14.3)
      (stroke (width 0.05) (type solid)) (layer "F.CrtYd"))
    (fp_line (start -5.1 14.3) (end 5.1 14.3)
      (stroke (width 0.05) (type solid)) (layer "F.CrtYd"))
    (fp_line (start -2.5 -1.3) (end -2.5 -0.4)
      (stroke (width 0.05) (type solid)) (layer "F.CrtYd"))
    (fp_line (start -2.5 -0.4) (end -5.1 -0.4)
      (stroke (width 0.05) (type solid)) (layer "F.CrtYd"))
    (fp_line (start 2.5 -1.3) (end -2.5 -1.3)
      (stroke (width 0.05) (type solid)) (layer "F.CrtYd"))
    (fp_line (start 2.5 -0.4) (end 2.5 -1.3)
      (stroke (width 0.05) (type solid)) (layer "F.CrtYd"))
    (fp_line (start 5.1 -0.4) (end 2.5 -0.4)
      (stroke (width 0.05) (type solid)) (layer "F.CrtYd"))
    (fp_line (start 5.1 0.7) (end 5.1 -0.4)
      (stroke (width 0.05) (type solid)) (layer "F.CrtYd"))
    (fp_line (start 5.1 5.2) (end 6.1 5.2)
      (stroke (width 0.05) (type solid)) (layer "F.CrtYd"))
    (fp_line (start 5.1 14.3) (end 5.1 5.2)
      (stroke (width 0.05) (type solid)) (layer "F.CrtYd"))
    (fp_line (start 6.1 0.7) (end 5.1 0.7)
      (stroke (width 0.05) (type solid)) (layer "F.CrtYd"))
    (fp_line (start 6.1 5.2) (end 6.1 0.7)
      (stroke (width 0.05) (type solid)) (layer "F.CrtYd"))
    (fp_line (start -3.6 -0.4) (end -4.5 0.5)
      (stroke (width 0.15) (type solid)) (layer "F.Fab"))
    (fp_rect (start -4.5 -0.4) (end 5.111 13.7)
      (stroke (width 0.15) (type solid)) (fill none) (layer "F.Fab"))
    (pad "1" thru_hole oval (at 0 0 270) (size 2 4.5) (drill oval 1 3.5) (layers "*.Cu" "*.Mask")
      (net 626 "VIN_RAW") (pinfunction "1") (pintype "passive"))
    (pad "2" thru_hole oval (at 4.879 2.948 180) (size 1.99 4) (drill oval 1 3) (layers "*.Cu" "*.Mask")
      (net 9 "GND") (pinfunction "2") (pintype "passive"))
    (pad "3" thru_hole oval (at 0 5.999 90) (size 2 4) (drill oval 1 3) (layers "*.Cu" "*.Mask")
      (net 9 "GND") (pinfunction "3") (pintype "passive"))
  )

  (footprint "data-center-rdimm-ddr4-tester-footprints:C_0603_1608Metric" (layer "F.Cu")
    (at 119.536328 102.497157)
    (descr "Capacitor SMD 0603")
    (tags "capacitor 0603")
    (property "Author" "Antmicro")
    (property "Dielectric" "")
    (property "License" "Apache-2.0")
    (property "MPN" "C1608X5R1E106M080AC")
    (property "Manufacturer" "TDK")
    (property "Sheetfile" "supply.kicad_sch")
    (property "Sheetname" "Supply")
    (property "Val" "10u/25V")
    (property "Voltage" "")
    (property "ki_description" " ")
    (attr smd)
    (fp_text reference "C27" (at -1.156328 -0.467157) (layer "F.SilkS")
        (effects (font (size 0.7 0.7) (thickness 0.15)) (justify left bottom))
    )
    (fp_text value "C_10u_25V_0603" (at 0 1.6) (layer "F.Fab") hide
        (effects (font (size 0.7 0.7) (thickness 0.15)) (justify left bottom))
    )
    (fp_text user "${REFERENCE}" (at -1.682 3.895) (layer "F.Fab") hide
        (effects (font (size 0.7 0.7) (thickness 0.15)) (justify left bottom))
    )
    (fp_text user "Author: Antmicro" (at -1.682 4.894) (layer "F.Fab") hide
        (effects (font (size 0.7 0.7) (thickness 0.15)) (justify left bottom))
    )
    (fp_text user "License: Apache-2.0" (at -1.682 5.895) (layer "F.Fab") hide
        (effects (font (size 0.7 0.7) (thickness 0.15)) (justify left bottom))
    )
    (fp_line (start -0.3 -0.3) (end 0.3 -0.3)
      (stroke (width 0.15) (type solid)) (layer "F.SilkS"))
    (fp_line (start -0.3 0.3) (end 0.3 0.3)
      (stroke (width 0.15) (type solid)) (layer "F.SilkS"))
    (fp_rect (start -1.24 -0.7) (end 1.24 0.7)
      (stroke (width 0.05) (type solid)) (fill none) (layer "F.CrtYd"))
    (fp_rect (start -0.8 -0.4) (end 0.8 0.4)
      (stroke (width 0.15) (type solid)) (fill none) (layer "F.Fab"))
    (pad "1" smd roundrect (at -0.7 0) (size 0.6 0.8) (layers "F.Cu" "F.Paste" "F.Mask") (roundrect_rratio 0.2)
      (net 103 "VIN") (pintype "passive"))
    (pad "2" smd roundrect (at 0.7 0) (size 0.6 0.8) (layers "F.Cu" "F.Paste" "F.Mask") (roundrect_rratio 0.2)
      (net 9 "GND") (pintype "passive"))
  )

  (footprint "data-center-rdimm-ddr4-tester-footprints:C_0402_1005Metric" (layer "F.Cu")
    (at 117.911328 114.997157 90)
    (descr "Capacitor SMD 0402")
    (tags "capacitor SMD 0402")
    (property "Author" "Antmicro")
    (property "Dielectric" "C0G")
    (property "License" "Apache-2.0")
    (property "MPN" "GRM1555C1E470JA01D")
    (property "Manufacturer" "Murata")
    (property "Sheetfile" "supply.kicad_sch")
    (property "Sheetname" "Supply")
    (property "Val" "47p")
    (property "Voltage" "")
    (property "ki_description" " ")
    (attr smd)
    (fp_text reference "C175" (at -4.492843 -3.621328 90) (layer "F.SilkS")
        (effects (font (size 0.7 0.7) (thickness 0.15)) (justify left bottom))
    )
    (fp_text value "C_47p_0402" (at 0 1.4 90) (layer "F.Fab") hide
        (effects (font (size 0.7 0.7) (thickness 0.15)) (justify left bottom))
    )
    (fp_text user "${REFERENCE}" (at -0.932 3.168 90) (layer "F.Fab") hide
        (effects (font (size 0.7 0.7) (thickness 0.15)) (justify left bottom))
    )
    (fp_text user "Author: Antmicro" (at -0.932 4.17 90) (layer "F.Fab") hide
        (effects (font (size 0.7 0.7) (thickness 0.15)) (justify left bottom))
    )
    (fp_text user "License: Apache-2.0" (at -0.932 5.17 90) (layer "F.Fab") hide
        (effects (font (size 0.7 0.7) (thickness 0.15)) (justify left bottom))
    )
    (fp_rect (start -0.94 -0.47) (end 0.94 0.47)
      (stroke (width 0.05) (type solid)) (fill none) (layer "F.CrtYd"))
    (fp_rect (start -0.499 -0.249) (end 0.499 0.249)
      (stroke (width 0.15) (type solid)) (fill none) (layer "F.Fab"))
    (pad "1" smd roundrect (at -0.484 0 90) (size 0.59 0.64) (layers "F.Cu" "F.Paste" "F.Mask") (roundrect_rratio 0.25)
      (net 69 "Net-(IC1-COMP)") (pintype "passive"))
    (pad "2" smd roundrect (at 0.484 0 90) (size 0.59 0.64) (layers "F.Cu" "F.Paste" "F.Mask") (roundrect_rratio 0.25)
      (net 9 "GND") (pintype "passive"))
  )

  (footprint "data-center-rdimm-ddr4-tester-footprints:C_0402_1005Metric" (layer "F.Cu")
    (at 115.661328 100.747157 180)
    (descr "Capacitor SMD 0402")
    (tags "capacitor SMD 0402")
    (property "Author" "Antmicro")
    (property "Dielectric" "")
    (property "License" "Apache-2.0")
    (property "MPN" "C1005X5R1E474M050BB")
    (property "Manufacturer" "TDK")
    (property "Sheetfile" "supply.kicad_sch")
    (property "Sheetname" "Supply")
    (property "Val" "470n")
    (property "Voltage" "")
    (property "ki_description" " ")
    (attr smd)
    (fp_text reference "C36" (at 0.091328 -1.212843) (layer "F.SilkS")
        (effects (font (size 0.7 0.7) (thickness 0.15)) (justify left bottom))
    )
    (fp_text value "C_470n_0402" (at 0 1.4 180) (layer "F.Fab") hide
        (effects (font (size 0.7 0.7) (thickness 0.15)) (justify left bottom))
    )
    (fp_text user "${REFERENCE}" (at -0.932 3.168 180) (layer "F.Fab") hide
        (effects (font (size 0.7 0.7) (thickness 0.15)) (justify left bottom))
    )
    (fp_text user "Author: Antmicro" (at -0.932 4.17 180) (layer "F.Fab") hide
        (effects (font (size 0.7 0.7) (thickness 0.15)) (justify left bottom))
    )
    (fp_text user "License: Apache-2.0" (at -0.932 5.17 180) (layer "F.Fab") hide
        (effects (font (size 0.7 0.7) (thickness 0.15)) (justify left bottom))
    )
    (fp_rect (start -0.94 -0.47) (end 0.94 0.47)
      (stroke (width 0.05) (type solid)) (fill none) (layer "F.CrtYd"))
    (fp_rect (start -0.499 -0.249) (end 0.499 0.249)
      (stroke (width 0.15) (type solid)) (fill none) (layer "F.Fab"))
    (pad "1" smd roundrect (at -0.484 0 180) (size 0.59 0.64) (layers "F.Cu" "F.Paste" "F.Mask") (roundrect_rratio 0.25)
      (net 305 "/Supply/VTTREF") (pintype "passive"))
    (pad "2" smd roundrect (at 0.484 0 180) (size 0.59 0.64) (layers "F.Cu" "F.Paste" "F.Mask") (roundrect_rratio 0.25)
      (net 9 "GND") (pintype "passive"))
  )

  (footprint "data-center-rdimm-ddr4-tester-footprints:Testpoint_smd_1mm" (layer "F.Cu")
    (at 109.287128 113.610008 90)
    (property "Author" "Antmicro")
    (property "License" "Apache-2.0")
    (property "MPN" "")
    (property "Manufacturer" "")
    (property "Sheetfile" "supply.kicad_sch")
    (property "Sheetname" "Supply")
    (property "ki_description" "Test Point 1mm")
    (attr exclude_from_pos_files)
    (fp_text reference "TP9" (at -0.809992 -0.637128 90) (layer "F.SilkS")
        (effects (font (size 0.7 0.7) (thickness 0.15)) (justify left bottom))
    )
    (fp_text value "TP_1mm_SMD" (at 0 1.4 90) (layer "F.Fab") hide
        (effects (font (size 0.7 0.7) (thickness 0.15)) (justify left bottom))
    )
    (fp_text user "Author: Antmicro" (at -0.5 4 90) (layer "F.Fab") hide
        (effects (font (size 0.7 0.7) (thickness 0.15)) (justify left bottom))
    )
    (fp_text user "License: Apache-2.0" (at -0.5 5.2 90) (layer "F.Fab") hide
        (effects (font (size 0.7 0.7) (thickness 0.15)) (justify left bottom))
    )
    (fp_text user "${REFERENCE}" (at -0.5 2.8 90) (layer "F.Fab") hide
        (effects (font (size 0.7 0.7) (thickness 0.15)) (justify left bottom))
    )
    (pad "1" smd circle (at 0 0 90) (size 1 1) (layers "F.Cu" "F.Mask")
      (net 167 "/Supply/SYS_EN") (pinfunction "1") (pintype "passive"))
  )

  (footprint "data-center-rdimm-ddr4-tester-footprints:R_0402_1005Metric" (layer "F.Cu")
    (at 118.411328 117.747157)
    (descr "Resistor SMD 0402")
    (tags "resistor SMD 0402")
    (property "Author" "Antmicro")
    (property "License" "Apache-2.0")
    (property "MPN" "CR0402-FX-1022GLF")
    (property "Manufacturer" "Bourns")
    (property "Sheetfile" "supply.kicad_sch")
    (property "Sheetname" "Supply")
    (property "Tolerance" "1%")
    (property "Val" "10k2")
    (property "ki_description" "10k2 resistor in 0402 package with 1% tolerance")
    (attr smd)
    (fp_text reference "R128" (at -5.171328 3.382843) (layer "F.SilkS")
        (effects (font (size 0.7 0.7) (thickness 0.15)) (justify left bottom))
    )
    (fp_text value "R_10k2_0402" (at 0 1.4) (layer "F.Fab") hide
        (effects (font (size 0.7 0.7) (thickness 0.15)) (justify left bottom))
    )
    (fp_text user "License: Apache-2.0" (at -0.95 5.169) (layer "F.Fab") hide
        (effects (font (size 0.7 0.7) (thickness 0.15)) (justify left bottom))
    )
    (fp_text user "${REFERENCE}" (at -0.95 3.168) (layer "F.Fab") hide
        (effects (font (size 0.7 0.7) (thickness 0.15)) (justify left bottom))
    )
    (fp_text user "Author: Antmicro" (at -0.95 4.169) (layer "F.Fab") hide
        (effects (font (size 0.7 0.7) (thickness 0.15)) (justify left bottom))
    )
    (fp_rect (start -0.93 -0.47) (end 0.93 0.47)
      (stroke (width 0.05) (type solid)) (fill none) (layer "F.CrtYd"))
    (fp_rect (start -0.5 -0.25) (end 0.5 0.25)
      (stroke (width 0.15) (type solid)) (fill none) (layer "F.Fab"))
    (pad "1" smd roundrect (at -0.485 0) (size 0.59 0.64) (layers "F.Cu" "F.Paste" "F.Mask") (roundrect_rratio 0.25)
      (net 110 "Net-(IC1-FB)") (pintype "passive"))
    (pad "2" smd roundrect (at 0.485 0) (size 0.59 0.64) (layers "F.Cu" "F.Paste" "F.Mask") (roundrect_rratio 0.25)
      (net 9 "GND") (pintype "passive"))
  )

  (footprint "data-center-rdimm-ddr4-tester-footprints:Testpoint_smd_1mm" (layer "F.Cu")
    (at 135 101.125)
    (property "Author" "Antmicro")
    (property "License" "Apache-2.0")
    (property "MPN" "")
    (property "Manufacturer" "")
    (property "Sheetfile" "supply.kicad_sch")
    (property "Sheetname" "Supply")
    (property "ki_description" "Test Point 1mm")
    (attr exclude_from_pos_files)
    (fp_text reference "3V3" (at -1.06 -0.615) (layer "F.SilkS")
        (effects (font (size 0.7 0.7) (thickness 0.15)) (justify left bottom))
    )
    (fp_text value "TP_1mm_SMD" (at 0 1.4) (layer "F.Fab") hide
        (effects (font (size 0.7 0.7) (thickness 0.15)) (justify left bottom))
    )
    (fp_text user "License: Apache-2.0" (at -0.5 5.2) (layer "F.Fab") hide
        (effects (font (size 0.7 0.7) (thickness 0.15)) (justify left bottom))
    )
    (fp_text user "Author: Antmicro" (at -0.5 4) (layer "F.Fab") hide
        (effects (font (size 0.7 0.7) (thickness 0.15)) (justify left bottom))
    )
    (fp_text user "${REFERENCE}" (at -0.5 2.8) (layer "F.Fab") hide
        (effects (font (size 0.7 0.7) (thickness 0.15)) (justify left bottom))
    )
    (pad "1" smd circle (at 0 0) (size 1 1) (layers "F.Cu" "F.Mask")
      (net 304 "VCC3V3") (pinfunction "1") (pintype "passive"))
  )

  (footprint "data-center-rdimm-ddr4-tester-footprints:C_0603_1608Metric" (layer "F.Cu")
    (at 116.661328 102.497157 180)
    (descr "Capacitor SMD 0603")
    (tags "capacitor 0603")
    (property "Author" "Antmicro")
    (property "Dielectric" "")
    (property "License" "Apache-2.0")
    (property "MPN" "C1608X5R1E106M080AC")
    (property "Manufacturer" "TDK")
    (property "Sheetfile" "supply.kicad_sch")
    (property "Sheetname" "Supply")
    (property "Val" "10u/25V")
    (property "Voltage" "")
    (property "ki_description" " ")
    (attr smd)
    (fp_text reference "C29" (at 1.241328 -1.062843 270) (layer "F.SilkS")
        (effects (font (size 0.7 0.7) (thickness 0.15)) (justify left bottom))
    )
    (fp_text value "C_10u_25V_0603" (at 0 1.6 180) (layer "F.Fab") hide
        (effects (font (size 0.7 0.7) (thickness 0.15)) (justify left bottom))
    )
    (fp_text user "License: Apache-2.0" (at -1.682 5.895 180) (layer "F.Fab") hide
        (effects (font (size 0.7 0.7) (thickness 0.15)) (justify left bottom))
    )
    (fp_text user "Author: Antmicro" (at -1.682 4.894 180) (layer "F.Fab") hide
        (effects (font (size 0.7 0.7) (thickness 0.15)) (justify left bottom))
    )
    (fp_text user "${REFERENCE}" (at -1.682 3.895 180) (layer "F.Fab") hide
        (effects (font (size 0.7 0.7) (thickness 0.15)) (justify left bottom))
    )
    (fp_line (start -0.3 -0.3) (end 0.3 -0.3)
      (stroke (width 0.15) (type solid)) (layer "F.SilkS"))
    (fp_line (start -0.3 0.3) (end 0.3 0.3)
      (stroke (width 0.15) (type solid)) (layer "F.SilkS"))
    (fp_rect (start -1.24 -0.7) (end 1.24 0.7)
      (stroke (width 0.05) (type solid)) (fill none) (layer "F.CrtYd"))
    (fp_rect (start -0.8 -0.4) (end 0.8 0.4)
      (stroke (width 0.15) (type solid)) (fill none) (layer "F.Fab"))
    (pad "1" smd roundrect (at -0.7 0 180) (size 0.6 0.8) (layers "F.Cu" "F.Paste" "F.Mask") (roundrect_rratio 0.2)
      (net 103 "VIN") (pintype "passive"))
    (pad "2" smd roundrect (at 0.7 0 180) (size 0.6 0.8) (layers "F.Cu" "F.Paste" "F.Mask") (roundrect_rratio 0.2)
      (net 9 "GND") (pintype "passive"))
  )

  (footprint "data-center-rdimm-ddr4-tester-footprints:C_0402_1005Metric" (layer "F.Cu")
    (at 110.286328 114.872157)
    (descr "Capacitor SMD 0402")
    (tags "capacitor SMD 0402")
    (property "Author" "Antmicro")
    (property "Dielectric" "X7R")
    (property "License" "Apache-2.0")
    (property "MPN" "GRM155R71H103KA88D")
    (property "Manufacturer" "Murata")
    (property "Sheetfile" "supply.kicad_sch")
    (property "Sheetname" "Supply")
    (property "Val" "10n")
    (property "Voltage" "50V")
    (property "ki_description" " ")
    (attr smd)
    (fp_text reference "C174" (at -1.446328 2.467843) (layer "F.SilkS")
        (effects (font (size 0.7 0.7) (thickness 0.15)) (justify left bottom))
    )
    (fp_text value "C_10n_0402" (at 0 1.4) (layer "F.Fab") hide
        (effects (font (size 0.7 0.7) (thickness 0.15)) (justify left bottom))
    )
    (fp_text user "${REFERENCE}" (at -0.932 3.168) (layer "F.Fab") hide
        (effects (font (size 0.7 0.7) (thickness 0.15)) (justify left bottom))
    )
    (fp_text user "License: Apache-2.0" (at -0.932 5.17) (layer "F.Fab") hide
        (effects (font (size 0.7 0.7) (thickness 0.15)) (justify left bottom))
    )
    (fp_text user "Author: Antmicro" (at -0.932 4.17) (layer "F.Fab") hide
        (effects (font (size 0.7 0.7) (thickness 0.15)) (justify left bottom))
    )
    (fp_rect (start -0.94 -0.47) (end 0.94 0.47)
      (stroke (width 0.05) (type solid)) (fill none) (layer "F.CrtYd"))
    (fp_rect (start -0.499 -0.249) (end 0.499 0.249)
      (stroke (width 0.15) (type solid)) (fill none) (layer "F.Fab"))
    (pad "1" smd roundrect (at -0.484 0) (size 0.59 0.64) (layers "F.Cu" "F.Paste" "F.Mask") (roundrect_rratio 0.25)
      (net 9 "GND") (pintype "passive"))
    (pad "2" smd roundrect (at 0.484 0) (size 0.59 0.64) (layers "F.Cu" "F.Paste" "F.Mask") (roundrect_rratio 0.25)
      (net 53 "Net-(IC1-SS{slash}TR)") (pintype "passive"))
  )

  (footprint "data-center-rdimm-ddr4-tester-footprints:R_0402_1005Metric" (layer "F.Cu")
    (at 120.65 110.85 -90)
    (descr "Resistor SMD 0402")
    (tags "resistor SMD 0402")
    (property "Author" "Antmicro")
    (property "License" "Apache-2.0")
    (property "MPN" "CR0402-FX-1003GLF")
    (property "Manufacturer" "Bourns")
    (property "Sheetfile" "supply.kicad_sch")
    (property "Sheetname" "Supply")
    (property "Tolerance" "1%")
    (property "Val" "100k")
    (property "ki_description" "100k resistor in 0402 package with 1% tolerance")
    (attr smd)
    (fp_text reference "R122" (at 2.85 1.8) (layer "F.SilkS")
        (effects (font (size 0.7 0.7) (thickness 0.15)) (justify left bottom))
    )
    (fp_text value "R_100k_0402" (at 0 1.4 -90) (layer "F.Fab") hide
        (effects (font (size 0.7 0.7) (thickness 0.15)) (justify left bottom))
    )
    (fp_text user "Author: Antmicro" (at -0.95 4.169 -90) (layer "F.Fab") hide
        (effects (font (size 0.7 0.7) (thickness 0.15)) (justify left bottom))
    )
    (fp_text user "License: Apache-2.0" (at -0.95 5.169 -90) (layer "F.Fab") hide
        (effects (font (size 0.7 0.7) (thickness 0.15)) (justify left bottom))
    )
    (fp_text user "${REFERENCE}" (at -0.95 3.168 -90) (layer "F.Fab") hide
        (effects (font (size 0.7 0.7) (thickness 0.15)) (justify left bottom))
    )
    (fp_rect (start -0.93 -0.47) (end 0.93 0.47)
      (stroke (width 0.05) (type solid)) (fill none) (layer "F.CrtYd"))
    (fp_rect (start -0.5 -0.25) (end 0.5 0.25)
      (stroke (width 0.15) (type solid)) (fill none) (layer "F.Fab"))
    (pad "1" smd roundrect (at -0.485 0 270) (size 0.59 0.64) (layers "F.Cu" "F.Paste" "F.Mask") (roundrect_rratio 0.25)
      (net 104 "VCC5V0") (pintype "passive"))
    (pad "2" smd roundrect (at 0.485 0 270) (size 0.59 0.64) (layers "F.Cu" "F.Paste" "F.Mask") (roundrect_rratio 0.25)
      (net 536 "/Supply/SYS_PWR_GOOD") (pintype "passive"))
  )

  (footprint "data-center-rdimm-ddr4-tester-footprints:C_0603_1608Metric" (layer "F.Cu")
    (at 116.036328 87.610008 180)
    (descr "Capacitor SMD 0603")
    (tags "capacitor 0603")
    (property "Author" "Antmicro")
    (property "Dielectric" "")
    (property "License" "Apache-2.0")
    (property "MPN" "GRM188R60J226MEA0D")
    (property "Manufacturer" "Murata")
    (property "Sheetfile" "supply.kicad_sch")
    (property "Sheetname" "Supply")
    (property "Val" "22u")
    (property "Voltage" "")
    (property "ki_description" " ")
    (attr smd)
    (fp_text reference "C40" (at 1.656328 12.840008 180) (layer "F.SilkS")
        (effects (font (size 0.7 0.7) (thickness 0.15)) (justify left bottom))
    )
    (fp_text value "C_22u_0603" (at 0 1.6 180) (layer "F.Fab") hide
        (effects (font (size 0.7 0.7) (thickness 0.15)) (justify left bottom))
    )
    (fp_text user "${REFERENCE}" (at -1.682 3.895 180) (layer "F.Fab") hide
        (effects (font (size 0.7 0.7) (thickness 0.15)) (justify left bottom))
    )
    (fp_text user "Author: Antmicro" (at -1.682 4.894 180) (layer "F.Fab") hide
        (effects (font (size 0.7 0.7) (thickness 0.15)) (justify left bottom))
    )
    (fp_text user "License: Apache-2.0" (at -1.682 5.895 180) (layer "F.Fab") hide
        (effects (font (size 0.7 0.7) (thickness 0.15)) (justify left bottom))
    )
    (fp_line (start -0.3 -0.3) (end 0.3 -0.3)
      (stroke (width 0.15) (type solid)) (layer "F.SilkS"))
    (fp_line (start -0.3 0.3) (end 0.3 0.3)
      (stroke (width 0.15) (type solid)) (layer "F.SilkS"))
    (fp_rect (start -1.24 -0.7) (end 1.24 0.7)
      (stroke (width 0.05) (type solid)) (fill none) (layer "F.CrtYd"))
    (fp_rect (start -0.8 -0.4) (end 0.8 0.4)
      (stroke (width 0.15) (type solid)) (fill none) (layer "F.Fab"))
    (pad "1" smd roundrect (at -0.7 0 180) (size 0.6 0.8) (layers "F.Cu" "F.Paste" "F.Mask") (roundrect_rratio 0.2)
      (net 301 "VDD1V2") (pintype "passive"))
    (pad "2" smd roundrect (at 0.7 0 180) (size 0.6 0.8) (layers "F.Cu" "F.Paste" "F.Mask") (roundrect_rratio 0.2)
      (net 9 "GND") (pintype "passive"))
  )

  (footprint "data-center-rdimm-ddr4-tester-footprints:R_0402_1005Metric" (layer "F.Cu")
    (at 119.411328 115.497157)
    (descr "Resistor SMD 0402")
    (tags "resistor SMD 0402")
    (property "Author" "Antmicro")
    (property "License" "Apache-2.0")
    (property "MPN" "CR0402-FX-1692GLF")
    (property "Manufacturer" "Bourns")
    (property "Sheetfile" "supply.kicad_sch")
    (property "Sheetname" "Supply")
    (property "Tolerance" "1%")
    (property "Val" "16k9")
    (property "ki_description" "16k9 resistor in 0402 package with 1% tolerance")
    (attr smd)
    (fp_text reference "R115" (at -4.931328 3.312843) (layer "F.SilkS")
        (effects (font (size 0.7 0.7) (thickness 0.15)) (justify left bottom))
    )
    (fp_text value "R_16k9_0402" (at 0 1.4) (layer "F.Fab") hide
        (effects (font (size 0.7 0.7) (thickness 0.15)) (justify left bottom))
    )
    (fp_text user "${REFERENCE}" (at -0.95 3.168) (layer "F.Fab") hide
        (effects (font (size 0.7 0.7) (thickness 0.15)) (justify left bottom))
    )
    (fp_text user "License: Apache-2.0" (at -0.95 5.169) (layer "F.Fab") hide
        (effects (font (size 0.7 0.7) (thickness 0.15)) (justify left bottom))
    )
    (fp_text user "Author: Antmicro" (at -0.95 4.169) (layer "F.Fab") hide
        (effects (font (size 0.7 0.7) (thickness 0.15)) (justify left bottom))
    )
    (fp_rect (start -0.93 -0.47) (end 0.93 0.47)
      (stroke (width 0.05) (type solid)) (fill none) (layer "F.CrtYd"))
    (fp_rect (start -0.5 -0.25) (end 0.5 0.25)
      (stroke (width 0.15) (type solid)) (fill none) (layer "F.Fab"))
    (pad "1" smd roundrect (at -0.485 0) (size 0.59 0.64) (layers "F.Cu" "F.Paste" "F.Mask") (roundrect_rratio 0.25)
      (net 69 "Net-(IC1-COMP)") (pintype "passive"))
    (pad "2" smd roundrect (at 0.485 0) (size 0.59 0.64) (layers "F.Cu" "F.Paste" "F.Mask") (roundrect_rratio 0.25)
      (net 107 "Net-(C172-Pad1)") (pintype "passive"))
  )

  (footprint "data-center-rdimm-ddr4-tester-footprints:R_0402_1005Metric" (layer "F.Cu")
    (at 121.536328 102.747157 -90)
    (descr "Resistor SMD 0402")
    (tags "resistor SMD 0402")
    (property "Author" "Antmicro")
    (property "License" "Apache-2.0")
    (property "MPN" "CR0402-FX-1003GLF")
    (property "Manufacturer" "Bourns")
    (property "Sheetfile" "supply.kicad_sch")
    (property "Sheetname" "Supply")
    (property "Tolerance" "1%")
    (property "Val" "100k")
    (property "ki_description" "100k resistor in 0402 package with 1% tolerance")
    (attr smd)
    (fp_text reference "R40" (at 1.062843 -1.263672 -90) (layer "F.SilkS")
        (effects (font (size 0.7 0.7) (thickness 0.15)) (justify left bottom))
    )
    (fp_text value "R_100k_0402" (at 0 1.4 -90) (layer "F.Fab") hide
        (effects (font (size 0.7 0.7) (thickness 0.15)) (justify left bottom))
    )
    (fp_text user "Author: Antmicro" (at -0.95 4.169 -90) (layer "F.Fab") hide
        (effects (font (size 0.7 0.7) (thickness 0.15)) (justify left bottom))
    )
    (fp_text user "${REFERENCE}" (at -0.95 3.168 -90) (layer "F.Fab") hide
        (effects (font (size 0.7 0.7) (thickness 0.15)) (justify left bottom))
    )
    (fp_text user "License: Apache-2.0" (at -0.95 5.169 -90) (layer "F.Fab") hide
        (effects (font (size 0.7 0.7) (thickness 0.15)) (justify left bottom))
    )
    (fp_rect (start -0.93 -0.47) (end 0.93 0.47)
      (stroke (width 0.05) (type solid)) (fill none) (layer "F.CrtYd"))
    (fp_rect (start -0.5 -0.25) (end 0.5 0.25)
      (stroke (width 0.15) (type solid)) (fill none) (layer "F.Fab"))
    (pad "1" smd roundrect (at -0.485 0 270) (size 0.59 0.64) (layers "F.Cu" "F.Paste" "F.Mask") (roundrect_rratio 0.25)
      (net 613 "Net-(U2-PGOOD)") (pintype "passive"))
    (pad "2" smd roundrect (at 0.485 0 270) (size 0.59 0.64) (layers "F.Cu" "F.Paste" "F.Mask") (roundrect_rratio 0.25)
      (net 307 "5V0_SYS") (pintype "passive"))
  )

  (footprint "data-center-rdimm-ddr4-tester-footprints:R_0402_1005Metric" (layer "F.Cu")
    (at 148.036328 104.372157)
    (descr "Resistor SMD 0402")
    (tags "resistor SMD 0402")
    (property "Author" "Antmicro")
    (property "License" "Apache-2.0")
    (property "MPN" "CR0402-FX-22R0GLF")
    (property "Manufacturer" "Bourns")
    (property "Sheetfile" "interfaces.kicad_sch")
    (property "Sheetname" "Interfaces")
    (property "Tolerance" "1%")
    (property "Val" "22R")
    (property "ki_description" "22R resistor in 0402 package with 1% tolerance")
    (attr smd)
    (fp_text reference "R4" (at 0.863672 0.367843) (layer "F.SilkS")
        (effects (font (size 0.7 0.7) (thickness 0.15)) (justify left bottom))
    )
    (fp_text value "R_22R_0402" (at 0 1.4) (layer "F.Fab") hide
        (effects (font (size 0.7 0.7) (thickness 0.15)) (justify left bottom))
    )
    (fp_text user "Author: Antmicro" (at -0.95 4.169) (layer "F.Fab") hide
        (effects (font (size 0.7 0.7) (thickness 0.15)) (justify left bottom))
    )
    (fp_text user "${REFERENCE}" (at -0.95 3.168) (layer "F.Fab") hide
        (effects (font (size 0.7 0.7) (thickness 0.15)) (justify left bottom))
    )
    (fp_text user "License: Apache-2.0" (at -0.95 5.169) (layer "F.Fab") hide
        (effects (font (size 0.7 0.7) (thickness 0.15)) (justify left bottom))
    )
    (fp_rect (start -0.93 -0.47) (end 0.93 0.47)
      (stroke (width 0.05) (type solid)) (fill none) (layer "F.CrtYd"))
    (fp_rect (start -0.5 -0.25) (end 0.5 0.25)
      (stroke (width 0.15) (type solid)) (fill none) (layer "F.Fab"))
    (pad "1" smd roundrect (at -0.485 0) (size 0.59 0.64) (layers "F.Cu" "F.Paste" "F.Mask") (roundrect_rratio 0.25)
      (net 588 "Net-(U7-BDBUS3)") (pintype "passive"))
    (pad "2" smd roundrect (at 0.485 0) (size 0.59 0.64) (layers "F.Cu" "F.Paste" "F.Mask") (roundrect_rratio 0.25)
      (net 131 "AUX_JTAG_TMS") (pintype "passive"))
  )

  (footprint "data-center-rdimm-ddr4-tester-footprints:C_0603_1608Metric" (layer "F.Cu")
    (at 124.661328 99.497157 -90)
    (descr "Capacitor SMD 0603")
    (tags "capacitor 0603")
    (property "Author" "Antmicro")
    (property "Dielectric" "")
    (property "License" "Apache-2.0")
    (property "MPN" "0603YC104KAZ2A")
    (property "Manufacturer" "AVX")
    (property "Sheetfile" "supply.kicad_sch")
    (property "Sheetname" "Supply")
    (property "Val" "100n")
    (property "Voltage" "")
    (property "ki_description" " ")
    (attr smd)
    (fp_text reference "C2" (at 2.442843 -0.358672 -90) (layer "F.SilkS")
        (effects (font (size 0.7 0.7) (thickness 0.15)) (justify left bottom))
    )
    (fp_text value "C_100n_0603" (at 0 1.6 -90) (layer "F.Fab") hide
        (effects (font (size 0.7 0.7) (thickness 0.15)) (justify left bottom))
    )
    (fp_text user "${REFERENCE}" (at -1.682 3.895 -90) (layer "F.Fab") hide
        (effects (font (size 0.7 0.7) (thickness 0.15)) (justify left bottom))
    )
    (fp_text user "Author: Antmicro" (at -1.682 4.894 -90) (layer "F.Fab") hide
        (effects (font (size 0.7 0.7) (thickness 0.15)) (justify left bottom))
    )
    (fp_text user "License: Apache-2.0" (at -1.682 5.895 -90) (layer "F.Fab") hide
        (effects (font (size 0.7 0.7) (thickness 0.15)) (justify left bottom))
    )
    (fp_line (start -0.3 -0.3) (end 0.3 -0.3)
      (stroke (width 0.15) (type solid)) (layer "F.SilkS"))
    (fp_line (start -0.3 0.3) (end 0.3 0.3)
      (stroke (width 0.15) (type solid)) (layer "F.SilkS"))
    (fp_rect (start -1.24 -0.7) (end 1.24 0.7)
      (stroke (width 0.05) (type solid)) (fill none) (layer "F.CrtYd"))
    (fp_rect (start -0.8 -0.4) (end 0.8 0.4)
      (stroke (width 0.15) (type solid)) (fill none) (layer "F.Fab"))
    (pad "1" smd roundrect (at -0.7 0 270) (size 0.6 0.8) (layers "F.Cu" "F.Paste" "F.Mask") (roundrect_rratio 0.2)
      (net 307 "5V0_SYS") (pintype "passive"))
    (pad "2" smd roundrect (at 0.7 0 270) (size 0.6 0.8) (layers "F.Cu" "F.Paste" "F.Mask") (roundrect_rratio 0.2)
      (net 9 "GND") (pintype "passive"))
  )

  (footprint "data-center-rdimm-ddr4-tester-footprints:C_0603_1608Metric" (layer "F.Cu")
    (at 126.286328 99.497157 -90)
    (descr "Capacitor SMD 0603")
    (tags "capacitor 0603")
    (property "Author" "Antmicro")
    (property "Dielectric" "")
    (property "License" "Apache-2.0")
    (property "MPN" "0603YD105KAT2A")
    (property "Manufacturer" "Walsin")
    (property "Sheetfile" "supply.kicad_sch")
    (property "Sheetname" "Supply")
    (property "Val" "1u")
    (property "Voltage" "")
    (property "ki_description" " ")
    (attr smd)
    (fp_text reference "C4" (at 2.542843 -0.333672 -90) (layer "F.SilkS")
        (effects (font (size 0.7 0.7) (thickness 0.15)) (justify left bottom))
    )
    (fp_text value "C_1u_0603" (at 0 1.6 -90) (layer "F.Fab") hide
        (effects (font (size 0.7 0.7) (thickness 0.15)) (justify left bottom))
    )
    (fp_text user "Author: Antmicro" (at -1.682 4.894 -90) (layer "F.Fab") hide
        (effects (font (size 0.7 0.7) (thickness 0.15)) (justify left bottom))
    )
    (fp_text user "${REFERENCE}" (at -1.682 3.895 -90) (layer "F.Fab") hide
        (effects (font (size 0.7 0.7) (thickness 0.15)) (justify left bottom))
    )
    (fp_text user "License: Apache-2.0" (at -1.682 5.895 -90) (layer "F.Fab") hide
        (effects (font (size 0.7 0.7) (thickness 0.15)) (justify left bottom))
    )
    (fp_line (start -0.3 -0.3) (end 0.3 -0.3)
      (stroke (width 0.15) (type solid)) (layer "F.SilkS"))
    (fp_line (start -0.3 0.3) (end 0.3 0.3)
      (stroke (width 0.15) (type solid)) (layer "F.SilkS"))
    (fp_rect (start -1.24 -0.7) (end 1.24 0.7)
      (stroke (width 0.05) (type solid)) (fill none) (layer "F.CrtYd"))
    (fp_rect (start -0.8 -0.4) (end 0.8 0.4)
      (stroke (width 0.15) (type solid)) (fill none) (layer "F.Fab"))
    (pad "1" smd roundrect (at -0.7 0 270) (size 0.6 0.8) (layers "F.Cu" "F.Paste" "F.Mask") (roundrect_rratio 0.2)
      (net 307 "5V0_SYS") (pintype "passive"))
    (pad "2" smd roundrect (at 0.7 0 270) (size 0.6 0.8) (layers "F.Cu" "F.Paste" "F.Mask") (roundrect_rratio 0.2)
      (net 9 "GND") (pintype "passive"))
  )

  (footprint "data-center-rdimm-ddr4-tester-footprints:C_0603_1608Metric" (layer "F.Cu")
    (at 128.411328 88.122157 90)
    (descr "Capacitor SMD 0603")
    (tags "capacitor 0603")
    (property "Author" "Antmicro")
    (property "Dielectric" "")
    (property "License" "Apache-2.0")
    (property "MPN" "GRM188R60J226MEA0D")
    (property "Manufacturer" "Murata")
    (property "Sheetfile" "supply.kicad_sch")
    (property "Sheetname" "Supply")
    (property "Val" "22u")
    (property "Voltage" "")
    (property "ki_description" " ")
    (attr smd)
    (fp_text reference "C31" (at 0.942157 0.288672 90) (layer "F.SilkS")
        (effects (font (size 0.7 0.7) (thickness 0.15)) (justify left bottom))
    )
    (fp_text value "C_22u_0603" (at 0 1.6 90) (layer "F.Fab") hide
        (effects (font (size 0.7 0.7) (thickness 0.15)) (justify left bottom))
    )
    (fp_text user "${REFERENCE}" (at -1.682 3.895 90) (layer "F.Fab") hide
        (effects (font (size 0.7 0.7) (thickness 0.15)) (justify left bottom))
    )
    (fp_text user "Author: Antmicro" (at -1.682 4.894 90) (layer "F.Fab") hide
        (effects (font (size 0.7 0.7) (thickness 0.15)) (justify left bottom))
    )
    (fp_text user "License: Apache-2.0" (at -1.682 5.895 90) (layer "F.Fab") hide
        (effects (font (size 0.7 0.7) (thickness 0.15)) (justify left bottom))
    )
    (fp_line (start -0.3 -0.3) (end 0.3 -0.3)
      (stroke (width 0.15) (type solid)) (layer "F.SilkS"))
    (fp_line (start -0.3 0.3) (end 0.3 0.3)
      (stroke (width 0.15) (type solid)) (layer "F.SilkS"))
    (fp_rect (start -1.24 -0.7) (end 1.24 0.7)
      (stroke (width 0.05) (type solid)) (fill none) (layer "F.CrtYd"))
    (fp_rect (start -0.8 -0.4) (end 0.8 0.4)
      (stroke (width 0.15) (type solid)) (fill none) (layer "F.Fab"))
    (pad "1" smd roundrect (at -0.7 0 90) (size 0.6 0.8) (layers "F.Cu" "F.Paste" "F.Mask") (roundrect_rratio 0.2)
      (net 303 "VCC2V5") (pintype "passive"))
    (pad "2" smd roundrect (at 0.7 0 90) (size 0.6 0.8) (layers "F.Cu" "F.Paste" "F.Mask") (roundrect_rratio 0.2)
      (net 9 "GND") (pintype "passive"))
  )

  (footprint "data-center-rdimm-ddr4-tester-footprints:R_0402_1005Metric" (layer "F.Cu")
    (at 148.056328 109.832157)
    (descr "Resistor SMD 0402")
    (tags "resistor SMD 0402")
    (property "Author" "Antmicro")
    (property "License" "Apache-2.0")
    (property "MPN" "CR0402-FX-22R0GLF")
    (property "Manufacturer" "Bourns")
    (property "Sheetfile" "interfaces.kicad_sch")
    (property "Sheetname" "Interfaces")
    (property "Tolerance" "1%")
    (property "Val" "22R")
    (property "ki_description" "22R resistor in 0402 package with 1% tolerance")
    (attr smd)
    (fp_text reference "R25" (at 0.863672 0.367843) (layer "F.SilkS")
        (effects (font (size 0.7 0.7) (thickness 0.15)) (justify left bottom))
    )
    (fp_text value "R_22R_0402" (at 0 1.4) (layer "F.Fab") hide
        (effects (font (size 0.7 0.7) (thickness 0.15)) (justify left bottom))
    )
    (fp_text user "${REFERENCE}" (at -0.95 3.168) (layer "F.Fab") hide
        (effects (font (size 0.7 0.7) (thickness 0.15)) (justify left bottom))
    )
    (fp_text user "Author: Antmicro" (at -0.95 4.169) (layer "F.Fab") hide
        (effects (font (size 0.7 0.7) (thickness 0.15)) (justify left bottom))
    )
    (fp_text user "License: Apache-2.0" (at -0.95 5.169) (layer "F.Fab") hide
        (effects (font (size 0.7 0.7) (thickness 0.15)) (justify left bottom))
    )
    (fp_rect (start -0.93 -0.47) (end 0.93 0.47)
      (stroke (width 0.05) (type solid)) (fill none) (layer "F.CrtYd"))
    (fp_rect (start -0.5 -0.25) (end 0.5 0.25)
      (stroke (width 0.15) (type solid)) (fill none) (layer "F.Fab"))
    (pad "1" smd roundrect (at -0.485 0) (size 0.59 0.64) (layers "F.Cu" "F.Paste" "F.Mask") (roundrect_rratio 0.25)
      (net 598 "Net-(U7-ADBUS3)") (pintype "passive"))
    (pad "2" smd roundrect (at 0.485 0) (size 0.59 0.64) (layers "F.Cu" "F.Paste" "F.Mask") (roundrect_rratio 0.25)
      (net 13 "TMS_JTAG") (pintype "passive"))
  )

  (footprint "data-center-rdimm-ddr4-tester-footprints:R_0402_1005Metric" (layer "F.Cu")
    (at 148.056328 110.907157)
    (descr "Resistor SMD 0402")
    (tags "resistor SMD 0402")
    (property "Author" "Antmicro")
    (property "License" "Apache-2.0")
    (property "MPN" "CR0402-FX-22R0GLF")
    (property "Manufacturer" "Bourns")
    (property "Sheetfile" "interfaces.kicad_sch")
    (property "Sheetname" "Interfaces")
    (property "Tolerance" "1%")
    (property "Val" "22R")
    (property "ki_description" "22R resistor in 0402 package with 1% tolerance")
    (attr smd)
    (fp_text reference "R20" (at 0.863672 0.367843) (layer "F.SilkS")
        (effects (font (size 0.7 0.7) (thickness 0.15)) (justify left bottom))
    )
    (fp_text value "R_22R_0402" (at 0 1.4) (layer "F.Fab") hide
        (effects (font (size 0.7 0.7) (thickness 0.15)) (justify left bottom))
    )
    (fp_text user "Author: Antmicro" (at -0.95 4.169) (layer "F.Fab") hide
        (effects (font (size 0.7 0.7) (thickness 0.15)) (justify left bottom))
    )
    (fp_text user "${REFERENCE}" (at -0.95 3.168) (layer "F.Fab") hide
        (effects (font (size 0.7 0.7) (thickness 0.15)) (justify left bottom))
    )
    (fp_text user "License: Apache-2.0" (at -0.95 5.169) (layer "F.Fab") hide
        (effects (font (size 0.7 0.7) (thickness 0.15)) (justify left bottom))
    )
    (fp_rect (start -0.93 -0.47) (end 0.93 0.47)
      (stroke (width 0.05) (type solid)) (fill none) (layer "F.CrtYd"))
    (fp_rect (start -0.5 -0.25) (end 0.5 0.25)
      (stroke (width 0.15) (type solid)) (fill none) (layer "F.Fab"))
    (pad "1" smd roundrect (at -0.485 0) (size 0.59 0.64) (layers "F.Cu" "F.Paste" "F.Mask") (roundrect_rratio 0.25)
      (net 595 "Net-(U7-ADBUS2)") (pintype "passive"))
    (pad "2" smd roundrect (at 0.485 0) (size 0.59 0.64) (layers "F.Cu" "F.Paste" "F.Mask") (roundrect_rratio 0.25)
      (net 15 "TDO_JTAG") (pintype "passive"))
  )

  (footprint "data-center-rdimm-ddr4-tester-footprints:R_0402_1005Metric" (layer "F.Cu")
    (at 148.056328 111.982157)
    (descr "Resistor SMD 0402")
    (tags "resistor SMD 0402")
    (property "Author" "Antmicro")
    (property "License" "Apache-2.0")
    (property "MPN" "CR0402-FX-22R0GLF")
    (property "Manufacturer" "Bourns")
    (property "Sheetfile" "interfaces.kicad_sch")
    (property "Sheetname" "Interfaces")
    (property "Tolerance" "1%")
    (property "Val" "22R")
    (property "ki_description" "22R resistor in 0402 package with 1% tolerance")
    (attr smd)
    (fp_text reference "R19" (at 0.863672 0.277843) (layer "F.SilkS")
        (effects (font (size 0.7 0.7) (thickness 0.15)) (justify left bottom))
    )
    (fp_text value "R_22R_0402" (at 0 1.4) (layer "F.Fab") hide
        (effects (font (size 0.7 0.7) (thickness 0.15)) (justify left bottom))
    )
    (fp_text user "Author: Antmicro" (at -0.95 4.169) (layer "F.Fab") hide
        (effects (font (size 0.7 0.7) (thickness 0.15)) (justify left bottom))
    )
    (fp_text user "License: Apache-2.0" (at -0.95 5.169) (layer "F.Fab") hide
        (effects (font (size 0.7 0.7) (thickness 0.15)) (justify left bottom))
    )
    (fp_text user "${REFERENCE}" (at -0.95 3.168) (layer "F.Fab") hide
        (effects (font (size 0.7 0.7) (thickness 0.15)) (justify left bottom))
    )
    (fp_rect (start -0.93 -0.47) (end 0.93 0.47)
      (stroke (width 0.05) (type solid)) (fill none) (layer "F.CrtYd"))
    (fp_rect (start -0.5 -0.25) (end 0.5 0.25)
      (stroke (width 0.15) (type solid)) (fill none) (layer "F.Fab"))
    (pad "1" smd roundrect (at -0.485 0) (size 0.59 0.64) (layers "F.Cu" "F.Paste" "F.Mask") (roundrect_rratio 0.25)
      (net 594 "Net-(U7-ADBUS1)") (pintype "passive"))
    (pad "2" smd roundrect (at 0.485 0) (size 0.59 0.64) (layers "F.Cu" "F.Paste" "F.Mask") (roundrect_rratio 0.25)
      (net 14 "TDI_JTAG") (pintype "passive"))
  )

  (footprint "data-center-rdimm-ddr4-tester-footprints:R_0402_1005Metric" (layer "F.Cu")
    (at 148.036328 113.122157)
    (descr "Resistor SMD 0402")
    (tags "resistor SMD 0402")
    (property "Author" "Antmicro")
    (property "License" "Apache-2.0")
    (property "MPN" "CR0402-FX-22R0GLF")
    (property "Manufacturer" "Bourns")
    (property "Sheetfile" "interfaces.kicad_sch")
    (property "Sheetname" "Interfaces")
    (property "Tolerance" "1%")
    (property "Val" "22R")
    (property "ki_description" "22R resistor in 0402 package with 1% tolerance")
    (attr smd)
    (fp_text reference "R18" (at 0.863672 0.137843) (layer "F.SilkS")
        (effects (font (size 0.7 0.7) (thickness 0.15)) (justify left bottom))
    )
    (fp_text value "R_22R_0402" (at 0 1.4) (layer "F.Fab") hide
        (effects (font (size 0.7 0.7) (thickness 0.15)) (justify left bottom))
    )
    (fp_text user "${REFERENCE}" (at -0.95 3.168) (layer "F.Fab") hide
        (effects (font (size 0.7 0.7) (thickness 0.15)) (justify left bottom))
    )
    (fp_text user "License: Apache-2.0" (at -0.95 5.169) (layer "F.Fab") hide
        (effects (font (size 0.7 0.7) (thickness 0.15)) (justify left bottom))
    )
    (fp_text user "Author: Antmicro" (at -0.95 4.169) (layer "F.Fab") hide
        (effects (font (size 0.7 0.7) (thickness 0.15)) (justify left bottom))
    )
    (fp_rect (start -0.93 -0.47) (end 0.93 0.47)
      (stroke (width 0.05) (type solid)) (fill none) (layer "F.CrtYd"))
    (fp_rect (start -0.5 -0.25) (end 0.5 0.25)
      (stroke (width 0.15) (type solid)) (fill none) (layer "F.Fab"))
    (pad "1" smd roundrect (at -0.485 0) (size 0.59 0.64) (layers "F.Cu" "F.Paste" "F.Mask") (roundrect_rratio 0.25)
      (net 593 "Net-(U7-ADBUS0)") (pintype "passive"))
    (pad "2" smd roundrect (at 0.485 0) (size 0.59 0.64) (layers "F.Cu" "F.Paste" "F.Mask") (roundrect_rratio 0.25)
      (net 12 "TCK_JTAG") (pintype "passive"))
  )

  (footprint "data-center-rdimm-ddr4-tester-footprints:C_0402_1005Metric" (layer "F.Cu")
    (at 133.946328 107.407157 180)
    (descr "Capacitor SMD 0402")
    (tags "capacitor SMD 0402")
    (property "Author" "Antmicro")
    (property "Dielectric" "X5R")
    (property "License" "Apache-2.0")
    (property "MPN" "GRM155R61H104KE14D")
    (property "Manufacturer" "Murata")
    (property "Sheetfile" "interfaces.kicad_sch")
    (property "Sheetname" "Interfaces")
    (property "Val" "100n")
    (property "Voltage" "50V")
    (property "ki_description" " ")
    (attr smd)
    (fp_text reference "C186" (at 3.766328 -0.322843 180) (layer "F.SilkS")
        (effects (font (size 0.7 0.7) (thickness 0.15)) (justify left bottom))
    )
    (fp_text value "C_100n_0402" (at 0 1.4 180) (layer "F.Fab") hide
        (effects (font (size 0.7 0.7) (thickness 0.15)) (justify left bottom))
    )
    (fp_text user "${REFERENCE}" (at -0.932 3.168 180) (layer "F.Fab") hide
        (effects (font (size 0.7 0.7) (thickness 0.15)) (justify left bottom))
    )
    (fp_text user "License: Apache-2.0" (at -0.932 5.17 180) (layer "F.Fab") hide
        (effects (font (size 0.7 0.7) (thickness 0.15)) (justify left bottom))
    )
    (fp_text user "Author: Antmicro" (at -0.932 4.17 180) (layer "F.Fab") hide
        (effects (font (size 0.7 0.7) (thickness 0.15)) (justify left bottom))
    )
    (fp_rect (start -0.94 -0.47) (end 0.94 0.47)
      (stroke (width 0.05) (type solid)) (fill none) (layer "F.CrtYd"))
    (fp_rect (start -0.499 -0.249) (end 0.499 0.249)
      (stroke (width 0.15) (type solid)) (fill none) (layer "F.Fab"))
    (pad "1" smd roundrect (at -0.484 0 180) (size 0.59 0.64) (layers "F.Cu" "F.Paste" "F.Mask") (roundrect_rratio 0.25)
      (net 143 "3V3_SYS") (pintype "passive"))
    (pad "2" smd roundrect (at 0.484 0 180) (size 0.59 0.64) (layers "F.Cu" "F.Paste" "F.Mask") (roundrect_rratio 0.25)
      (net 9 "GND") (pintype "passive"))
  )

  (footprint "data-center-rdimm-ddr4-tester-footprints:C_0402_1005Metric" (layer "F.Cu")
    (at 133 116 -90)
    (descr "Capacitor SMD 0402")
    (tags "capacitor SMD 0402")
    (property "Author" "Antmicro")
    (property "Dielectric" "")
    (property "License" "Apache-2.0")
    (property "MPN" "MC0402N180J500CT")
    (property "Manufacturer" "Multicomp")
    (property "Sheetfile" "interfaces.kicad_sch")
    (property "Sheetname" "Interfaces")
    (property "Val" "18p")
    (property "Voltage" "")
    (property "ki_description" " ")
    (attr smd)
    (fp_text reference "C190" (at -0.717157 -0.388672 -90) (layer "F.SilkS")
        (effects (font (size 0.7 0.7) (thickness 0.15)) (justify left bottom))
    )
    (fp_text value "C_18p_0402" (at 0 1.4 -90) (layer "F.Fab") hide
        (effects (font (size 0.7 0.7) (thickness 0.15)) (justify left bottom))
    )
    (fp_text user "${REFERENCE}" (at -0.932 3.168 -90) (layer "F.Fab") hide
        (effects (font (size 0.7 0.7) (thickness 0.15)) (justify left bottom))
    )
    (fp_text user "License: Apache-2.0" (at -0.932 5.17 -90) (layer "F.Fab") hide
        (effects (font (size 0.7 0.7) (thickness 0.15)) (justify left bottom))
    )
    (fp_text user "Author: Antmicro" (at -0.932 4.17 -90) (layer "F.Fab") hide
        (effects (font (size 0.7 0.7) (thickness 0.15)) (justify left bottom))
    )
    (fp_rect (start -0.94 -0.47) (end 0.94 0.47)
      (stroke (width 0.05) (type solid)) (fill none) (layer "F.CrtYd"))
    (fp_rect (start -0.499 -0.249) (end 0.499 0.249)
      (stroke (width 0.15) (type solid)) (fill none) (layer "F.Fab"))
    (pad "1" smd roundrect (at -0.484 0 270) (size 0.59 0.64) (layers "F.Cu" "F.Paste" "F.Mask") (roundrect_rratio 0.25)
      (net 80 "Net-(U7-OSCI)") (pintype "passive"))
    (pad "2" smd roundrect (at 0.484 0 270) (size 0.59 0.64) (layers "F.Cu" "F.Paste" "F.Mask") (roundrect_rratio 0.25)
      (net 9 "GND") (pintype "passive"))
  )

  (footprint "data-center-rdimm-ddr4-tester-footprints:C_0402_1005Metric" (layer "F.Cu")
    (at 148.035 108.8)
    (descr "Capacitor SMD 0402")
    (tags "capacitor SMD 0402")
    (property "Author" "Antmicro")
    (property "Dielectric" "X5R")
    (property "License" "Apache-2.0")
    (property "MPN" "GRM155R61H104KE14D")
    (property "Manufacturer" "Murata")
    (property "Sheetfile" "interfaces.kicad_sch")
    (property "Sheetname" "Interfaces")
    (property "Val" "100n")
    (property "Voltage" "50V")
    (property "ki_description" " ")
    (attr smd)
    (fp_text reference "C191" (at 0.864672 0.367843) (layer "F.SilkS")
        (effects (font (size 0.7 0.7) (thickness 0.15)) (justify left bottom))
    )
    (fp_text value "C_100n_0402" (at 0 1.4) (layer "F.Fab") hide
        (effects (font (size 0.7 0.7) (thickness 0.15)) (justify left bottom))
    )
    (fp_text user "License: Apache-2.0" (at -0.932 5.17) (layer "F.Fab") hide
        (effects (font (size 0.7 0.7) (thickness 0.15)) (justify left bottom))
    )
    (fp_text user "Author: Antmicro" (at -0.932 4.17) (layer "F.Fab") hide
        (effects (font (size 0.7 0.7) (thickness 0.15)) (justify left bottom))
    )
    (fp_text user "${REFERENCE}" (at -0.932 3.168) (layer "F.Fab") hide
        (effects (font (size 0.7 0.7) (thickness 0.15)) (justify left bottom))
    )
    (fp_rect (start -0.94 -0.47) (end 0.94 0.47)
      (stroke (width 0.05) (type solid)) (fill none) (layer "F.CrtYd"))
    (fp_rect (start -0.499 -0.249) (end 0.499 0.249)
      (stroke (width 0.15) (type solid)) (fill none) (layer "F.Fab"))
    (pad "1" smd roundrect (at -0.484 0) (size 0.59 0.64) (layers "F.Cu" "F.Paste" "F.Mask") (roundrect_rratio 0.25)
      (net 143 "3V3_SYS") (pintype "passive"))
    (pad "2" smd roundrect (at 0.484 0) (size 0.59 0.64) (layers "F.Cu" "F.Paste" "F.Mask") (roundrect_rratio 0.25)
      (net 9 "GND") (pintype "passive"))
  )

  (footprint "data-center-rdimm-ddr4-tester-footprints:C_0402_1005Metric" (layer "F.Cu")
    (at 143.661328 100.212157 90)
    (descr "Capacitor SMD 0402")
    (tags "capacitor SMD 0402")
    (property "Author" "Antmicro")
    (property "Dielectric" "")
    (property "License" "Apache-2.0")
    (property "MPN" "GRM155R61A475MEAAD")
    (property "Manufacturer" "Murata")
    (property "Sheetfile" "interfaces.kicad_sch")
    (property "Sheetname" "Interfaces")
    (property "Val" "4u7")
    (property "Voltage" "")
    (property "ki_description" " ")
    (attr smd)
    (fp_text reference "C195" (at -1.117843 2.308672 90) (layer "F.SilkS")
        (effects (font (size 0.7 0.7) (thickness 0.15)) (justify left bottom))
    )
    (fp_text value "C_4u7_0402" (at 0 1.4 90) (layer "F.Fab") hide
        (effects (font (size 0.7 0.7) (thickness 0.15)) (justify left bottom))
    )
    (fp_text user "${REFERENCE}" (at -0.932 3.168 90) (layer "F.Fab") hide
        (effects (font (size 0.7 0.7) (thickness 0.15)) (justify left bottom))
    )
    (fp_text user "Author: Antmicro" (at -0.932 4.17 90) (layer "F.Fab") hide
        (effects (font (size 0.7 0.7) (thickness 0.15)) (justify left bottom))
    )
    (fp_text user "License: Apache-2.0" (at -0.932 5.17 90) (layer "F.Fab") hide
        (effects (font (size 0.7 0.7) (thickness 0.15)) (justify left bottom))
    )
    (fp_rect (start -0.94 -0.47) (end 0.94 0.47)
      (stroke (width 0.05) (type solid)) (fill none) (layer "F.CrtYd"))
    (fp_rect (start -0.499 -0.249) (end 0.499 0.249)
      (stroke (width 0.15) (type solid)) (fill none) (layer "F.Fab"))
    (pad "1" smd roundrect (at -0.484 0 90) (size 0.59 0.64) (layers "F.Cu" "F.Paste" "F.Mask") (roundrect_rratio 0.25)
      (net 145 "1V8_FT") (pintype "passive"))
    (pad "2" smd roundrect (at 0.484 0 90) (size 0.59 0.64) (layers "F.Cu" "F.Paste" "F.Mask") (roundrect_rratio 0.25)
      (net 9 "GND") (pintype "passive"))
  )

  (footprint "data-center-rdimm-ddr4-tester-footprints:FB_0603_1608Metric" (layer "F.Cu")
    (at 138.786328 117.497157 90)
    (property "Author" "Antmicro")
    (property "License" "Apache-2.0")
    (property "MPN" "BLM18AG601SN1D")
    (property "Manufacturer" "Murata")
    (property "Sheetfile" "interfaces.kicad_sch")
    (property "Sheetname" "Interfaces")
    (property "ki_description" "Ferrite Beads WE-TMSB Suppression 240Ohm 200mA ")
    (property "ki_keywords" " Multilayer Suppression Beads ")
    (attr smd)
    (fp_text reference "FB5" (at -2.302843 2.533672 90) (layer "F.SilkS")
        (effects (font (size 0.7 0.7) (thickness 0.15)) (justify left bottom))
    )
    (fp_text value "FB_600Z_0.5A_0603" (at 0 1.7 90) (layer "F.Fab") hide
        (effects (font (size 0.7 0.7) (thickness 0.15)) (justify left bottom))
    )
    (fp_text user "${REFERENCE}" (at -1.653 4.6 90) (layer "F.Fab") hide
        (effects (font (size 0.7 0.7) (thickness 0.15)) (justify left bottom))
    )
    (fp_text user "License: Apache-2.0" (at -1.653 5.9 90) (layer "F.Fab") hide
        (effects (font (size 0.7 0.7) (thickness 0.15)) (justify left bottom))
    )
    (fp_text user "Author: Antmicro" (at -1.653 3.162 90) (layer "F.Fab") hide
        (effects (font (size 0.7 0.7) (thickness 0.15)) (justify left bottom))
    )
    (fp_line (start -0.196 -0.408) (end 0.193 -0.408)
      (stroke (width 0.15) (type solid)) (layer "F.SilkS"))
    (fp_line (start -0.196 0.406) (end 0.193 0.406)
      (stroke (width 0.15) (type solid)) (layer "F.SilkS"))
    (fp_rect (start -1.42 -0.69) (end 1.42 0.69)
      (stroke (width 0.05) (type solid)) (fill none) (layer "F.CrtYd"))
    (fp_line (start -0.803 0.406) (end -0.803 -0.408)
      (stroke (width 0.15) (type solid)) (layer "F.Fab"))
    (fp_line (start 0.8 -0.408) (end -0.803 -0.408)
      (stroke (width 0.15) (type solid)) (layer "F.Fab"))
    (fp_line (start 0.8 -0.408) (end 0.8 0.406)
      (stroke (width 0.15) (type solid)) (layer "F.Fab"))
    (fp_line (start 0.8 0.406) (end -0.803 0.406)
      (stroke (width 0.15) (type solid)) (layer "F.Fab"))
    (pad "1" smd roundrect (at -0.891 0 90) (size 0.762 1.09) (layers "F.Cu" "F.Paste" "F.Mask") (roundrect_rratio 0.15)
      (net 143 "3V3_SYS") (pintype "passive"))
    (pad "2" smd roundrect (at 0.888 0 90) (size 0.762 1.09) (layers "F.Cu" "F.Paste" "F.Mask") (roundrect_rratio 0.15)
      (net 76 "Net-(U7-V_{PHY})") (pintype "passive"))
  )

  (footprint "data-center-rdimm-ddr4-tester-footprints:R_0402_1005Metric" (layer "F.Cu")
    (at 139.776328 114.627157 90)
    (descr "Resistor SMD 0402")
    (tags "resistor SMD 0402")
    (property "Author" "Antmicro")
    (property "License" "Apache-2.0")
    (property "MPN" "CR0402-FX-1202GLF")
    (property "Manufacturer" "Bourns")
    (property "Sheetfile" "interfaces.kicad_sch")
    (property "Sheetname" "Interfaces")
    (property "Tolerance" "1%")
    (property "Val" "12k")
    (property "ki_description" "12k resistor in 0402 package with 1% tolerance")
    (attr smd)
    (fp_text reference "R129" (at -1.102843 1.223672 90) (layer "F.SilkS")
        (effects (font (size 0.7 0.7) (thickness 0.15)) (justify left bottom))
    )
    (fp_text value "R_12k_0402" (at 0 1.4 90) (layer "F.Fab") hide
        (effects (font (size 0.7 0.7) (thickness 0.15)) (justify left bottom))
    )
    (fp_text user "License: Apache-2.0" (at -0.95 5.169 90) (layer "F.Fab") hide
        (effects (font (size 0.7 0.7) (thickness 0.15)) (justify left bottom))
    )
    (fp_text user "${REFERENCE}" (at -0.95 3.168 90) (layer "F.Fab") hide
        (effects (font (size 0.7 0.7) (thickness 0.15)) (justify left bottom))
    )
    (fp_text user "Author: Antmicro" (at -0.95 4.169 90) (layer "F.Fab") hide
        (effects (font (size 0.7 0.7) (thickness 0.15)) (justify left bottom))
    )
    (fp_rect (start -0.93 -0.47) (end 0.93 0.47)
      (stroke (width 0.05) (type solid)) (fill none) (layer "F.CrtYd"))
    (fp_rect (start -0.5 -0.25) (end 0.5 0.25)
      (stroke (width 0.15) (type solid)) (fill none) (layer "F.Fab"))
    (pad "1" smd roundrect (at -0.485 0 90) (size 0.59 0.64) (layers "F.Cu" "F.Paste" "F.Mask") (roundrect_rratio 0.25)
      (net 9 "GND") (pintype "passive"))
    (pad "2" smd roundrect (at 0.485 0 90) (size 0.59 0.64) (layers "F.Cu" "F.Paste" "F.Mask") (roundrect_rratio 0.25)
      (net 654 "Net-(U7-REF)") (pintype "passive"))
  )

  (footprint "data-center-rdimm-ddr4-tester-footprints:C_0402_1005Metric" (layer "F.Cu")
    (at 142.066328 115.237157)
    (descr "Capacitor SMD 0402")
    (tags "capacitor SMD 0402")
    (property "Author" "Antmicro")
    (property "Dielectric" "X5R")
    (property "License" "Apache-2.0")
    (property "MPN" "GRM155R61H104KE14D")
    (property "Manufacturer" "Murata")
    (property "Sheetfile" "interfaces.kicad_sch")
    (property "Sheetname" "Interfaces")
    (property "Val" "100n")
    (property "Voltage" "50V")
    (property "ki_description" " ")
    (attr smd)
    (fp_text reference "C184" (at -0.536328 3.922843) (layer "F.SilkS")
        (effects (font (size 0.7 0.7) (thickness 0.15)) (justify left bottom))
    )
    (fp_text value "C_100n_0402" (at 0 1.4) (layer "F.Fab") hide
        (effects (font (size 0.7 0.7) (thickness 0.15)) (justify left bottom))
    )
    (fp_text user "License: Apache-2.0" (at -0.932 5.17) (layer "F.Fab") hide
        (effects (font (size 0.7 0.7) (thickness 0.15)) (justify left bottom))
    )
    (fp_text user "Author: Antmicro" (at -0.932 4.17) (layer "F.Fab") hide
        (effects (font (size 0.7 0.7) (thickness 0.15)) (justify left bottom))
    )
    (fp_text user "${REFERENCE}" (at -0.932 3.168) (layer "F.Fab") hide
        (effects (font (size 0.7 0.7) (thickness 0.15)) (justify left bottom))
    )
    (fp_rect (start -0.94 -0.47) (end 0.94 0.47)
      (stroke (width 0.05) (type solid)) (fill none) (layer "F.CrtYd"))
    (fp_rect (start -0.499 -0.249) (end 0.499 0.249)
      (stroke (width 0.15) (type solid)) (fill none) (layer "F.Fab"))
    (pad "1" smd roundrect (at -0.484 0) (size 0.59 0.64) (layers "F.Cu" "F.Paste" "F.Mask") (roundrect_rratio 0.25)
      (net 75 "Net-(U7-V_{PLL})") (pintype "passive"))
    (pad "2" smd roundrect (at 0.484 0) (size 0.59 0.64) (layers "F.Cu" "F.Paste" "F.Mask") (roundrect_rratio 0.25)
      (net 9 "GND") (pintype "passive"))
  )

  (footprint "data-center-rdimm-ddr4-tester-footprints:C_0402_1005Metric" (layer "F.Cu")
    (at 142.066328 114.157157)
    (descr "Capacitor SMD 0402")
    (tags "capacitor SMD 0402")
    (property "Author" "Antmicro")
    (property "Dielectric" "")
    (property "License" "Apache-2.0")
    (property "MPN" "GRM155R61A475MEAAD")
    (property "Manufacturer" "Murata")
    (property "Sheetfile" "interfaces.kicad_sch")
    (property "Sheetname" "Interfaces")
    (property "Val" "4u7")
    (property "Voltage" "")
    (property "ki_description" " ")
    (attr smd)
    (fp_text reference "C187" (at -0.536328 3.922843) (layer "F.SilkS")
        (effects (font (size 0.7 0.7) (thickness 0.15)) (justify left bottom))
    )
    (fp_text value "C_4u7_0402" (at 0 1.4) (layer "F.Fab") hide
        (effects (font (size 0.7 0.7) (thickness 0.15)) (justify left bottom))
    )
    (fp_text user "License: Apache-2.0" (at -0.932 5.17) (layer "F.Fab") hide
        (effects (font (size 0.7 0.7) (thickness 0.15)) (justify left bottom))
    )
    (fp_text user "Author: Antmicro" (at -0.932 4.17) (layer "F.Fab") hide
        (effects (font (size 0.7 0.7) (thickness 0.15)) (justify left bottom))
    )
    (fp_text user "${REFERENCE}" (at -0.932 3.168) (layer "F.Fab") hide
        (effects (font (size 0.7 0.7) (thickness 0.15)) (justify left bottom))
    )
    (fp_rect (start -0.94 -0.47) (end 0.94 0.47)
      (stroke (width 0.05) (type solid)) (fill none) (layer "F.CrtYd"))
    (fp_rect (start -0.499 -0.249) (end 0.499 0.249)
      (stroke (width 0.15) (type solid)) (fill none) (layer "F.Fab"))
    (pad "1" smd roundrect (at -0.484 0) (size 0.59 0.64) (layers "F.Cu" "F.Paste" "F.Mask") (roundrect_rratio 0.25)
      (net 75 "Net-(U7-V_{PLL})") (pintype "passive"))
    (pad "2" smd roundrect (at 0.484 0) (size 0.59 0.64) (layers "F.Cu" "F.Paste" "F.Mask") (roundrect_rratio 0.25)
      (net 9 "GND") (pintype "passive"))
  )

  (footprint "data-center-rdimm-ddr4-tester-footprints:R_0402_1005Metric" (layer "F.Cu")
    (at 135.1 121.325 90)
    (descr "Resistor SMD 0402")
    (tags "resistor SMD 0402")
    (property "Author" "Antmicro")
    (property "License" "Apache-2.0")
    (property "MPN" "CR0402-FX-2002GLF")
    (property "Manufacturer" "Bourns")
    (property "Sheetfile" "interfaces.kicad_sch")
    (property "Sheetname" "Interfaces")
    (property "Tolerance" "1%")
    (property "Val" "20k")
    (property "ki_description" "20k resistor in 0402 package with 1% tolerance")
    (attr smd)
    (fp_text reference "R134" (at -3.675 0.35 90) (layer "F.SilkS")
        (effects (font (size 0.7 0.7) (thickness 0.15)) (justify left bottom))
    )
    (fp_text value "R_20k_0402" (at 0 1.4 90) (layer "F.Fab") hide
        (effects (font (size 0.7 0.7) (thickness 0.15)) (justify left bottom))
    )
    (fp_text user "License: Apache-2.0" (at -0.95 5.169 90) (layer "F.Fab") hide
        (effects (font (size 0.7 0.7) (thickness 0.15)) (justify left bottom))
    )
    (fp_text user "${REFERENCE}" (at -0.95 3.168 90) (layer "F.Fab") hide
        (effects (font (size 0.7 0.7) (thickness 0.15)) (justify left bottom))
    )
    (fp_text user "Author: Antmicro" (at -0.95 4.169 90) (layer "F.Fab") hide
        (effects (font (size 0.7 0.7) (thickness 0.15)) (justify left bottom))
    )
    (fp_rect (start -0.93 -0.47) (end 0.93 0.47)
      (stroke (width 0.05) (type solid)) (fill none) (layer "F.CrtYd"))
    (fp_rect (start -0.5 -0.25) (end 0.5 0.25)
      (stroke (width 0.15) (type solid)) (fill none) (layer "F.Fab"))
    (pad "1" smd roundrect (at -0.485 0 90) (size 0.59 0.64) (layers "F.Cu" "F.Paste" "F.Mask") (roundrect_rratio 0.25)
      (net 143 "3V3_SYS") (pintype "passive"))
    (pad "2" smd roundrect (at 0.485 0 90) (size 0.59 0.64) (layers "F.Cu" "F.Paste" "F.Mask") (roundrect_rratio 0.25)
      (net 84 "SD_CLK") (pintype "passive"))
  )

  (footprint "data-center-rdimm-ddr4-tester-footprints:R_0402_1005Metric" (layer "F.Cu")
    (at 132.9 121.325 90)
    (descr "Resistor SMD 0402")
    (tags "resistor SMD 0402")
    (property "Author" "Antmicro")
    (property "License" "Apache-2.0")
    (property "MPN" "CR0402-FX-2002GLF")
    (property "Manufacturer" "Bourns")
    (property "Sheetfile" "interfaces.kicad_sch")
    (property "Sheetname" "Interfaces")
    (property "Tolerance" "1%")
    (property "Val" "20k")
    (property "ki_description" "20k resistor in 0402 package with 1% tolerance")
    (attr smd)
    (fp_text reference "R135" (at -3.675 0.35 90) (layer "F.SilkS")
        (effects (font (size 0.7 0.7) (thickness 0.15)) (justify left bottom))
    )
    (fp_text value "R_20k_0402" (at 0 1.4 90) (layer "F.Fab") hide
        (effects (font (size 0.7 0.7) (thickness 0.15)) (justify left bottom))
    )
    (fp_text user "License: Apache-2.0" (at -0.95 5.169 90) (layer "F.Fab") hide
        (effects (font (size 0.7 0.7) (thickness 0.15)) (justify left bottom))
    )
    (fp_text user "Author: Antmicro" (at -0.95 4.169 90) (layer "F.Fab") hide
        (effects (font (size 0.7 0.7) (thickness 0.15)) (justify left bottom))
    )
    (fp_text user "${REFERENCE}" (at -0.95 3.168 90) (layer "F.Fab") hide
        (effects (font (size 0.7 0.7) (thickness 0.15)) (justify left bottom))
    )
    (fp_rect (start -0.93 -0.47) (end 0.93 0.47)
      (stroke (width 0.05) (type solid)) (fill none) (layer "F.CrtYd"))
    (fp_rect (start -0.5 -0.25) (end 0.5 0.25)
      (stroke (width 0.15) (type solid)) (fill none) (layer "F.Fab"))
    (pad "1" smd roundrect (at -0.485 0 90) (size 0.59 0.64) (layers "F.Cu" "F.Paste" "F.Mask") (roundrect_rratio 0.25)
      (net 143 "3V3_SYS") (pintype "passive"))
    (pad "2" smd roundrect (at 0.485 0 90) (size 0.59 0.64) (layers "F.Cu" "F.Paste" "F.Mask") (roundrect_rratio 0.25)
      (net 85 "SD_CMD") (pintype "passive"))
  )

  (footprint "data-center-rdimm-ddr4-tester-footprints:R_0402_1005Metric" (layer "F.Cu")
    (at 138.35 121.325 90)
    (descr "Resistor SMD 0402")
    (tags "resistor SMD 0402")
    (property "Author" "Antmicro")
    (property "License" "Apache-2.0")
    (property "MPN" "CR0402-FX-2002GLF")
    (property "Manufacturer" "Bourns")
    (property "Sheetfile" "interfaces.kicad_sch")
    (property "Sheetname" "Interfaces")
    (property "Tolerance" "1%")
    (property "Val" "20k")
    (property "ki_description" "20k resistor in 0402 package with 1% tolerance")
    (attr smd)
    (fp_text reference "R132" (at -3.685 0.335 90) (layer "F.SilkS")
        (effects (font (size 0.7 0.7) (thickness 0.15)) (justify left bottom))
    )
    (fp_text value "R_20k_0402" (at 0 1.4 90) (layer "F.Fab") hide
        (effects (font (size 0.7 0.7) (thickness 0.15)) (justify left bottom))
    )
    (fp_text user "Author: Antmicro" (at -0.95 4.169 90) (layer "F.Fab") hide
        (effects (font (size 0.7 0.7) (thickness 0.15)) (justify left bottom))
    )
    (fp_text user "License: Apache-2.0" (at -0.95 5.169 90) (layer "F.Fab") hide
        (effects (font (size 0.7 0.7) (thickness 0.15)) (justify left bottom))
    )
    (fp_text user "${REFERENCE}" (at -0.95 3.168 90) (layer "F.Fab") hide
        (effects (font (size 0.7 0.7) (thickness 0.15)) (justify left bottom))
    )
    (fp_rect (start -0.93 -0.47) (end 0.93 0.47)
      (stroke (width 0.05) (type solid)) (fill none) (layer "F.CrtYd"))
    (fp_rect (start -0.5 -0.25) (end 0.5 0.25)
      (stroke (width 0.15) (type solid)) (fill none) (layer "F.Fab"))
    (pad "1" smd roundrect (at -0.485 0 90) (size 0.59 0.64) (layers "F.Cu" "F.Paste" "F.Mask") (roundrect_rratio 0.25)
      (net 143 "3V3_SYS") (pintype "passive"))
    (pad "2" smd roundrect (at 0.485 0 90) (size 0.59 0.64) (layers "F.Cu" "F.Paste" "F.Mask") (roundrect_rratio 0.25)
      (net 82 "SD_DAT1") (pintype "passive"))
  )

  (footprint "data-center-rdimm-ddr4-tester-footprints:C_0603_1608Metric" (layer "F.Cu")
    (at 116.661328 103.997157 180)
    (descr "Capacitor SMD 0603")
    (tags "capacitor 0603")
    (property "Author" "Antmicro")
    (property "Dielectric" "")
    (property "License" "Apache-2.0")
    (property "MPN" "C1608X5R1E106M080AC")
    (property "Manufacturer" "TDK")
    (property "Sheetfile" "supply.kicad_sch")
    (property "Sheetname" "Supply")
    (property "Val" "10u/25V")
    (property "Voltage" "")
    (property "ki_description" " ")
    (attr smd)
    (fp_text reference "C28" (at 1.261328 -1.652843 270) (layer "F.SilkS")
        (effects (font (size 0.7 0.7) (thickness 0.15)) (justify left bottom))
    )
    (fp_text value "C_10u_25V_0603" (at 0 1.6 180) (layer "F.Fab") hide
        (effects (font (size 0.7 0.7) (thickness 0.15)) (justify left bottom))
    )
    (fp_text user "License: Apache-2.0" (at -1.682 5.895 180) (layer "F.Fab") hide
        (effects (font (size 0.7 0.7) (thickness 0.15)) (justify left bottom))
    )
    (fp_text user "Author: Antmicro" (at -1.682 4.894 180) (layer "F.Fab") hide
        (effects (font (size 0.7 0.7) (thickness 0.15)) (justify left bottom))
    )
    (fp_text user "${REFERENCE}" (at -1.682 3.895 180) (layer "F.Fab") hide
        (effects (font (size 0.7 0.7) (thickness 0.15)) (justify left bottom))
    )
    (fp_line (start -0.3 -0.3) (end 0.3 -0.3)
      (stroke (width 0.15) (type solid)) (layer "F.SilkS"))
    (fp_line (start -0.3 0.3) (end 0.3 0.3)
      (stroke (width 0.15) (type solid)) (layer "F.SilkS"))
    (fp_rect (start -1.24 -0.7) (end 1.24 0.7)
      (stroke (width 0.05) (type solid)) (fill none) (layer "F.CrtYd"))
    (fp_rect (start -0.8 -0.4) (end 0.8 0.4)
      (stroke (width 0.15) (type solid)) (fill none) (layer "F.Fab"))
    (pad "1" smd roundrect (at -0.7 0 180) (size 0.6 0.8) (layers "F.Cu" "F.Paste" "F.Mask") (roundrect_rratio 0.2)
      (net 103 "VIN") (pintype "passive"))
    (pad "2" smd roundrect (at 0.7 0 180) (size 0.6 0.8) (layers "F.Cu" "F.Paste" "F.Mask") (roundrect_rratio 0.2)
      (net 9 "GND") (pintype "passive"))
  )

  (footprint "data-center-rdimm-ddr4-tester-footprints:FB_0603_1608Metric" (layer "F.Cu")
    (at 142.306328 116.527157 180)
    (property "Author" "Antmicro")
    (property "License" "Apache-2.0")
    (property "MPN" "BLM18AG601SN1D")
    (property "Manufacturer" "Murata")
    (property "Sheetfile" "interfaces.kicad_sch")
    (property "Sheetname" "Interfaces")
    (property "ki_description" "Ferrite Beads WE-TMSB Suppression 240Ohm 200mA ")
    (property "ki_keywords" " Multilayer Suppression Beads ")
    (attr smd)
    (fp_text reference "FB4" (at 0.706328 -3.582843 180) (layer "F.SilkS")
        (effects (font (size 0.7 0.7) (thickness 0.15)) (justify left bottom))
    )
    (fp_text value "FB_600Z_0.5A_0603" (at 0 1.7 180) (layer "F.Fab") hide
        (effects (font (size 0.7 0.7) (thickness 0.15)) (justify left bottom))
    )
    (fp_text user "Author: Antmicro" (at -1.653 3.162 180) (layer "F.Fab") hide
        (effects (font (size 0.7 0.7) (thickness 0.15)) (justify left bottom))
    )
    (fp_text user "License: Apache-2.0" (at -1.653 5.9 180) (layer "F.Fab") hide
        (effects (font (size 0.7 0.7) (thickness 0.15)) (justify left bottom))
    )
    (fp_text user "${REFERENCE}" (at -1.653 4.6 180) (layer "F.Fab") hide
        (effects (font (size 0.7 0.7) (thickness 0.15)) (justify left bottom))
    )
    (fp_line (start -0.196 -0.408) (end 0.193 -0.408)
      (stroke (width 0.15) (type solid)) (layer "F.SilkS"))
    (fp_line (start -0.196 0.406) (end 0.193 0.406)
      (stroke (width 0.15) (type solid)) (layer "F.SilkS"))
    (fp_rect (start -1.42 -0.69) (end 1.42 0.69)
      (stroke (width 0.05) (type solid)) (fill none) (layer "F.CrtYd"))
    (fp_line (start -0.803 0.406) (end -0.803 -0.408)
      (stroke (width 0.15) (type solid)) (layer "F.Fab"))
    (fp_line (start 0.8 -0.408) (end -0.803 -0.408)
      (stroke (width 0.15) (type solid)) (layer "F.Fab"))
    (fp_line (start 0.8 -0.408) (end 0.8 0.406)
      (stroke (width 0.15) (type solid)) (layer "F.Fab"))
    (fp_line (start 0.8 0.406) (end -0.803 0.406)
      (stroke (width 0.15) (type solid)) (layer "F.Fab"))
    (pad "1" smd roundrect (at -0.891 0 180) (size 0.762 1.09) (layers "F.Cu" "F.Paste" "F.Mask") (roundrect_rratio 0.15)
      (net 143 "3V3_SYS") (pintype "passive"))
    (pad "2" smd roundrect (at 0.888 0 180) (size 0.762 1.09) (layers "F.Cu" "F.Paste" "F.Mask") (roundrect_rratio 0.15)
      (net 75 "Net-(U7-V_{PLL})") (pintype "passive"))
  )

  (footprint "data-center-rdimm-ddr4-tester-footprints:C_0402_1005Metric" (layer "F.Cu")
    (at 137.536328 117.372157 90)
    (descr "Capacitor SMD 0402")
    (tags "capacitor SMD 0402")
    (property "Author" "Antmicro")
    (property "Dielectric" "")
    (property "License" "Apache-2.0")
    (property "MPN" "MC0402N180J500CT")
    (property "Manufacturer" "Multicomp")
    (property "Sheetfile" "interfaces.kicad_sch")
    (property "Sheetname" "Interfaces")
    (property "Val" "18p")
    (property "Voltage" "")
    (property "ki_description" " ")
    (attr smd)
    (fp_text reference "C193" (at -2.827843 2.813672 90) (layer "F.SilkS")
        (effects (font (size 0.7 0.7) (thickness 0.15)) (justify left bottom))
    )
    (fp_text value "C_18p_0402" (at 0 1.4 90) (layer "F.Fab") hide
        (effects (font (size 0.7 0.7) (thickness 0.15)) (justify left bottom))
    )
    (fp_text user "${REFERENCE}" (at -0.932 3.168 90) (layer "F.Fab") hide
        (effects (font (size 0.7 0.7) (thickness 0.15)) (justify left bottom))
    )
    (fp_text user "License: Apache-2.0" (at -0.932 5.17 90) (layer "F.Fab") hide
        (effects (font (size 0.7 0.7) (thickness 0.15)) (justify left bottom))
    )
    (fp_text user "Author: Antmicro" (at -0.932 4.17 90) (layer "F.Fab") hide
        (effects (font (size 0.7 0.7) (thickness 0.15)) (justify left bottom))
    )
    (fp_rect (start -0.94 -0.47) (end 0.94 0.47)
      (stroke (width 0.05) (type solid)) (fill none) (layer "F.CrtYd"))
    (fp_rect (start -0.499 -0.249) (end 0.499 0.249)
      (stroke (width 0.15) (type solid)) (fill none) (layer "F.Fab"))
    (pad "1" smd roundrect (at -0.484 0 90) (size 0.59 0.64) (layers "F.Cu" "F.Paste" "F.Mask") (roundrect_rratio 0.25)
      (net 81 "Net-(U7-OSCO)") (pintype "passive"))
    (pad "2" smd roundrect (at 0.484 0 90) (size 0.59 0.64) (layers "F.Cu" "F.Paste" "F.Mask") (roundrect_rratio 0.25)
      (net 9 "GND") (pintype "passive"))
  )

  (footprint "data-center-rdimm-ddr4-tester-footprints:R_0402_1005Metric" (layer "F.Cu")
    (at 118.411328 116.622157 180)
    (descr "Resistor SMD 0402")
    (tags "resistor SMD 0402")
    (property "Author" "Antmicro")
    (property "License" "Apache-2.0")
    (property "MPN" "CR0402-FX-5362GLF")
    (property "Manufacturer" "Bourns")
    (property "Sheetfile" "supply.kicad_sch")
    (property "Sheetname" "Supply")
    (property "Tolerance" "1%")
    (property "Val" "53k6")
    (property "ki_description" "53k6 resistor in 0402 package with 1% tolerance")
    (attr smd)
    (fp_text reference "R127" (at 5.151328 -3.597843 180) (layer "F.SilkS")
        (effects (font (size 0.7 0.7) (thickness 0.15)) (justify left bottom))
    )
    (fp_text value "R_53k6_0402" (at 0 1.4 180) (layer "F.Fab") hide
        (effects (font (size 0.7 0.7) (thickness 0.15)) (justify left bottom))
    )
    (fp_text user "Author: Antmicro" (at -0.95 4.169 180) (layer "F.Fab") hide
        (effects (font (size 0.7 0.7) (thickness 0.15)) (justify left bottom))
    )
    (fp_text user "${REFERENCE}" (at -0.95 3.168 180) (layer "F.Fab") hide
        (effects (font (size 0.7 0.7) (thickness 0.15)) (justify left bottom))
    )
    (fp_text user "License: Apache-2.0" (at -0.95 5.169 180) (layer "F.Fab") hide
        (effects (font (size 0.7 0.7) (thickness 0.15)) (justify left bottom))
    )
    (fp_rect (start -0.93 -0.47) (end 0.93 0.47)
      (stroke (width 0.05) (type solid)) (fill none) (layer "F.CrtYd"))
    (fp_rect (start -0.5 -0.25) (end 0.5 0.25)
      (stroke (width 0.15) (type solid)) (fill none) (layer "F.Fab"))
    (pad "1" smd roundrect (at -0.485 0 180) (size 0.59 0.64) (layers "F.Cu" "F.Paste" "F.Mask") (roundrect_rratio 0.25)
      (net 118 "Net-(R126-Pad2)") (pintype "passive"))
    (pad "2" smd roundrect (at 0.485 0 180) (size 0.59 0.64) (layers "F.Cu" "F.Paste" "F.Mask") (roundrect_rratio 0.25)
      (net 110 "Net-(IC1-FB)") (pintype "passive"))
  )

  (footprint "data-center-rdimm-ddr4-tester-footprints:C_0603_1608Metric" (layer "F.Cu")
    (at 116.036328 89.122157 180)
    (descr "Capacitor SMD 0603")
    (tags "capacitor 0603")
    (property "Author" "Antmicro")
    (property "Dielectric" "")
    (property "License" "Apache-2.0")
    (property "MPN" "GRM188R60J226MEA0D")
    (property "Manufacturer" "Murata")
    (property "Sheetfile" "supply.kicad_sch")
    (property "Sheetname" "Supply")
    (property "Val" "22u")
    (property "Voltage" "")
    (property "ki_description" " ")
    (attr smd)
    (fp_text reference "C42" (at 1.636328 13.392157 180) (layer "F.SilkS")
        (effects (font (size 0.7 0.7) (thickness 0.15)) (justify left bottom))
    )
    (fp_text value "C_22u_0603" (at 0 1.6 180) (layer "F.Fab") hide
        (effects (font (size 0.7 0.7) (thickness 0.15)) (justify left bottom))
    )
    (fp_text user "Author: Antmicro" (at -1.682 4.894 180) (layer "F.Fab") hide
        (effects (font (size 0.7 0.7) (thickness 0.15)) (justify left bottom))
    )
    (fp_text user "License: Apache-2.0" (at -1.682 5.895 180) (layer "F.Fab") hide
        (effects (font (size 0.7 0.7) (thickness 0.15)) (justify left bottom))
    )
    (fp_text user "${REFERENCE}" (at -1.682 3.895 180) (layer "F.Fab") hide
        (effects (font (size 0.7 0.7) (thickness 0.15)) (justify left bottom))
    )
    (fp_line (start -0.3 -0.3) (end 0.3 -0.3)
      (stroke (width 0.15) (type solid)) (layer "F.SilkS"))
    (fp_line (start -0.3 0.3) (end 0.3 0.3)
      (stroke (width 0.15) (type solid)) (layer "F.SilkS"))
    (fp_rect (start -1.24 -0.7) (end 1.24 0.7)
      (stroke (width 0.05) (type solid)) (fill none) (layer "F.CrtYd"))
    (fp_rect (start -0.8 -0.4) (end 0.8 0.4)
      (stroke (width 0.15) (type solid)) (fill none) (layer "F.Fab"))
    (pad "1" smd roundrect (at -0.7 0 180) (size 0.6 0.8) (layers "F.Cu" "F.Paste" "F.Mask") (roundrect_rratio 0.2)
      (net 301 "VDD1V2") (pintype "passive"))
    (pad "2" smd roundrect (at 0.7 0 180) (size 0.6 0.8) (layers "F.Cu" "F.Paste" "F.Mask") (roundrect_rratio 0.2)
      (net 9 "GND") (pintype "passive"))
  )

  (footprint "data-center-rdimm-ddr4-tester-footprints:C_0603_1608Metric" (layer "F.Cu")
    (at 116.036328 90.622157 180)
    (descr "Capacitor SMD 0603")
    (tags "capacitor 0603")
    (property "Author" "Antmicro")
    (property "Dielectric" "")
    (property "License" "Apache-2.0")
    (property "MPN" "GRM188R60J226MEA0D")
    (property "Manufacturer" "Murata")
    (property "Sheetfile" "supply.kicad_sch")
    (property "Sheetname" "Supply")
    (property "Val" "22u")
    (property "Voltage" "")
    (property "ki_description" " ")
    (attr smd)
    (fp_text reference "C41" (at 1.626328 13.922157 180) (layer "F.SilkS")
        (effects (font (size 0.7 0.7) (thickness 0.15)) (justify left bottom))
    )
    (fp_text value "C_22u_0603" (at 0 1.6 180) (layer "F.Fab") hide
        (effects (font (size 0.7 0.7) (thickness 0.15)) (justify left bottom))
    )
    (fp_text user "Author: Antmicro" (at -1.682 4.894 180) (layer "F.Fab") hide
        (effects (font (size 0.7 0.7) (thickness 0.15)) (justify left bottom))
    )
    (fp_text user "License: Apache-2.0" (at -1.682 5.895 180) (layer "F.Fab") hide
        (effects (font (size 0.7 0.7) (thickness 0.15)) (justify left bottom))
    )
    (fp_text user "${REFERENCE}" (at -1.682 3.895 180) (layer "F.Fab") hide
        (effects (font (size 0.7 0.7) (thickness 0.15)) (justify left bottom))
    )
    (fp_line (start -0.3 -0.3) (end 0.3 -0.3)
      (stroke (width 0.15) (type solid)) (layer "F.SilkS"))
    (fp_line (start -0.3 0.3) (end 0.3 0.3)
      (stroke (width 0.15) (type solid)) (layer "F.SilkS"))
    (fp_rect (start -1.24 -0.7) (end 1.24 0.7)
      (stroke (width 0.05) (type solid)) (fill none) (layer "F.CrtYd"))
    (fp_rect (start -0.8 -0.4) (end 0.8 0.4)
      (stroke (width 0.15) (type solid)) (fill none) (layer "F.Fab"))
    (pad "1" smd roundrect (at -0.7 0 180) (size 0.6 0.8) (layers "F.Cu" "F.Paste" "F.Mask") (roundrect_rratio 0.2)
      (net 301 "VDD1V2") (pintype "passive"))
    (pad "2" smd roundrect (at 0.7 0 180) (size 0.6 0.8) (layers "F.Cu" "F.Paste" "F.Mask") (roundrect_rratio 0.2)
      (net 9 "GND") (pintype "passive"))
  )

  (footprint "data-center-rdimm-ddr4-tester-footprints:R_0402_1005Metric" (layer "F.Cu")
    (at 221.803 112.867 90)
    (descr "Resistor SMD 0402")
    (tags "resistor SMD 0402")
    (property "Author" "Antmicro")
    (property "License" "Apache-2.0")
    (property "MPN" "CR0402-FX-1000GLF")
    (property "Manufacturer" "Bourns")
    (property "Sheetfile" "config-spi.kicad_sch")
    (property "Sheetname" "Config SPI flash")
    (property "Tolerance" "1%")
    (property "Val" "100R")
    (property "ki_description" "100R resistor in 0402 package with 1% tolerance")
    (attr smd)
    (fp_text reference "R10" (at 0.677 0.387 90) (layer "F.SilkS")
        (effects (font (size 0.7 0.7) (thickness 0.15)) (justify left bottom))
    )
    (fp_text value "R_100R_0402" (at 0 1.4 90) (layer "F.Fab") hide
        (effects (font (size 0.7 0.7) (thickness 0.15)) (justify left bottom))
    )
    (fp_text user "Author: Antmicro" (at -0.95 4.169 90) (layer "F.Fab") hide
        (effects (font (size 0.7 0.7) (thickness 0.15)) (justify left bottom))
    )
    (fp_text user "License: Apache-2.0" (at -0.95 5.169 90) (layer "F.Fab") hide
        (effects (font (size 0.7 0.7) (thickness 0.15)) (justify left bottom))
    )
    (fp_text user "${REFERENCE}" (at -0.95 3.168 90) (layer "F.Fab") hide
        (effects (font (size 0.7 0.7) (thickness 0.15)) (justify left bottom))
    )
    (fp_rect (start -0.93 -0.47) (end 0.93 0.47)
      (stroke (width 0.05) (type solid)) (fill none) (layer "F.CrtYd"))
    (fp_rect (start -0.5 -0.25) (end 0.5 0.25)
      (stroke (width 0.15) (type solid)) (fill none) (layer "F.Fab"))
    (pad "1" smd roundrect (at -0.485 0 90) (size 0.59 0.64) (layers "F.Cu" "F.Paste" "F.Mask") (roundrect_rratio 0.25)
      (net 143 "3V3_SYS") (pintype "passive"))
    (pad "2" smd roundrect (at 0.485 0 90) (size 0.59 0.64) (layers "F.Cu" "F.Paste" "F.Mask") (roundrect_rratio 0.25)
      (net 79 "PUDC_B") (pintype "passive"))
  )

  (footprint "data-center-rdimm-ddr4-tester-footprints:R_0402_1005Metric" (layer "F.Cu")
    (at 238.434 117.001 180)
    (descr "Resistor SMD 0402")
    (tags "resistor SMD 0402")
    (property "Author" "Antmicro")
    (property "License" "Apache-2.0")
    (property "MPN" "CR0402-FX-4701GLF")
    (property "Manufacturer" "Bourns")
    (property "Sheetfile" "config-spi.kicad_sch")
    (property "Sheetname" "Config SPI flash")
    (property "Tolerance" "1%")
    (property "Val" "4k7")
    (property "ki_description" "4k7 resistor in 0402 package with 1% tolerance")
    (attr smd)
    (fp_text reference "R21" (at -0.786 -0.369 180) (layer "F.SilkS")
        (effects (font (size 0.7 0.7) (thickness 0.15)) (justify left bottom))
    )
    (fp_text value "R_4k7_0402" (at 0 1.4 180) (layer "F.Fab") hide
        (effects (font (size 0.7 0.7) (thickness 0.15)) (justify left bottom))
    )
    (fp_text user "${REFERENCE}" (at -0.95 3.168 180) (layer "F.Fab") hide
        (effects (font (size 0.7 0.7) (thickness 0.15)) (justify left bottom))
    )
    (fp_text user "Author: Antmicro" (at -0.95 4.169 180) (layer "F.Fab") hide
        (effects (font (size 0.7 0.7) (thickness 0.15)) (justify left bottom))
    )
    (fp_text user "License: Apache-2.0" (at -0.95 5.169 180) (layer "F.Fab") hide
        (effects (font (size 0.7 0.7) (thickness 0.15)) (justify left bottom))
    )
    (fp_rect (start -0.93 -0.47) (end 0.93 0.47)
      (stroke (width 0.05) (type solid)) (fill none) (layer "F.CrtYd"))
    (fp_rect (start -0.5 -0.25) (end 0.5 0.25)
      (stroke (width 0.15) (type solid)) (fill none) (layer "F.Fab"))
    (pad "1" smd roundrect (at -0.485 0 180) (size 0.59 0.64) (layers "F.Cu" "F.Paste" "F.Mask") (roundrect_rratio 0.25)
      (net 143 "3V3_SYS") (pintype "passive"))
    (pad "2" smd roundrect (at 0.485 0 180) (size 0.59 0.64) (layers "F.Cu" "F.Paste" "F.Mask") (roundrect_rratio 0.25)
      (net 22 "QSPI_DQ3") (pintype "passive"))
  )

  (footprint "data-center-rdimm-ddr4-tester-footprints:R_0402_1005Metric" (layer "F.Cu")
    (at 222.432 118.271)
    (descr "Resistor SMD 0402")
    (tags "resistor SMD 0402")
    (property "Author" "Antmicro")
    (property "License" "Apache-2.0")
    (property "MPN" "CR0402-FX-4701GLF")
    (property "Manufacturer" "Bourns")
    (property "Sheetfile" "config-spi.kicad_sch")
    (property "Sheetname" "Config SPI flash")
    (property "Tolerance" "1%")
    (property "Val" "4k7")
    (property "ki_description" "4k7 resistor in 0402 package with 1% tolerance")
    (attr smd)
    (fp_text reference "R22" (at -3.062 0.359) (layer "F.SilkS")
        (effects (font (size 0.7 0.7) (thickness 0.15)) (justify left bottom))
    )
    (fp_text value "R_4k7_0402" (at 0 1.4) (layer "F.Fab") hide
        (effects (font (size 0.7 0.7) (thickness 0.15)) (justify left bottom))
    )
    (fp_text user "License: Apache-2.0" (at -0.95 5.169) (layer "F.Fab") hide
        (effects (font (size 0.7 0.7) (thickness 0.15)) (justify left bottom))
    )
    (fp_text user "${REFERENCE}" (at -0.95 3.168) (layer "F.Fab") hide
        (effects (font (size 0.7 0.7) (thickness 0.15)) (justify left bottom))
    )
    (fp_text user "Author: Antmicro" (at -0.95 4.169) (layer "F.Fab") hide
        (effects (font (size 0.7 0.7) (thickness 0.15)) (justify left bottom))
    )
    (fp_rect (start -0.93 -0.47) (end 0.93 0.47)
      (stroke (width 0.05) (type solid)) (fill none) (layer "F.CrtYd"))
    (fp_rect (start -0.5 -0.25) (end 0.5 0.25)
      (stroke (width 0.15) (type solid)) (fill none) (layer "F.Fab"))
    (pad "1" smd roundrect (at -0.485 0) (size 0.59 0.64) (layers "F.Cu" "F.Paste" "F.Mask") (roundrect_rratio 0.25)
      (net 143 "3V3_SYS") (pintype "passive"))
    (pad "2" smd roundrect (at 0.485 0) (size 0.59 0.64) (layers "F.Cu" "F.Paste" "F.Mask") (roundrect_rratio 0.25)
      (net 21 "QSPI_DQ2") (pintype "passive"))
  )

  (footprint "data-center-rdimm-ddr4-tester-footprints:R_0402_1005Metric" (layer "F.Cu")
    (at 224.4005 115.731 180)
    (descr "Resistor SMD 0402")
    (tags "resistor SMD 0402")
    (property "Author" "Antmicro")
    (property "Current" "1A")
    (property "License" "Apache-2.0")
    (property "MPN" "ERJ2GE0R00X")
    (property "Manufacturer" "Panasonic")
    (property "Sheetfile" "config-spi.kicad_sch")
    (property "Sheetname" "Config SPI flash")
    (property "Tolerance" "")
    (property "Val" "0R")
    (property "ki_description" "0R resistor in 0402 package with unspecified tolerance")
    (attr smd)
    (fp_text reference "R23" (at 1.0505 0.401 180) (layer "F.SilkS")
        (effects (font (size 0.7 0.7) (thickness 0.15)) (justify left bottom))
    )
    (fp_text value "R_0R_0402" (at 0 1.4 180) (layer "F.Fab") hide
        (effects (font (size 0.7 0.7) (thickness 0.15)) (justify left bottom))
    )
    (fp_text user "Author: Antmicro" (at -0.95 4.169 180) (layer "F.Fab") hide
        (effects (font (size 0.7 0.7) (thickness 0.15)) (justify left bottom))
    )
    (fp_text user "${REFERENCE}" (at -0.95 3.168 180) (layer "F.Fab") hide
        (effects (font (size 0.7 0.7) (thickness 0.15)) (justify left bottom))
    )
    (fp_text user "License: Apache-2.0" (at -0.95 5.169 180) (layer "F.Fab") hide
        (effects (font (size 0.7 0.7) (thickness 0.15)) (justify left bottom))
    )
    (fp_rect (start -0.93 -0.47) (end 0.93 0.47)
      (stroke (width 0.05) (type solid)) (fill none) (layer "F.CrtYd"))
    (fp_rect (start -0.5 -0.25) (end 0.5 0.25)
      (stroke (width 0.15) (type solid)) (fill none) (layer "F.Fab"))
    (pad "1" smd roundrect (at -0.485 0 180) (size 0.59 0.64) (layers "F.Cu" "F.Paste" "F.Mask") (roundrect_rratio 0.25)
      (net 596 "Net-(U3-~{CS})") (pintype "passive"))
    (pad "2" smd roundrect (at 0.485 0 180) (size 0.59 0.64) (layers "F.Cu" "F.Paste" "F.Mask") (roundrect_rratio 0.25)
      (net 95 "FCS_B") (pintype "passive"))
  )

  (footprint "data-center-rdimm-ddr4-tester-footprints:R_0402_1005Metric" (layer "F.Cu")
    (at 224.4005 118.271 180)
    (descr "Resistor SMD 0402")
    (tags "resistor SMD 0402")
    (property "Author" "Antmicro")
    (property "Current" "1A")
    (property "License" "Apache-2.0")
    (property "MPN" "ERJ2GE0R00X")
    (property "Manufacturer" "Panasonic")
    (property "Sheetfile" "config-spi.kicad_sch")
    (property "Sheetname" "Config SPI flash")
    (property "Tolerance" "")
    (property "Val" "0R")
    (property "ki_description" "0R resistor in 0402 package with unspecified tolerance")
    (attr smd)
    (fp_text reference "R27" (at 1.1805 -1.169 180) (layer "F.SilkS")
        (effects (font (size 0.7 0.7) (thickness 0.15)) (justify left bottom))
    )
    (fp_text value "R_0R_0402" (at 0 1.4 180) (layer "F.Fab") hide
        (effects (font (size 0.7 0.7) (thickness 0.15)) (justify left bottom))
    )
    (fp_text user "${REFERENCE}" (at -0.95 3.168 180) (layer "F.Fab") hide
        (effects (font (size 0.7 0.7) (thickness 0.15)) (justify left bottom))
    )
    (fp_text user "Author: Antmicro" (at -0.95 4.169 180) (layer "F.Fab") hide
        (effects (font (size 0.7 0.7) (thickness 0.15)) (justify left bottom))
    )
    (fp_text user "License: Apache-2.0" (at -0.95 5.169 180) (layer "F.Fab") hide
        (effects (font (size 0.7 0.7) (thickness 0.15)) (justify left bottom))
    )
    (fp_rect (start -0.93 -0.47) (end 0.93 0.47)
      (stroke (width 0.05) (type solid)) (fill none) (layer "F.CrtYd"))
    (fp_rect (start -0.5 -0.25) (end 0.5 0.25)
      (stroke (width 0.15) (type solid)) (fill none) (layer "F.Fab"))
    (pad "1" smd roundrect (at -0.485 0 180) (size 0.59 0.64) (layers "F.Cu" "F.Paste" "F.Mask") (roundrect_rratio 0.25)
      (net 600 "Net-(U3-~{WP}{slash}IO2)") (pintype "passive"))
    (pad "2" smd roundrect (at 0.485 0 180) (size 0.59 0.64) (layers "F.Cu" "F.Paste" "F.Mask") (roundrect_rratio 0.25)
      (net 21 "QSPI_DQ2") (pintype "passive"))
  )

  (footprint "data-center-rdimm-ddr4-tester-footprints:R_0402_1005Metric" (layer "F.Cu")
    (at 220.787 112.867 -90)
    (descr "Resistor SMD 0402")
    (tags "resistor SMD 0402")
    (property "Author" "Antmicro")
    (property "DNP" "DNP")
    (property "License" "Apache-2.0")
    (property "MPN" "CR0402-FX-1000GLF")
    (property "Manufacturer" "Bourns")
    (property "Sheetfile" "config-spi.kicad_sch")
    (property "Sheetname" "Config SPI flash")
    (property "Tolerance" "1%")
    (property "Val" "100R")
    (property "dnp" "")
    (property "exclude_from_bom" "")
    (property "ki_description" "100R resistor in 0402 package with 1% tolerance")
    (attr exclude_from_pos_files exclude_from_bom)
    (fp_text reference "R36" (at -0.667 -0.363 -90) (layer "F.SilkS")
        (effects (font (size 0.7 0.7) (thickness 0.15)) (justify left bottom))
    )
    (fp_text value "R_100R_0402" (at 0 1.4 -90) (layer "F.Fab") hide
        (effects (font (size 0.7 0.7) (thickness 0.15)) (justify left bottom))
    )
    (fp_text user "Author: Antmicro" (at -0.95 4.169 -90) (layer "F.Fab") hide
        (effects (font (size 0.7 0.7) (thickness 0.15)) (justify left bottom))
    )
    (fp_text user "License: Apache-2.0" (at -0.95 5.169 -90) (layer "F.Fab") hide
        (effects (font (size 0.7 0.7) (thickness 0.15)) (justify left bottom))
    )
    (fp_text user "${REFERENCE}" (at -0.95 3.168 -90) (layer "F.Fab") hide
        (effects (font (size 0.7 0.7) (thickness 0.15)) (justify left bottom))
    )
    (fp_rect (start -0.93 -0.47) (end 0.93 0.47)
      (stroke (width 0.05) (type solid)) (fill none) (layer "F.CrtYd"))
    (fp_rect (start -0.5 -0.25) (end 0.5 0.25)
      (stroke (width 0.15) (type solid)) (fill none) (layer "F.Fab"))
    (pad "1" smd roundrect (at -0.485 0 270) (size 0.59 0.64) (layers "F.Cu" "F.Paste" "F.Mask") (roundrect_rratio 0.25)
      (net 79 "PUDC_B") (pintype "passive"))
    (pad "2" smd roundrect (at 0.485 0 270) (size 0.59 0.64) (layers "F.Cu" "F.Paste" "F.Mask") (roundrect_rratio 0.25)
      (net 9 "GND") (pintype "passive"))
  )

  (footprint "data-center-rdimm-ddr4-tester-footprints:R_0402_1005Metric" (layer "F.Cu")
    (at 235.767 119.541)
    (descr "Resistor SMD 0402")
    (tags "resistor SMD 0402")
    (property "Author" "Antmicro")
    (property "Current" "1A")
    (property "License" "Apache-2.0")
    (property "MPN" "ERJ2GE0R00X")
    (property "Manufacturer" "Panasonic")
    (property "Sheetfile" "config-spi.kicad_sch")
    (property "Sheetname" "Config SPI flash")
    (property "Tolerance" "")
    (property "Val" "0R")
    (property "ki_description" "0R resistor in 0402 package with unspecified tolerance")
    (attr smd)
    (fp_text reference "R59" (at -1.027 -4.361) (layer "F.SilkS")
        (effects (font (size 0.7 0.7) (thickness 0.15)) (justify left bottom))
    )
    (fp_text value "R_0R_0402" (at 0 1.4) (layer "F.Fab") hide
        (effects (font (size 0.7 0.7) (thickness 0.15)) (justify left bottom))
    )
    (fp_text user "Author: Antmicro" (at -0.95 4.169) (layer "F.Fab") hide
        (effects (font (size 0.7 0.7) (thickness 0.15)) (justify left bottom))
    )
    (fp_text user "License: Apache-2.0" (at -0.95 5.169) (layer "F.Fab") hide
        (effects (font (size 0.7 0.7) (thickness 0.15)) (justify left bottom))
    )
    (fp_text user "${REFERENCE}" (at -0.95 3.168) (layer "F.Fab") hide
        (effects (font (size 0.7 0.7) (thickness 0.15)) (justify left bottom))
    )
    (fp_rect (start -0.93 -0.47) (end 0.93 0.47)
      (stroke (width 0.05) (type solid)) (fill none) (layer "F.CrtYd"))
    (fp_rect (start -0.5 -0.25) (end 0.5 0.25)
      (stroke (width 0.15) (type solid)) (fill none) (layer "F.Fab"))
    (pad "1" smd roundrect (at -0.485 0) (size 0.59 0.64) (layers "F.Cu" "F.Paste" "F.Mask") (roundrect_rratio 0.25)
      (net 650 "Net-(U3-SI{slash}IO0)") (pintype "passive"))
    (pad "2" smd roundrect (at 0.485 0) (size 0.59 0.64) (layers "F.Cu" "F.Paste" "F.Mask") (roundrect_rratio 0.25)
      (net 19 "QSPI_DQ0") (pintype "passive"))
  )

  (footprint "data-center-rdimm-ddr4-tester-footprints:R_0402_1005Metric" (layer "F.Cu")
    (at 224.4005 117.001 180)
    (descr "Resistor SMD 0402")
    (tags "resistor SMD 0402")
    (property "Author" "Antmicro")
    (property "Current" "1A")
    (property "License" "Apache-2.0")
    (property "MPN" "ERJ2GE0R00X")
    (property "Manufacturer" "Panasonic")
    (property "Sheetfile" "config-spi.kicad_sch")
    (property "Sheetname" "Config SPI flash")
    (property "Tolerance" "")
    (property "Val" "0R")
    (property "ki_description" "0R resistor in 0402 package with unspecified tolerance")
    (attr smd)
    (fp_text reference "R60" (at 3.0105 -0.399 180) (layer "F.SilkS")
        (effects (font (size 0.7 0.7) (thickness 0.15)) (justify left bottom))
    )
    (fp_text value "R_0R_0402" (at 0 1.4 180) (layer "F.Fab") hide
        (effects (font (size 0.7 0.7) (thickness 0.15)) (justify left bottom))
    )
    (fp_text user "${REFERENCE}" (at -0.95 3.168 180) (layer "F.Fab") hide
        (effects (font (size 0.7 0.7) (thickness 0.15)) (justify left bottom))
    )
    (fp_text user "License: Apache-2.0" (at -0.95 5.169 180) (layer "F.Fab") hide
        (effects (font (size 0.7 0.7) (thickness 0.15)) (justify left bottom))
    )
    (fp_text user "Author: Antmicro" (at -0.95 4.169 180) (layer "F.Fab") hide
        (effects (font (size 0.7 0.7) (thickness 0.15)) (justify left bottom))
    )
    (fp_rect (start -0.93 -0.47) (end 0.93 0.47)
      (stroke (width 0.05) (type solid)) (fill none) (layer "F.CrtYd"))
    (fp_rect (start -0.5 -0.25) (end 0.5 0.25)
      (stroke (width 0.15) (type solid)) (fill none) (layer "F.Fab"))
    (pad "1" smd roundrect (at -0.485 0 180) (size 0.59 0.64) (layers "F.Cu" "F.Paste" "F.Mask") (roundrect_rratio 0.25)
      (net 651 "Net-(U3-SO{slash}IO1)") (pintype "passive"))
    (pad "2" smd roundrect (at 0.485 0 180) (size 0.59 0.64) (layers "F.Cu" "F.Paste" "F.Mask") (roundrect_rratio 0.25)
      (net 20 "QSPI_DQ1") (pintype "passive"))
  )

  (footprint "data-center-rdimm-ddr4-tester-footprints:R_0402_1005Metric" (layer "F.Cu")
    (at 235.767 118.271)
    (descr "Resistor SMD 0402")
    (tags "resistor SMD 0402")
    (property "Author" "Antmicro")
    (property "Current" "1A")
    (property "License" "Apache-2.0")
    (property "MPN" "ERJ2GE0R00X")
    (property "Manufacturer" "Panasonic")
    (property "Sheetfile" "config-spi.kicad_sch")
    (property "Sheetname" "Config SPI flash")
    (property "Tolerance" "")
    (property "Val" "0R")
    (property "ki_description" "0R resistor in 0402 package with unspecified tolerance")
    (attr smd)
    (fp_text reference "R24" (at -1.027 -4.011) (layer "F.SilkS")
        (effects (font (size 0.7 0.7) (thickness 0.15)) (justify left bottom))
    )
    (fp_text value "R_0R_0402" (at 0 1.4) (layer "F.Fab") hide
        (effects (font (size 0.7 0.7) (thickness 0.15)) (justify left bottom))
    )
    (fp_text user "License: Apache-2.0" (at -0.95 5.169) (layer "F.Fab") hide
        (effects (font (size 0.7 0.7) (thickness 0.15)) (justify left bottom))
    )
    (fp_text user "Author: Antmicro" (at -0.95 4.169) (layer "F.Fab") hide
        (effects (font (size 0.7 0.7) (thickness 0.15)) (justify left bottom))
    )
    (fp_text user "${REFERENCE}" (at -0.95 3.168) (layer "F.Fab") hide
        (effects (font (size 0.7 0.7) (thickness 0.15)) (justify left bottom))
    )
    (fp_rect (start -0.93 -0.47) (end 0.93 0.47)
      (stroke (width 0.05) (type solid)) (fill none) (layer "F.CrtYd"))
    (fp_rect (start -0.5 -0.25) (end 0.5 0.25)
      (stroke (width 0.15) (type solid)) (fill none) (layer "F.Fab"))
    (pad "1" smd roundrect (at -0.485 0) (size 0.59 0.64) (layers "F.Cu" "F.Paste" "F.Mask") (roundrect_rratio 0.25)
      (net 597 "Net-(U3-SCK)") (pintype "passive"))
    (pad "2" smd roundrect (at 0.485 0) (size 0.59 0.64) (layers "F.Cu" "F.Paste" "F.Mask") (roundrect_rratio 0.25)
      (net 96 "CCLK") (pintype "passive"))
  )

  (footprint "data-center-rdimm-ddr4-tester-footprints:C_0603_1608Metric" (layer "F.Cu")
    (at 139.5 98.25 180)
    (descr "Capacitor SMD 0603")
    (tags "capacitor 0603")
    (property "Author" "Antmicro")
    (property "Dielectric" "")
    (property "License" "Apache-2.0")
    (property "MPN" "06031C103JAT2A")
    (property "Manufacturer" "AVX")
    (property "Sheetfile" "supply.kicad_sch")
    (property "Sheetname" "Supply")
    (property "Val" "10n")
    (property "Voltage" "")
    (property "ki_description" " ")
    (attr smd)
    (fp_text reference "C100" (at -1.01 -0.34 180) (layer "F.SilkS")
        (effects (font (size 0.7 0.7) (thickness 0.15)) (justify left bottom))
    )
    (fp_text value "C_10n_0603" (at 0 1.6 180) (layer "F.Fab") hide
        (effects (font (size 0.7 0.7) (thickness 0.15)) (justify left bottom))
    )
    (fp_text user "Author: Antmicro" (at -1.682 4.894 180) (layer "F.Fab") hide
        (effects (font (size 0.7 0.7) (thickness 0.15)) (justify left bottom))
    )
    (fp_text user "${REFERENCE}" (at -1.682 3.895 180) (layer "F.Fab") hide
        (effects (font (size 0.7 0.7) (thickness 0.15)) (justify left bottom))
    )
    (fp_text user "License: Apache-2.0" (at -1.682 5.895 180) (layer "F.Fab") hide
        (effects (font (size 0.7 0.7) (thickness 0.15)) (justify left bottom))
    )
    (fp_line (start -0.3 -0.3) (end 0.3 -0.3)
      (stroke (width 0.15) (type solid)) (layer "F.SilkS"))
    (fp_line (start -0.3 0.3) (end 0.3 0.3)
      (stroke (width 0.15) (type solid)) (layer "F.SilkS"))
    (fp_rect (start -1.24 -0.7) (end 1.24 0.7)
      (stroke (width 0.05) (type solid)) (fill none) (layer "F.CrtYd"))
    (fp_rect (start -0.8 -0.4) (end 0.8 0.4)
      (stroke (width 0.15) (type solid)) (fill none) (layer "F.Fab"))
    (pad "1" smd roundrect (at -0.7 0 180) (size 0.6 0.8) (layers "F.Cu" "F.Paste" "F.Mask") (roundrect_rratio 0.2)
      (net 4 "Net-(U10-TADJ)") (pintype "passive"))
    (pad "2" smd roundrect (at 0.7 0 180) (size 0.6 0.8) (layers "F.Cu" "F.Paste" "F.Mask") (roundrect_rratio 0.2)
      (net 9 "GND") (pintype "passive"))
  )

  (footprint "data-center-rdimm-ddr4-tester-footprints:C_0402_1005Metric" (layer "F.Cu")
    (at 136.786328 93.010008)
    (descr "Capacitor SMD 0402")
    (tags "capacitor SMD 0402")
    (property "Author" "Antmicro")
    (property "Dielectric" "X5R")
    (property "License" "Apache-2.0")
    (property "MPN" "GRM155R61H104KE14D")
    (property "Manufacturer" "Murata")
    (property "Sheetfile" "supply.kicad_sch")
    (property "Sheetname" "Supply")
    (property "Val" "100n")
    (property "Voltage" "50V")
    (property "ki_description" " ")
    (attr smd)
    (fp_text reference "C101" (at -1.136328 -0.480008) (layer "F.SilkS")
        (effects (font (size 0.7 0.7) (thickness 0.15)) (justify left bottom))
    )
    (fp_text value "C_100n_0402" (at 0 1.4) (layer "F.Fab") hide
        (effects (font (size 0.7 0.7) (thickness 0.15)) (justify left bottom))
    )
    (fp_text user "${REFERENCE}" (at -0.932 3.168) (layer "F.Fab") hide
        (effects (font (size 0.7 0.7) (thickness 0.15)) (justify left bottom))
    )
    (fp_text user "License: Apache-2.0" (at -0.932 5.17) (layer "F.Fab") hide
        (effects (font (size 0.7 0.7) (thickness 0.15)) (justify left bottom))
    )
    (fp_text user "Author: Antmicro" (at -0.932 4.17) (layer "F.Fab") hide
        (effects (font (size 0.7 0.7) (thickness 0.15)) (justify left bottom))
    )
    (fp_rect (start -0.94 -0.47) (end 0.94 0.47)
      (stroke (width 0.05) (type solid)) (fill none) (layer "F.CrtYd"))
    (fp_rect (start -0.499 -0.249) (end 0.499 0.249)
      (stroke (width 0.15) (type solid)) (fill none) (layer "F.Fab"))
    (pad "1" smd roundrect (at -0.484 0) (size 0.59 0.64) (layers "F.Cu" "F.Paste" "F.Mask") (roundrect_rratio 0.25)
      (net 307 "5V0_SYS") (pintype "passive"))
    (pad "2" smd roundrect (at 0.484 0) (size 0.59 0.64) (layers "F.Cu" "F.Paste" "F.Mask") (roundrect_rratio 0.25)
      (net 9 "GND") (pintype "passive"))
  )

  (footprint "data-center-rdimm-ddr4-tester-footprints:R_0402_1005Metric" (layer "F.Cu")
    (at 136.5 98.25)
    (descr "Resistor SMD 0402")
    (tags "resistor SMD 0402")
    (property "Author" "Antmicro")
    (property "Current" "1A")
    (property "License" "Apache-2.0")
    (property "MPN" "ERJ2GE0R00X")
    (property "Manufacturer" "Panasonic")
    (property "Sheetfile" "supply.kicad_sch")
    (property "Sheetname" "Supply")
    (property "Tolerance" "")
    (property "Val" "0R")
    (property "ki_description" "0R resistor in 0402 package with unspecified tolerance")
    (attr smd)
    (fp_text reference "R55" (at -1.14 1.27) (layer "F.SilkS")
        (effects (font (size 0.7 0.7) (thickness 0.15)) (justify left bottom))
    )
    (fp_text value "R_0R_0402" (at 0 1.4) (layer "F.Fab") hide
        (effects (font (size 0.7 0.7) (thickness 0.15)) (justify left bottom))
    )
    (fp_text user "License: Apache-2.0" (at -0.95 5.169) (layer "F.Fab") hide
        (effects (font (size 0.7 0.7) (thickness 0.15)) (justify left bottom))
    )
    (fp_text user "${REFERENCE}" (at -0.95 3.168) (layer "F.Fab") hide
        (effects (font (size 0.7 0.7) (thickness 0.15)) (justify left bottom))
    )
    (fp_text user "Author: Antmicro" (at -0.95 4.169) (layer "F.Fab") hide
        (effects (font (size 0.7 0.7) (thickness 0.15)) (justify left bottom))
    )
    (fp_rect (start -0.93 -0.47) (end 0.93 0.47)
      (stroke (width 0.05) (type solid)) (fill none) (layer "F.CrtYd"))
    (fp_rect (start -0.5 -0.25) (end 0.5 0.25)
      (stroke (width 0.15) (type solid)) (fill none) (layer "F.Fab"))
    (pad "1" smd roundrect (at -0.485 0) (size 0.59 0.64) (layers "F.Cu" "F.Paste" "F.Mask") (roundrect_rratio 0.25)
      (net 649 "Net-(U10-INV)") (pintype "passive"))
    (pad "2" smd roundrect (at 0.485 0) (size 0.59 0.64) (layers "F.Cu" "F.Paste" "F.Mask") (roundrect_rratio 0.25)
      (net 9 "GND") (pintype "passive"))
  )

  (footprint "data-center-rdimm-ddr4-tester-footprints:Testpoint_smd_1mm" (layer "F.Cu")
    (at 142.625 93.8008)
    (property "Author" "Antmicro")
    (property "License" "Apache-2.0")
    (property "MPN" "")
    (property "Manufacturer" "")
    (property "Sheetfile" "supply.kicad_sch")
    (property "Sheetname" "Supply")
    (property "ki_description" "Test Point 1mm")
    (attr exclude_from_pos_files)
    (fp_text reference "TP6" (at 0.445 0.3292) (layer "F.SilkS")
        (effects (font (size 0.7 0.7) (thickness 0.15)) (justify left bottom))
    )
    (fp_text value "TP_1mm_SMD" (at 0 1.4) (layer "F.Fab") hide
        (effects (font (size 0.7 0.7) (thickness 0.15)) (justify left bottom))
    )
    (fp_text user "License: Apache-2.0" (at -0.5 5.2) (layer "F.Fab") hide
        (effects (font (size 0.7 0.7) (thickness 0.15)) (justify left bottom))
    )
    (fp_text user "${REFERENCE}" (at -0.5 2.8) (layer "F.Fab") hide
        (effects (font (size 0.7 0.7) (thickness 0.15)) (justify left bottom))
    )
    (fp_text user "Author: Antmicro" (at -0.5 4) (layer "F.Fab") hide
        (effects (font (size 0.7 0.7) (thickness 0.15)) (justify left bottom))
    )
    (pad "1" smd circle (at 0 0) (size 1 1) (layers "F.Cu" "F.Mask")
      (net 151 "/Supply/VCC_INT_EN") (pinfunction "1") (pintype "passive"))
  )

  (footprint "data-center-rdimm-ddr4-tester-footprints:Testpoint_smd_1mm" (layer "F.Cu")
    (at 142.625 95.25)
    (property "Author" "Antmicro")
    (property "License" "Apache-2.0")
    (property "MPN" "")
    (property "Manufacturer" "")
    (property "Sheetfile" "supply.kicad_sch")
    (property "Sheetname" "Supply")
    (property "ki_description" "Test Point 1mm")
    (attr exclude_from_pos_files)
    (fp_text reference "TP7" (at 0.505 0.44) (layer "F.SilkS")
        (effects (font (size 0.7 0.7) (thickness 0.15)) (justify left bottom))
    )
    (fp_text value "TP_1mm_SMD" (at 0 1.4) (layer "F.Fab") hide
        (effects (font (size 0.7 0.7) (thickness 0.15)) (justify left bottom))
    )
    (fp_text user "Author: Antmicro" (at -0.5 4) (layer "F.Fab") hide
        (effects (font (size 0.7 0.7) (thickness 0.15)) (justify left bottom))
    )
    (fp_text user "${REFERENCE}" (at -0.5 2.8) (layer "F.Fab") hide
        (effects (font (size 0.7 0.7) (thickness 0.15)) (justify left bottom))
    )
    (fp_text user "License: Apache-2.0" (at -0.5 5.2) (layer "F.Fab") hide
        (effects (font (size 0.7 0.7) (thickness 0.15)) (justify left bottom))
    )
    (pad "1" smd circle (at 0 0) (size 1 1) (layers "F.Cu" "F.Mask")
      (net 152 "/Supply/VCC_AUX_EN") (pinfunction "1") (pintype "passive"))
  )

  (footprint "data-center-rdimm-ddr4-tester-footprints:VSSOP-8_3x3mm_P0.65mm" (layer "F.Cu")
    (at 138.125 95.5)
    (property "Author" "Antmicro")
    (property "License" "Apache-2.0")
    (property "MPN" "LM3881MME/NOPB")
    (property "Manufacturer" "Texas Instruments")
    (property "Sheetfile" "supply.kicad_sch")
    (property "Sheetname" "Supply")
    (property "ki_description" "LM3881MME/NOPB")
    (attr smd)
    (fp_text reference "U10" (at -0.495 -1.92) (layer "F.SilkS")
        (effects (font (size 0.7 0.7) (thickness 0.15)) (justify left bottom))
    )
    (fp_text value "LM3881MME_NOPB" (at 0 2.9) (layer "F.Fab") hide
        (effects (font (size 0.7 0.7) (thickness 0.15)) (justify left bottom))
    )
    (fp_text user "License: Apache-2.0" (at -0.352 8.371) (layer "F.Fab") hide
        (effects (font (size 0.7 0.7) (thickness 0.15)) (justify left bottom))
    )
    (fp_text user "Author: Antmicro" (at -0.352 7.171) (layer "F.Fab") hide
        (effects (font (size 0.7 0.7) (thickness 0.15)) (justify left bottom))
    )
    (fp_text user "${REFERENCE}" (at -0.352 5.972) (layer "F.Fab") hide
        (effects (font (size 0.7 0.7) (thickness 0.15)) (justify left bottom))
    )
    (fp_line (start -1.6 -1.625) (end 1.554 -1.625)
      (stroke (width 0.12) (type solid)) (layer "F.SilkS"))
    (fp_line (start -1.496 1.625) (end 1.554 1.625)
      (stroke (width 0.12) (type solid)) (layer "F.SilkS"))
    (fp_circle (center -2.1 -1.438) (end -2.05 -1.438)
      (stroke (width 0.12) (type solid)) (fill solid) (layer "F.SilkS"))
    (fp_rect (start -3 -1.838) (end 3 1.862)
      (stroke (width 0.05) (type solid)) (fill none) (layer "F.CrtYd"))
    (fp_line (start -1.497 -1.502) (end 1.504 -1.502)
      (stroke (width 0.15) (type solid)) (layer "F.Fab"))
    (fp_line (start -1.497 1.5) (end -1.497 -1.502)
      (stroke (width 0.15) (type solid)) (layer "F.Fab"))
    (fp_line (start 1.504 -1.502) (end 1.504 1.5)
      (stroke (width 0.15) (type solid)) (layer "F.Fab"))
    (fp_line (start 1.504 1.5) (end -1.497 1.5)
      (stroke (width 0.15) (type solid)) (layer "F.Fab"))
    (pad "1" smd rect (at -2.096 -0.975) (size 1.556504 0.457986) (layers "F.Cu" "F.Paste" "F.Mask")
      (net 307 "5V0_SYS") (pinfunction "VCC") (pintype "power_in"))
    (pad "2" smd roundrect (at -2.096 -0.326) (size 1.556504 0.457986) (layers "F.Cu" "F.Paste" "F.Mask") (roundrect_rratio 0.5)
      (net 790 "/Supply/PWR_SEQ_EN") (pinfunction "EN") (pintype "passive"))
    (pad "3" smd roundrect (at -2.096 0.325) (size 1.556504 0.457986) (layers "F.Cu" "F.Paste" "F.Mask") (roundrect_rratio 0.5)
      (net 9 "GND") (pinfunction "GND") (pintype "power_in"))
    (pad "4" smd roundrect (at -2.096 0.974) (size 1.556504 0.457986) (layers "F.Cu" "F.Paste" "F.Mask") (roundrect_rratio 0.5)
      (net 649 "Net-(U10-INV)") (pinfunction "INV") (pintype "input"))
    (pad "5" smd roundrect (at 2.105 0.974) (size 1.556504 0.457986) (layers "F.Cu" "F.Paste" "F.Mask") (roundrect_rratio 0.5)
      (net 4 "Net-(U10-TADJ)") (pinfunction "TADJ") (pintype "passive"))
    (pad "6" smd roundrect (at 2.105 0.325) (size 1.556504 0.457986) (layers "F.Cu" "F.Paste" "F.Mask") (roundrect_rratio 0.5)
      (net 153 "/Supply/VCC_IO_EN") (pinfunction "FLAG3") (pintype "open_collector"))
    (pad "7" smd roundrect (at 2.105 -0.326) (size 1.556504 0.457986) (layers "F.Cu" "F.Paste" "F.Mask") (roundrect_rratio 0.5)
      (net 152 "/Supply/VCC_AUX_EN") (pinfunction "FLAG2") (pintype "open_collector"))
    (pad "8" smd roundrect (at 2.105 -0.975) (size 1.556504 0.457986) (layers "F.Cu" "F.Paste" "F.Mask") (roundrect_rratio 0.5)
      (net 151 "/Supply/VCC_INT_EN") (pinfunction "FLAG1") (pintype "open_collector"))
  )

  (footprint "data-center-rdimm-ddr4-tester-footprints:R_0402_1005Metric" (layer "F.Cu")
    (at 222.432 115.731)
    (descr "Resistor SMD 0402")
    (tags "resistor SMD 0402")
    (property "Author" "Antmicro")
    (property "License" "Apache-2.0")
    (property "MPN" "CR0402-FX-2201GLF")
    (property "Manufacturer" "Bourns")
    (property "Sheetfile" "config-spi.kicad_sch")
    (property "Sheetname" "Config SPI flash")
    (property "Tolerance" "1%")
    (property "Val" "2k2")
    (property "ki_description" "2k2 resistor in 0402 package with 1% tolerance")
    (attr smd)
    (fp_text reference "R14" (at -1.152 -0.431) (layer "F.SilkS")
        (effects (font (size 0.7 0.7) (thickness 0.15)) (justify left bottom))
    )
    (fp_text value "R_2k2_0402" (at 0 1.4) (layer "F.Fab") hide
        (effects (font (size 0.7 0.7) (thickness 0.15)) (justify left bottom))
    )
    (fp_text user "${REFERENCE}" (at -0.95 3.168) (layer "F.Fab") hide
        (effects (font (size 0.7 0.7) (thickness 0.15)) (justify left bottom))
    )
    (fp_text user "License: Apache-2.0" (at -0.95 5.169) (layer "F.Fab") hide
        (effects (font (size 0.7 0.7) (thickness 0.15)) (justify left bottom))
    )
    (fp_text user "Author: Antmicro" (at -0.95 4.169) (layer "F.Fab") hide
        (effects (font (size 0.7 0.7) (thickness 0.15)) (justify left bottom))
    )
    (fp_rect (start -0.93 -0.47) (end 0.93 0.47)
      (stroke (width 0.05) (type solid)) (fill none) (layer "F.CrtYd"))
    (fp_rect (start -0.5 -0.25) (end 0.5 0.25)
      (stroke (width 0.15) (type solid)) (fill none) (layer "F.Fab"))
    (pad "1" smd roundrect (at -0.485 0) (size 0.59 0.64) (layers "F.Cu" "F.Paste" "F.Mask") (roundrect_rratio 0.25)
      (net 143 "3V3_SYS") (pintype "passive"))
    (pad "2" smd roundrect (at 0.485 0) (size 0.59 0.64) (layers "F.Cu" "F.Paste" "F.Mask") (roundrect_rratio 0.25)
      (net 95 "FCS_B") (pintype "passive"))
  )

  (footprint "data-center-rdimm-ddr4-tester-footprints:R_0402_1005Metric" (layer "F.Cu")
    (at 137.325 121.315 90)
    (descr "Resistor SMD 0402")
    (tags "resistor SMD 0402")
    (property "Author" "Antmicro")
    (property "License" "Apache-2.0")
    (property "MPN" "CR0402-FX-2002GLF")
    (property "Manufacturer" "Bourns")
    (property "Sheetfile" "interfaces.kicad_sch")
    (property "Sheetname" "Interfaces")
    (property "Tolerance" "1%")
    (property "Val" "20k")
    (property "ki_description" "20k resistor in 0402 package with 1% tolerance")
    (attr smd)
    (fp_text reference "R133" (at -3.685 0.335 90) (layer "F.SilkS")
        (effects (font (size 0.7 0.7) (thickness 0.15)) (justify left bottom))
    )
    (fp_text value "R_20k_0402" (at 0 1.4 90) (layer "F.Fab") hide
        (effects (font (size 0.7 0.7) (thickness 0.15)) (justify left bottom))
    )
    (fp_text user "Author: Antmicro" (at -0.95 4.169 90) (layer "F.Fab") hide
        (effects (font (size 0.7 0.7) (thickness 0.15)) (justify left bottom))
    )
    (fp_text user "License: Apache-2.0" (at -0.95 5.169 90) (layer "F.Fab") hide
        (effects (font (size 0.7 0.7) (thickness 0.15)) (justify left bottom))
    )
    (fp_text user "${REFERENCE}" (at -0.95 3.168 90) (layer "F.Fab") hide
        (effects (font (size 0.7 0.7) (thickness 0.15)) (justify left bottom))
    )
    (fp_rect (start -0.93 -0.47) (end 0.93 0.47)
      (stroke (width 0.05) (type solid)) (fill none) (layer "F.CrtYd"))
    (fp_rect (start -0.5 -0.25) (end 0.5 0.25)
      (stroke (width 0.15) (type solid)) (fill none) (layer "F.Fab"))
    (pad "1" smd roundrect (at -0.485 0 90) (size 0.59 0.64) (layers "F.Cu" "F.Paste" "F.Mask") (roundrect_rratio 0.25)
      (net 143 "3V3_SYS") (pintype "passive"))
    (pad "2" smd roundrect (at 0.485 0 90) (size 0.59 0.64) (layers "F.Cu" "F.Paste" "F.Mask") (roundrect_rratio 0.25)
      (net 83 "SD_DAT0") (pintype "passive"))
  )

  (footprint "data-center-rdimm-ddr4-tester-footprints:R_0402_1005Metric" (layer "F.Cu")
    (at 131.8 121.325 90)
    (descr "Resistor SMD 0402")
    (tags "resistor SMD 0402")
    (property "Author" "Antmicro")
    (property "License" "Apache-2.0")
    (property "MPN" "CR0402-FX-2002GLF")
    (property "Manufacturer" "Bourns")
    (property "Sheetfile" "interfaces.kicad_sch")
    (property "Sheetname" "Interfaces")
    (property "Tolerance" "1%")
    (property "Val" "20k")
    (property "ki_description" "20k resistor in 0402 package with 1% tolerance")
    (attr smd)
    (fp_text reference "R137" (at -3.675 0.35 90) (layer "F.SilkS")
        (effects (font (size 0.7 0.7) (thickness 0.15)) (justify left bottom))
    )
    (fp_text value "R_20k_0402" (at 0 1.4 90) (layer "F.Fab") hide
        (effects (font (size 0.7 0.7) (thickness 0.15)) (justify left bottom))
    )
    (fp_text user "License: Apache-2.0" (at -0.95 5.169 90) (layer "F.Fab") hide
        (effects (font (size 0.7 0.7) (thickness 0.15)) (justify left bottom))
    )
    (fp_text user "${REFERENCE}" (at -0.95 3.168 90) (layer "F.Fab") hide
        (effects (font (size 0.7 0.7) (thickness 0.15)) (justify left bottom))
    )
    (fp_text user "Author: Antmicro" (at -0.95 4.169 90) (layer "F.Fab") hide
        (effects (font (size 0.7 0.7) (thickness 0.15)) (justify left bottom))
    )
    (fp_rect (start -0.93 -0.47) (end 0.93 0.47)
      (stroke (width 0.05) (type solid)) (fill none) (layer "F.CrtYd"))
    (fp_rect (start -0.5 -0.25) (end 0.5 0.25)
      (stroke (width 0.15) (type solid)) (fill none) (layer "F.Fab"))
    (pad "1" smd roundrect (at -0.485 0 90) (size 0.59 0.64) (layers "F.Cu" "F.Paste" "F.Mask") (roundrect_rratio 0.25)
      (net 143 "3V3_SYS") (pintype "passive"))
    (pad "2" smd roundrect (at 0.485 0 90) (size 0.59 0.64) (layers "F.Cu" "F.Paste" "F.Mask") (roundrect_rratio 0.25)
      (net 86 "SD_DAT3") (pintype "passive"))
  )

  (footprint "data-center-rdimm-ddr4-tester-footprints:R_0402_1005Metric" (layer "F.Cu")
    (at 130.7 121.325 90)
    (descr "Resistor SMD 0402")
    (tags "resistor SMD 0402")
    (property "Author" "Antmicro")
    (property "License" "Apache-2.0")
    (property "MPN" "CR0402-FX-2002GLF")
    (property "Manufacturer" "Bourns")
    (property "Sheetfile" "interfaces.kicad_sch")
    (property "Sheetname" "Interfaces")
    (property "Tolerance" "1%")
    (property "Val" "20k")
    (property "ki_description" "20k resistor in 0402 package with 1% tolerance")
    (attr smd)
    (fp_text reference "R138" (at -3.675 0.35 90) (layer "F.SilkS")
        (effects (font (size 0.7 0.7) (thickness 0.15)) (justify left bottom))
    )
    (fp_text value "R_20k_0402" (at 0 1.4 90) (layer "F.Fab") hide
        (effects (font (size 0.7 0.7) (thickness 0.15)) (justify left bottom))
    )
    (fp_text user "Author: Antmicro" (at -0.95 4.169 90) (layer "F.Fab") hide
        (effects (font (size 0.7 0.7) (thickness 0.15)) (justify left bottom))
    )
    (fp_text user "${REFERENCE}" (at -0.95 3.168 90) (layer "F.Fab") hide
        (effects (font (size 0.7 0.7) (thickness 0.15)) (justify left bottom))
    )
    (fp_text user "License: Apache-2.0" (at -0.95 5.169 90) (layer "F.Fab") hide
        (effects (font (size 0.7 0.7) (thickness 0.15)) (justify left bottom))
    )
    (fp_rect (start -0.93 -0.47) (end 0.93 0.47)
      (stroke (width 0.05) (type solid)) (fill none) (layer "F.CrtYd"))
    (fp_rect (start -0.5 -0.25) (end 0.5 0.25)
      (stroke (width 0.15) (type solid)) (fill none) (layer "F.Fab"))
    (pad "1" smd roundrect (at -0.485 0 90) (size 0.59 0.64) (layers "F.Cu" "F.Paste" "F.Mask") (roundrect_rratio 0.25)
      (net 143 "3V3_SYS") (pintype "passive"))
    (pad "2" smd roundrect (at 0.485 0 90) (size 0.59 0.64) (layers "F.Cu" "F.Paste" "F.Mask") (roundrect_rratio 0.25)
      (net 87 "SD_DAT2") (pintype "passive"))
  )

  (footprint "data-center-rdimm-ddr4-tester-footprints:C_0402_1005Metric" (layer "F.Cu")
    (at 138.286328 113.969157 180)
    (descr "Capacitor SMD 0402")
    (tags "capacitor SMD 0402")
    (property "Author" "Antmicro")
    (property "Dielectric" "X5R")
    (property "License" "Apache-2.0")
    (property "MPN" "GRM155R61H104KE14D")
    (property "Manufacturer" "Murata")
    (property "Sheetfile" "interfaces.kicad_sch")
    (property "Sheetname" "Interfaces")
    (property "Val" "100n")
    (property "Voltage" "50V")
    (property "ki_description" " ")
    (attr smd)
    (fp_text reference "C185" (at 1.936328 1.539157 180) (layer "F.SilkS")
        (effects (font (size 0.7 0.7) (thickness 0.15)) (justify left bottom))
    )
    (fp_text value "C_100n_0402" (at 0 1.4 180) (layer "F.Fab") hide
        (effects (font (size 0.7 0.7) (thickness 0.15)) (justify left bottom))
    )
    (fp_text user "Author: Antmicro" (at -0.932 4.17 180) (layer "F.Fab") hide
        (effects (font (size 0.7 0.7) (thickness 0.15)) (justify left bottom))
    )
    (fp_text user "${REFERENCE}" (at -0.932 3.168 180) (layer "F.Fab") hide
        (effects (font (size 0.7 0.7) (thickness 0.15)) (justify left bottom))
    )
    (fp_text user "License: Apache-2.0" (at -0.932 5.17 180) (layer "F.Fab") hide
        (effects (font (size 0.7 0.7) (thickness 0.15)) (justify left bottom))
    )
    (fp_rect (start -0.94 -0.47) (end 0.94 0.47)
      (stroke (width 0.05) (type solid)) (fill none) (layer "F.CrtYd"))
    (fp_rect (start -0.499 -0.249) (end 0.499 0.249)
      (stroke (width 0.15) (type solid)) (fill none) (layer "F.Fab"))
    (pad "1" smd roundrect (at -0.484 0 180) (size 0.59 0.64) (layers "F.Cu" "F.Paste" "F.Mask") (roundrect_rratio 0.25)
      (net 76 "Net-(U7-V_{PHY})") (pintype "passive"))
    (pad "2" smd roundrect (at 0.484 0 180) (size 0.59 0.64) (layers "F.Cu" "F.Paste" "F.Mask") (roundrect_rratio 0.25)
      (net 9 "GND") (pintype "passive"))
  )

  (footprint "data-center-rdimm-ddr4-tester-footprints:C_0402_1005Metric" (layer "F.Cu")
    (at 133.936328 104.832157 180)
    (descr "Capacitor SMD 0402")
    (tags "capacitor SMD 0402")
    (property "Author" "Antmicro")
    (property "Dielectric" "X5R")
    (property "License" "Apache-2.0")
    (property "MPN" "GRM155R61H104KE14D")
    (property "Manufacturer" "Murata")
    (property "Sheetfile" "interfaces.kicad_sch")
    (property "Sheetname" "Interfaces")
    (property "Val" "100n")
    (property "Voltage" "50V")
    (property "ki_description" " ")
    (attr smd)
    (fp_text reference "C188" (at 3.706328 -0.377843 180) (layer "F.SilkS")
        (effects (font (size 0.7 0.7) (thickness 0.15)) (justify left bottom))
    )
    (fp_text value "C_100n_0402" (at 0 1.4 180) (layer "F.Fab") hide
        (effects (font (size 0.7 0.7) (thickness 0.15)) (justify left bottom))
    )
    (fp_text user "${REFERENCE}" (at -0.932 3.168 180) (layer "F.Fab") hide
        (effects (font (size 0.7 0.7) (thickness 0.15)) (justify left bottom))
    )
    (fp_text user "Author: Antmicro" (at -0.932 4.17 180) (layer "F.Fab") hide
        (effects (font (size 0.7 0.7) (thickness 0.15)) (justify left bottom))
    )
    (fp_text user "License: Apache-2.0" (at -0.932 5.17 180) (layer "F.Fab") hide
        (effects (font (size 0.7 0.7) (thickness 0.15)) (justify left bottom))
    )
    (fp_rect (start -0.94 -0.47) (end 0.94 0.47)
      (stroke (width 0.05) (type solid)) (fill none) (layer "F.CrtYd"))
    (fp_rect (start -0.499 -0.249) (end 0.499 0.249)
      (stroke (width 0.15) (type solid)) (fill none) (layer "F.Fab"))
    (pad "1" smd roundrect (at -0.484 0 180) (size 0.59 0.64) (layers "F.Cu" "F.Paste" "F.Mask") (roundrect_rratio 0.25)
      (net 143 "3V3_SYS") (pintype "passive"))
    (pad "2" smd roundrect (at 0.484 0 180) (size 0.59 0.64) (layers "F.Cu" "F.Paste" "F.Mask") (roundrect_rratio 0.25)
      (net 9 "GND") (pintype "passive"))
  )

  (footprint "data-center-rdimm-ddr4-tester-footprints:C_0402_1005Metric" (layer "F.Cu")
    (at 133.936328 103.752157 180)
    (descr "Capacitor SMD 0402")
    (tags "capacitor SMD 0402")
    (property "Author" "Antmicro")
    (property "Dielectric" "X5R")
    (property "License" "Apache-2.0")
    (property "MPN" "GRM155R61H104KE14D")
    (property "Manufacturer" "Murata")
    (property "Sheetfile" "interfaces.kicad_sch")
    (property "Sheetname" "Interfaces")
    (property "Val" "100n")
    (property "Voltage" "50V")
    (property "ki_description" " ")
    (attr smd)
    (fp_text reference "C197" (at 3.706328 -0.377843 180) (layer "F.SilkS")
        (effects (font (size 0.7 0.7) (thickness 0.15)) (justify left bottom))
    )
    (fp_text value "C_100n_0402" (at 0 1.4 180) (layer "F.Fab") hide
        (effects (font (size 0.7 0.7) (thickness 0.15)) (justify left bottom))
    )
    (fp_text user "${REFERENCE}" (at -0.932 3.168 180) (layer "F.Fab") hide
        (effects (font (size 0.7 0.7) (thickness 0.15)) (justify left bottom))
    )
    (fp_text user "License: Apache-2.0" (at -0.932 5.17 180) (layer "F.Fab") hide
        (effects (font (size 0.7 0.7) (thickness 0.15)) (justify left bottom))
    )
    (fp_text user "Author: Antmicro" (at -0.932 4.17 180) (layer "F.Fab") hide
        (effects (font (size 0.7 0.7) (thickness 0.15)) (justify left bottom))
    )
    (fp_rect (start -0.94 -0.47) (end 0.94 0.47)
      (stroke (width 0.05) (type solid)) (fill none) (layer "F.CrtYd"))
    (fp_rect (start -0.499 -0.249) (end 0.499 0.249)
      (stroke (width 0.15) (type solid)) (fill none) (layer "F.Fab"))
    (pad "1" smd roundrect (at -0.484 0 180) (size 0.59 0.64) (layers "F.Cu" "F.Paste" "F.Mask") (roundrect_rratio 0.25)
      (net 145 "1V8_FT") (pintype "passive"))
    (pad "2" smd roundrect (at 0.484 0 180) (size 0.59 0.64) (layers "F.Cu" "F.Paste" "F.Mask") (roundrect_rratio 0.25)
      (net 9 "GND") (pintype "passive"))
  )

  (footprint "data-center-rdimm-ddr4-tester-footprints:R_0402_1005Metric" (layer "F.Cu")
    (at 118.711328 96.285008 90)
    (descr "Resistor SMD 0402")
    (tags "resistor SMD 0402")
    (property "Author" "Antmicro")
    (property "License" "Apache-2.0")
    (property "MPN" "CR0402-FX-5R10GLF")
    (property "Manufacturer" "Bourns")
    (property "Sheetfile" "supply.kicad_sch")
    (property "Sheetname" "Supply")
    (property "Tolerance" "1%")
    (property "Val" "5R1")
    (property "ki_description" "5R1 resistor in 0402 package with 1% tolerance")
    (attr smd)
    (fp_text reference "R35" (at -1.064992 -0.511328 90) (layer "F.SilkS")
        (effects (font (size 0.7 0.7) (thickness 0.15)) (justify left bottom))
    )
    (fp_text value "R_5R1_0402" (at 0 1.4 90) (layer "F.Fab") hide
        (effects (font (size 0.7 0.7) (thickness 0.15)) (justify left bottom))
    )
    (fp_text user "License: Apache-2.0" (at -0.95 5.169 90) (layer "F.Fab") hide
        (effects (font (size 0.7 0.7) (thickness 0.15)) (justify left bottom))
    )
    (fp_text user "Author: Antmicro" (at -0.95 4.169 90) (layer "F.Fab") hide
        (effects (font (size 0.7 0.7) (thickness 0.15)) (justify left bottom))
    )
    (fp_text user "${REFERENCE}" (at -0.95 3.168 90) (layer "F.Fab") hide
        (effects (font (size 0.7 0.7) (thickness 0.15)) (justify left bottom))
    )
    (fp_rect (start -0.93 -0.47) (end 0.93 0.47)
      (stroke (width 0.05) (type solid)) (fill none) (layer "F.CrtYd"))
    (fp_rect (start -0.5 -0.25) (end 0.5 0.25)
      (stroke (width 0.15) (type solid)) (fill none) (layer "F.Fab"))
    (pad "1" smd roundrect (at -0.485 0 90) (size 0.59 0.64) (layers "F.Cu" "F.Paste" "F.Mask") (roundrect_rratio 0.25)
      (net 601 "Net-(U2-BST)") (pintype "passive"))
    (pad "2" smd roundrect (at 0.485 0 90) (size 0.59 0.64) (layers "F.Cu" "F.Paste" "F.Mask") (roundrect_rratio 0.25)
      (net 105 "Net-(C35-Pad1)") (pintype "passive"))
  )

  (footprint "data-center-rdimm-ddr4-tester-footprints:Testpoint_smd_1mm" (layer "F.Cu")
    (at 142.5 96.875)
    (property "Author" "Antmicro")
    (property "License" "Apache-2.0")
    (property "MPN" "")
    (property "Manufacturer" "")
    (property "Sheetfile" "supply.kicad_sch")
    (property "Sheetname" "Supply")
    (property "ki_description" "Test Point 1mm")
    (attr exclude_from_pos_files)
    (fp_text reference "TP8" (at 0.52 0.385) (layer "F.SilkS")
        (effects (font (size 0.7 0.7) (thickness 0.15)) (justify left bottom))
    )
    (fp_text value "TP_1mm_SMD" (at 0 1.4) (layer "F.Fab") hide
        (effects (font (size 0.7 0.7) (thickness 0.15)) (justify left bottom))
    )
    (fp_text user "${REFERENCE}" (at -0.5 2.8) (layer "F.Fab") hide
        (effects (font (size 0.7 0.7) (thickness 0.15)) (justify left bottom))
    )
    (fp_text user "License: Apache-2.0" (at -0.5 5.2) (layer "F.Fab") hide
        (effects (font (size 0.7 0.7) (thickness 0.15)) (justify left bottom))
    )
    (fp_text user "Author: Antmicro" (at -0.5 4) (layer "F.Fab") hide
        (effects (font (size 0.7 0.7) (thickness 0.15)) (justify left bottom))
    )
    (pad "1" smd circle (at 0 0) (size 1 1) (layers "F.Cu" "F.Mask")
      (net 153 "/Supply/VCC_IO_EN") (pinfunction "1") (pintype "passive"))
  )

  (footprint "data-center-rdimm-ddr4-tester-footprints:C_0402_1005Metric" (layer "F.Cu")
    (at 140.161328 100.212157 90)
    (descr "Capacitor SMD 0402")
    (tags "capacitor SMD 0402")
    (property "Author" "Antmicro")
    (property "Dielectric" "X5R")
    (property "License" "Apache-2.0")
    (property "MPN" "GRM155R61H104KE14D")
    (property "Manufacturer" "Murata")
    (property "Sheetfile" "interfaces.kicad_sch")
    (property "Sheetname" "Interfaces")
    (property "Val" "100n")
    (property "Voltage" "50V")
    (property "ki_description" " ")
    (attr smd)
    (fp_text reference "C192" (at -1.207843 -1.431328 90) (layer "F.SilkS")
        (effects (font (size 0.7 0.7) (thickness 0.15)) (justify left bottom))
    )
    (fp_text value "C_100n_0402" (at 0 1.4 90) (layer "F.Fab") hide
        (effects (font (size 0.7 0.7) (thickness 0.15)) (justify left bottom))
    )
    (fp_text user "License: Apache-2.0" (at -0.932 5.17 90) (layer "F.Fab") hide
        (effects (font (size 0.7 0.7) (thickness 0.15)) (justify left bottom))
    )
    (fp_text user "${REFERENCE}" (at -0.932 3.168 90) (layer "F.Fab") hide
        (effects (font (size 0.7 0.7) (thickness 0.15)) (justify left bottom))
    )
    (fp_text user "Author: Antmicro" (at -0.932 4.17 90) (layer "F.Fab") hide
        (effects (font (size 0.7 0.7) (thickness 0.15)) (justify left bottom))
    )
    (fp_rect (start -0.94 -0.47) (end 0.94 0.47)
      (stroke (width 0.05) (type solid)) (fill none) (layer "F.CrtYd"))
    (fp_rect (start -0.499 -0.249) (end 0.499 0.249)
      (stroke (width 0.15) (type solid)) (fill none) (layer "F.Fab"))
    (pad "1" smd roundrect (at -0.484 0 90) (size 0.59 0.64) (layers "F.Cu" "F.Paste" "F.Mask") (roundrect_rratio 0.25)
      (net 143 "3V3_SYS") (pintype "passive"))
    (pad "2" smd roundrect (at 0.484 0 90) (size 0.59 0.64) (layers "F.Cu" "F.Paste" "F.Mask") (roundrect_rratio 0.25)
      (net 9 "GND") (pintype "passive"))
  )

  (footprint "data-center-rdimm-ddr4-tester-footprints:PinHeader_1x3_P2.54mm_Drill1.1mm" (layer "F.Cu")
    (at 216.914328 120.547157 90)
    (property "Author" "Antmicro")
    (property "License" "Apache-2.0")
    (property "MPN" "61300311121")
    (property "Manufacturer" "Würth Elektronik")
    (property "Sheetfile" "supply.kicad_sch")
    (property "Sheetname" "Supply")
    (property "ki_description" "3x1 goldpin header")
    (property "ki_keywords" "3x1 goldpin header")
    (attr through_hole)
    (fp_text reference "J8" (at 6.755157 0.255672 180) (layer "F.SilkS")
        (effects (font (size 0.7 0.7) (thickness 0.15)) (justify left bottom))
    )
    (fp_text value "PinHeader_1x3_P2.54mm_Drill1.1mm" (at -1.6 2.7 90) (layer "F.Fab")
        (effects (font (size 0.7 0.7) (thickness 0.15)) (justify left bottom))
    )
    (fp_text user "License: Apache-2.0" (at -1.6 6.6 90) (layer "F.Fab") hide
        (effects (font (size 0.7 0.7) (thickness 0.15)) (justify left bottom))
    )
    (fp_text user "Author: Antmicro" (at -1.6 5.2 90) (layer "F.Fab") hide
        (effects (font (size 0.7 0.7) (thickness 0.15)) (justify left bottom))
    )
    (fp_text user "${REFERENCE}" (at -1.6 4 90) (layer "F.Fab") hide
        (effects (font (size 0.7 0.7) (thickness 0.15)) (justify left bottom))
    )
    (fp_line (start -1.401 -1.401) (end -1.401 -0.902)
      (stroke (width 0.15) (type solid)) (layer "F.SilkS"))
    (fp_line (start -1.401 -1.401) (end -0.902 -1.401)
      (stroke (width 0.15) (type solid)) (layer "F.SilkS"))
    (fp_line (start -1.401 1.398) (end -1.401 0.9)
      (stroke (width 0.15) (type solid)) (layer "F.SilkS"))
    (fp_line (start -1.401 1.398) (end -0.902 1.398)
      (stroke (width 0.15) (type solid)) (layer "F.SilkS"))
    (fp_line (start 6.499 -1.401) (end 5.999 -1.401)
      (stroke (width 0.15) (type solid)) (layer "F.SilkS"))
    (fp_line (start 6.499 -1.401) (end 6.499 -0.902)
      (stroke (width 0.15) (type solid)) (layer "F.SilkS"))
    (fp_line (start 6.499 1.398) (end 5.999 1.398)
      (stroke (width 0.15) (type solid)) (layer "F.SilkS"))
    (fp_line (start 6.499 1.398) (end 6.499 0.9)
      (stroke (width 0.15) (type solid)) (layer "F.SilkS"))
    (fp_line (start -1.52 -1.52) (end -1.52 1.5)
      (stroke (width 0.05) (type solid)) (layer "F.CrtYd"))
    (fp_line (start -1.52 -1.52) (end 6.58 -1.52)
      (stroke (width 0.05) (type solid)) (layer "F.CrtYd"))
    (fp_line (start -1.52 1.5) (end 6.58 1.5)
      (stroke (width 0.05) (type solid)) (layer "F.CrtYd"))
    (fp_line (start 6.58 -1.52) (end 6.58 1.5)
      (stroke (width 0.05) (type solid)) (layer "F.CrtYd"))
    (fp_line (start -1.27 -1.27) (end -1.27 1.269)
      (stroke (width 0.15) (type solid)) (layer "F.Fab"))
    (fp_line (start -1.27 -1.27) (end 6.349 -1.27)
      (stroke (width 0.15) (type solid)) (layer "F.Fab"))
    (fp_line (start -1.27 1.269) (end 6.349 1.269)
      (stroke (width 0.15) (type solid)) (layer "F.Fab"))
    (fp_line (start 6.349 -1.27) (end 6.349 1.269)
      (stroke (width 0.15) (type solid)) (layer "F.Fab"))
    (pad "1" thru_hole rect (at 0 0 90) (size 1.7 1.7) (drill 1.1) (layers "*.Cu" "*.Mask")
      (net 307 "5V0_SYS") (pintype "passive"))
    (pad "2" thru_hole circle (at 2.539 0 90) (size 1.7 1.7) (drill 1.1) (layers "*.Cu" "*.Mask")
      (net 383 "unconnected-(J8-Pad2)") (pintype "passive+no_connect"))
    (pad "3" thru_hole circle (at 5.078 0 90) (size 1.7 1.7) (drill 1.1) (layers "*.Cu" "*.Mask")
      (net 9 "GND") (pintype "passive"))
  )

  (footprint "data-center-rdimm-ddr4-tester-footprints:antmicro-logo_scaled_20mm_mask" (layer "F.Cu")
    (at 222.05 103.65)
    (descr "Antmicro Logo scaled 20mm F.Mask")
    (tags "Antmicro Logo scaled 20mm F.Mask")
    (property "Author" "Antmicro")
    (property "License" "Apache-2.0")
    (property "MPN" "")
    (property "Manufacturer" "")
    (property "Sheetfile" "data-center-rdimm-ddr4-tester.kicad_sch")
    (property "Sheetname" "")
    (attr through_hole exclude_from_pos_files)
    (fp_text reference "N2" (at 0.05 -5.5) (layer "F.SilkS") hide
        (effects (font (size 0.7 0.7) (thickness 0.15)) (justify left bottom))
    )
    (fp_text value "antmicro_logo" (at -0.101 5.099) (layer "F.SilkS") hide
        (effects (font (size 0.7 0.7) (thickness 0.15)) (justify left bottom))
    )
    (fp_text user "License: Apache-2.0" (at -9.998 9.099) (layer "F.Fab") hide
        (effects (font (size 0.7 0.7) (thickness 0.15)) (justify left bottom))
    )
    (fp_text user "Author: Antmicro" (at -9.998 8.099) (layer "F.Fab") hide
        (effects (font (size 0.7 0.7) (thickness 0.15)) (justify left bottom))
    )
    (fp_text user "${REFERENCE}" (at -9.998 7.099) (layer "F.Fab") hide
        (effects (font (size 0.7 0.7) (thickness 0.15)) (justify left bottom))
    )
    (fp_poly
      (pts
        (xy 5.212 0.944)
        (xy 4.834 0.944)
        (xy 4.834 -1.292)
        (xy 5.212 -1.292)
        (xy 5.212 0.944)
      )

      (stroke (width 0.00186) (type solid)) (fill solid) (layer "F.Mask"))
    (fp_poly
      (pts
        (xy 8.164 -1.321)
        (xy 8.193 -1.317)
        (xy 8.204 -1.31)
        (xy 8.204 -1.308)
        (xy 8.2 -1.285)
        (xy 8.188 -1.24)
        (xy 8.171 -1.181)
        (xy 8.163 -1.156)
        (xy 8.142 -1.092)
        (xy 8.126 -1.053)
        (xy 8.112 -1.034)
        (xy 8.097 -1.031)
        (xy 8.094 -1.032)
        (xy 7.996 -1.053)
        (xy 7.886 -1.06)
        (xy 7.778 -1.053)
        (xy 7.683 -1.032)
        (xy 7.665 -1.026)
        (xy 7.622 -1.009)
        (xy 7.622 0.944)
        (xy 7.244 0.944)
        (xy 7.244 -1.178)
        (xy 7.358 -1.219)
        (xy 7.457 -1.253)
        (xy 7.548 -1.277)
        (xy 7.639 -1.295)
        (xy 7.738 -1.307)
        (xy 7.856 -1.315)
        (xy 7.94 -1.319)
        (xy 8.042 -1.322)
        (xy 8.115 -1.322)
        (xy 8.164 -1.321)
      )

      (stroke (width 0.00186) (type solid)) (fill solid) (layer "F.Mask"))
    (fp_poly
      (pts
        (xy 0.795 -1.891)
        (xy 0.798 -1.849)
        (xy 0.8 -1.786)
        (xy 0.802 -1.705)
        (xy 0.803 -1.612)
        (xy 0.803 -1.599)
        (xy 0.803 -1.292)
        (xy 1.181 -1.292)
        (xy 1.181 -1.04)
        (xy 0.803 -1.04)
        (xy 0.803 0.498)
        (xy 0.838 0.566)
        (xy 0.885 0.631)
        (xy 0.944 0.671)
        (xy 1.021 0.688)
        (xy 1.082 0.689)
        (xy 1.181 0.685)
        (xy 1.181 0.806)
        (xy 1.178 0.88)
        (xy 1.17 0.926)
        (xy 1.161 0.939)
        (xy 1.138 0.945)
        (xy 1.09 0.95)
        (xy 1.028 0.954)
        (xy 0.984 0.956)
        (xy 0.897 0.957)
        (xy 0.832 0.953)
        (xy 0.778 0.942)
        (xy 0.743 0.931)
        (xy 0.647 0.886)
        (xy 0.571 0.823)
        (xy 0.508 0.737)
        (xy 0.488 0.701)
        (xy 0.433 0.593)
        (xy 0.428 -0.223)
        (xy 0.424 -1.04)
        (xy 0.173 -1.04)
        (xy 0.173 -1.292)
        (xy 0.425 -1.292)
        (xy 0.425 -1.795)
        (xy 0.603 -1.85)
        (xy 0.673 -1.872)
        (xy 0.733 -1.89)
        (xy 0.774 -1.902)
        (xy 0.792 -1.906)
        (xy 0.795 -1.891)
      )

      (stroke (width 0.00186) (type solid)) (fill solid) (layer "F.Mask"))
    (fp_poly
      (pts
        (xy -0.82 -1.315)
        (xy -0.737 -1.312)
        (xy -0.672 -1.308)
        (xy -0.621 -1.301)
        (xy -0.577 -1.291)
        (xy -0.56 -1.286)
        (xy -0.417 -1.232)
        (xy -0.302 -1.164)
        (xy -0.212 -1.082)
        (xy -0.154 -0.996)
        (xy -0.135 -0.961)
        (xy -0.119 -0.927)
        (xy -0.105 -0.893)
        (xy -0.094 -0.855)
        (xy -0.085 -0.811)
        (xy -0.078 -0.758)
        (xy -0.073 -0.693)
        (xy -0.069 -0.612)
        (xy -0.067 -0.515)
        (xy -0.065 -0.397)
        (xy -0.064 -0.256)
        (xy -0.064 -0.088)
        (xy -0.063 0.105)
        (xy -0.063 0.944)
        (xy -0.441 0.944)
        (xy -0.441 0.113)
        (xy -0.442 -0.083)
        (xy -0.442 -0.25)
        (xy -0.443 -0.391)
        (xy -0.445 -0.508)
        (xy -0.448 -0.604)
        (xy -0.452 -0.682)
        (xy -0.457 -0.744)
        (xy -0.465 -0.794)
        (xy -0.474 -0.833)
        (xy -0.486 -0.864)
        (xy -0.501 -0.89)
        (xy -0.518 -0.913)
        (xy -0.538 -0.937)
        (xy -0.539 -0.939)
        (xy -0.604 -0.997)
        (xy -0.684 -1.039)
        (xy -0.784 -1.066)
        (xy -0.822 -1.072)
        (xy -0.927 -1.078)
        (xy -1.044 -1.073)
        (xy -1.158 -1.056)
        (xy -1.24 -1.034)
        (xy -1.3 -1.013)
        (xy -1.304 -0.034)
        (xy -1.308 0.944)
        (xy -1.686 0.944)
        (xy -1.686 -1.178)
        (xy -1.54 -1.225)
        (xy -1.44 -1.257)
        (xy -1.354 -1.28)
        (xy -1.276 -1.297)
        (xy -1.195 -1.307)
        (xy -1.105 -1.313)
        (xy -0.995 -1.315)
        (xy -0.93 -1.315)
        (xy -0.82 -1.315)
      )

      (stroke (width 0.00186) (type solid)) (fill solid) (layer "F.Mask"))
    (fp_poly
      (pts
        (xy 3.757 -1.312)
        (xy 3.91 -1.278)
        (xy 4.043 -1.223)
        (xy 4.153 -1.146)
        (xy 4.24 -1.047)
        (xy 4.282 -0.977)
        (xy 4.299 -0.943)
        (xy 4.313 -0.91)
        (xy 4.325 -0.876)
        (xy 4.335 -0.837)
        (xy 4.343 -0.791)
        (xy 4.349 -0.734)
        (xy 4.353 -0.665)
        (xy 4.357 -0.581)
        (xy 4.359 -0.478)
        (xy 4.361 -0.354)
        (xy 4.361 -0.206)
        (xy 4.362 -0.031)
        (xy 4.362 0.111)
        (xy 4.362 0.944)
        (xy 3.985 0.944)
        (xy 3.98 0.074)
        (xy 3.976 -0.796)
        (xy 3.93 -0.879)
        (xy 3.867 -0.961)
        (xy 3.786 -1.022)
        (xy 3.691 -1.062)
        (xy 3.586 -1.079)
        (xy 3.476 -1.074)
        (xy 3.366 -1.045)
        (xy 3.26 -0.994)
        (xy 3.185 -0.938)
        (xy 3.118 -0.88)
        (xy 3.118 0.944)
        (xy 2.74 0.944)
        (xy 2.74 0.092)
        (xy 2.739 -0.122)
        (xy 2.739 -0.305)
        (xy 2.737 -0.459)
        (xy 2.735 -0.585)
        (xy 2.732 -0.683)
        (xy 2.729 -0.755)
        (xy 2.725 -0.802)
        (xy 2.722 -0.821)
        (xy 2.679 -0.91)
        (xy 2.613 -0.981)
        (xy 2.523 -1.034)
        (xy 2.413 -1.067)
        (xy 2.284 -1.079)
        (xy 2.154 -1.073)
        (xy 2.082 -1.064)
        (xy 2.031 -1.056)
        (xy 1.989 -1.046)
        (xy 1.944 -1.031)
        (xy 1.917 -1.021)
        (xy 1.874 -1.005)
        (xy 1.874 0.944)
        (xy 1.511 0.944)
        (xy 1.511 -1.18)
        (xy 1.661 -1.228)
        (xy 1.83 -1.276)
        (xy 1.988 -1.306)
        (xy 2.148 -1.319)
        (xy 2.314 -1.319)
        (xy 2.448 -1.311)
        (xy 2.557 -1.297)
        (xy 2.649 -1.272)
        (xy 2.732 -1.237)
        (xy 2.811 -1.189)
        (xy 2.843 -1.165)
        (xy 2.947 -1.087)
        (xy 3.012 -1.14)
        (xy 3.14 -1.224)
        (xy 3.283 -1.283)
        (xy 3.443 -1.315)
        (xy 3.582 -1.323)
        (xy 3.757 -1.312)
      )

      (stroke (width 0.00186) (type solid)) (fill solid) (layer "F.Mask"))
    (fp_poly
      (pts
        (xy 9.278 -1.313)
        (xy 9.419 -1.281)
        (xy 9.543 -1.225)
        (xy 9.656 -1.146)
        (xy 9.708 -1.097)
        (xy 9.808 -0.975)
        (xy 9.887 -0.831)
        (xy 9.945 -0.666)
        (xy 9.984 -0.476)
        (xy 9.998 -0.354)
        (xy 10.005 -0.134)
        (xy 9.992 0.072)
        (xy 9.96 0.262)
        (xy 9.908 0.434)
        (xy 9.837 0.585)
        (xy 9.749 0.714)
        (xy 9.643 0.819)
        (xy 9.578 0.867)
        (xy 9.475 0.918)
        (xy 9.352 0.956)
        (xy 9.219 0.98)
        (xy 9.087 0.986)
        (xy 8.966 0.975)
        (xy 8.81 0.933)
        (xy 8.673 0.864)
        (xy 8.553 0.771)
        (xy 8.452 0.653)
        (xy 8.371 0.511)
        (xy 8.31 0.346)
        (xy 8.277 0.202)
        (xy 8.249 -0.011)
        (xy 8.243 -0.182)
        (xy 8.619 -0.182)
        (xy 8.626 -0.007)
        (xy 8.647 0.163)
        (xy 8.682 0.318)
        (xy 8.73 0.449)
        (xy 8.792 0.552)
        (xy 8.87 0.633)
        (xy 8.961 0.69)
        (xy 9.06 0.721)
        (xy 9.164 0.724)
        (xy 9.268 0.699)
        (xy 9.303 0.683)
        (xy 9.391 0.625)
        (xy 9.465 0.546)
        (xy 9.524 0.443)
        (xy 9.569 0.315)
        (xy 9.601 0.162)
        (xy 9.62 0)
        (xy 9.628 -0.198)
        (xy 9.62 -0.382)
        (xy 9.597 -0.55)
        (xy 9.558 -0.698)
        (xy 9.505 -0.825)
        (xy 9.439 -0.927)
        (xy 9.397 -0.971)
        (xy 9.307 -1.035)
        (xy 9.21 -1.071)
        (xy 9.109 -1.079)
        (xy 9.009 -1.062)
        (xy 8.915 -1.019)
        (xy 8.831 -0.953)
        (xy 8.76 -0.863)
        (xy 8.733 -0.813)
        (xy 8.684 -0.68)
        (xy 8.648 -0.526)
        (xy 8.627 -0.358)
        (xy 8.619 -0.182)
        (xy 8.243 -0.182)
        (xy 8.242 -0.218)
        (xy 8.255 -0.417)
        (xy 8.288 -0.602)
        (xy 8.339 -0.772)
        (xy 8.41 -0.923)
        (xy 8.498 -1.051)
        (xy 8.524 -1.081)
        (xy 8.637 -1.182)
        (xy 8.765 -1.255)
        (xy 8.908 -1.302)
        (xy 9.068 -1.322)
        (xy 9.117 -1.323)
        (xy 9.278 -1.313)
      )

      (stroke (width 0.00186) (type solid)) (fill solid) (layer "F.Mask"))
    (fp_poly
      (pts
        (xy 6.48 -1.32)
        (xy 6.584 -1.31)
        (xy 6.642 -1.3)
        (xy 6.701 -1.282)
        (xy 6.765 -1.259)
        (xy 6.825 -1.233)
        (xy 6.873 -1.209)
        (xy 6.9 -1.189)
        (xy 6.902 -1.186)
        (xy 6.901 -1.166)
        (xy 6.889 -1.128)
        (xy 6.872 -1.079)
        (xy 6.852 -1.03)
        (xy 6.833 -0.989)
        (xy 6.818 -0.966)
        (xy 6.815 -0.963)
        (xy 6.795 -0.969)
        (xy 6.757 -0.985)
        (xy 6.717 -1.002)
        (xy 6.597 -1.044)
        (xy 6.478 -1.06)
        (xy 6.365 -1.05)
        (xy 6.267 -1.016)
        (xy 6.184 -0.957)
        (xy 6.109 -0.87)
        (xy 6.042 -0.76)
        (xy 5.988 -0.629)
        (xy 5.964 -0.554)
        (xy 5.946 -0.461)
        (xy 5.934 -0.347)
        (xy 5.929 -0.22)
        (xy 5.931 -0.091)
        (xy 5.938 0.032)
        (xy 5.953 0.138)
        (xy 5.965 0.191)
        (xy 6.018 0.347)
        (xy 6.085 0.476)
        (xy 6.166 0.576)
        (xy 6.262 0.649)
        (xy 6.269 0.653)
        (xy 6.318 0.678)
        (xy 6.36 0.692)
        (xy 6.409 0.698)
        (xy 6.476 0.7)
        (xy 6.48 0.7)
        (xy 6.551 0.697)
        (xy 6.613 0.686)
        (xy 6.676 0.665)
        (xy 6.75 0.631)
        (xy 6.805 0.602)
        (xy 6.811 0.606)
        (xy 6.823 0.627)
        (xy 6.842 0.667)
        (xy 6.868 0.73)
        (xy 6.904 0.819)
        (xy 6.907 0.827)
        (xy 6.898 0.844)
        (xy 6.866 0.868)
        (xy 6.818 0.895)
        (xy 6.759 0.922)
        (xy 6.697 0.945)
        (xy 6.68 0.95)
        (xy 6.596 0.968)
        (xy 6.494 0.98)
        (xy 6.388 0.984)
        (xy 6.292 0.98)
        (xy 6.251 0.975)
        (xy 6.192 0.96)
        (xy 6.121 0.935)
        (xy 6.055 0.906)
        (xy 5.924 0.825)
        (xy 5.811 0.718)
        (xy 5.717 0.586)
        (xy 5.641 0.431)
        (xy 5.585 0.252)
        (xy 5.566 0.164)
        (xy 5.552 0.061)
        (xy 5.545 -0.061)
        (xy 5.544 -0.193)
        (xy 5.549 -0.327)
        (xy 5.56 -0.453)
        (xy 5.576 -0.563)
        (xy 5.589 -0.623)
        (xy 5.65 -0.797)
        (xy 5.731 -0.949)
        (xy 5.831 -1.077)
        (xy 5.948 -1.181)
        (xy 6.081 -1.259)
        (xy 6.187 -1.298)
        (xy 6.27 -1.314)
        (xy 6.372 -1.322)
        (xy 6.48 -1.32)
      )

      (stroke (width 0.00186) (type solid)) (fill solid) (layer "F.Mask"))
    (fp_poly
      (pts
        (xy -2.763 -1.313)
        (xy -2.663 -1.294)
        (xy -2.55 -1.259)
        (xy -2.459 -1.216)
        (xy -2.38 -1.16)
        (xy -2.341 -1.124)
        (xy -2.284 -1.053)
        (xy -2.232 -0.961)
        (xy -2.192 -0.861)
        (xy -2.174 -0.79)
        (xy -2.17 -0.754)
        (xy -2.167 -0.69)
        (xy -2.164 -0.599)
        (xy -2.162 -0.485)
        (xy -2.16 -0.35)
        (xy -2.159 -0.196)
        (xy -2.158 -0.027)
        (xy -2.158 0.064)
        (xy -2.158 0.833)
        (xy -2.232 0.865)
        (xy -2.364 0.913)
        (xy -2.517 0.949)
        (xy -2.682 0.974)
        (xy -2.85 0.986)
        (xy -3.011 0.983)
        (xy -3.097 0.975)
        (xy -3.264 0.942)
        (xy -3.407 0.889)
        (xy -3.525 0.817)
        (xy -3.618 0.725)
        (xy -3.686 0.616)
        (xy -3.729 0.487)
        (xy -3.746 0.341)
        (xy -3.746 0.268)
        (xy -3.744 0.254)
        (xy -3.383 0.254)
        (xy -3.38 0.384)
        (xy -3.352 0.497)
        (xy -3.298 0.591)
        (xy -3.221 0.665)
        (xy -3.12 0.719)
        (xy -3.072 0.735)
        (xy -3.011 0.745)
        (xy -2.928 0.75)
        (xy -2.835 0.75)
        (xy -2.74 0.744)
        (xy -2.655 0.734)
        (xy -2.589 0.72)
        (xy -2.579 0.716)
        (xy -2.504 0.689)
        (xy -2.504 -0.302)
        (xy -2.595 -0.291)
        (xy -2.653 -0.282)
        (xy -2.728 -0.267)
        (xy -2.806 -0.25)
        (xy -2.831 -0.244)
        (xy -2.992 -0.194)
        (xy -3.125 -0.133)
        (xy -3.229 -0.06)
        (xy -3.306 0.026)
        (xy -3.357 0.125)
        (xy -3.381 0.238)
        (xy -3.383 0.254)
        (xy -3.744 0.254)
        (xy -3.725 0.126)
        (xy -3.678 0)
        (xy -3.602 -0.112)
        (xy -3.559 -0.158)
        (xy -3.465 -0.233)
        (xy -3.343 -0.303)
        (xy -3.198 -0.365)
        (xy -3.034 -0.417)
        (xy -2.856 -0.46)
        (xy -2.666 -0.49)
        (xy -2.663 -0.49)
        (xy -2.5 -0.51)
        (xy -2.51 -0.644)
        (xy -2.528 -0.77)
        (xy -2.564 -0.871)
        (xy -2.62 -0.949)
        (xy -2.697 -1.007)
        (xy -2.797 -1.045)
        (xy -2.845 -1.056)
        (xy -2.975 -1.067)
        (xy -3.12 -1.056)
        (xy -3.272 -1.024)
        (xy -3.426 -0.972)
        (xy -3.439 -0.967)
        (xy -3.488 -0.947)
        (xy -3.523 -0.936)
        (xy -3.537 -0.934)
        (xy -3.545 -0.95)
        (xy -3.56 -0.987)
        (xy -3.579 -1.035)
        (xy -3.598 -1.086)
        (xy -3.613 -1.129)
        (xy -3.622 -1.155)
        (xy -3.623 -1.159)
        (xy -3.609 -1.169)
        (xy -3.575 -1.188)
        (xy -3.537 -1.206)
        (xy -3.395 -1.257)
        (xy -3.239 -1.294)
        (xy -3.075 -1.316)
        (xy -2.914 -1.323)
        (xy -2.763 -1.313)
      )

      (stroke (width 0.00186) (type solid)) (fill solid) (layer "F.Mask"))
    (fp_poly
      (pts
        (xy -7.153 -3.366)
        (xy -7.087 -3.351)
        (xy -7.086 -3.351)
        (xy -7.066 -3.34)
        (xy -7.021 -3.315)
        (xy -6.953 -3.277)
        (xy -6.865 -3.227)
        (xy -6.759 -3.167)
        (xy -6.639 -3.099)
        (xy -6.505 -3.022)
        (xy -6.361 -2.94)
        (xy -6.209 -2.853)
        (xy -6.052 -2.762)
        (xy -5.891 -2.67)
        (xy -5.729 -2.577)
        (xy -5.569 -2.485)
        (xy -5.413 -2.395)
        (xy -5.264 -2.309)
        (xy -5.123 -2.227)
        (xy -4.994 -2.152)
        (xy -4.878 -2.085)
        (xy -4.778 -2.027)
        (xy -4.697 -1.979)
        (xy -4.636 -1.943)
        (xy -4.599 -1.921)
        (xy -4.595 -1.918)
        (xy -4.528 -1.863)
        (xy -4.476 -1.798)
        (xy -4.434 -1.725)
        (xy -4.429 -0.224)
        (xy -4.429 0.063)
        (xy -4.428 0.323)
        (xy -4.429 0.553)
        (xy -4.429 0.755)
        (xy -4.43 0.928)
        (xy -4.432 1.071)
        (xy -4.434 1.184)
        (xy -4.436 1.266)
        (xy -4.439 1.318)
        (xy -4.441 1.337)
        (xy -4.448 1.36)
        (xy -4.454 1.382)
        (xy -4.463 1.403)
        (xy -4.476 1.423)
        (xy -4.494 1.445)
        (xy -4.519 1.47)
        (xy -4.552 1.497)
        (xy -4.596 1.529)
        (xy -4.652 1.567)
        (xy -4.721 1.611)
        (xy -4.805 1.663)
        (xy -4.906 1.723)
        (xy -5.025 1.794)
        (xy -5.165 1.875)
        (xy -5.326 1.969)
        (xy -5.511 2.076)
        (xy -5.72 2.197)
        (xy -5.813 2.251)
        (xy -7.079 2.982)
        (xy -7.197 2.988)
        (xy -7.315 2.994)
        (xy -7.78 2.727)
        (xy -8.064 2.563)
        (xy -8.323 2.415)
        (xy -8.557 2.28)
        (xy -8.767 2.159)
        (xy -8.955 2.051)
        (xy -9.122 1.954)
        (xy -9.27 1.868)
        (xy -9.399 1.792)
        (xy -9.51 1.726)
        (xy -9.606 1.669)
        (xy -9.688 1.619)
        (xy -9.756 1.576)
        (xy -9.812 1.539)
        (xy -9.857 1.507)
        (xy -9.893 1.481)
        (xy -9.92 1.458)
        (xy -9.94 1.437)
        (xy -9.955 1.42)
        (xy -9.965 1.403)
        (xy -9.972 1.387)
        (xy -9.977 1.371)
        (xy -9.981 1.354)
        (xy -9.985 1.337)
        (xy -9.988 1.309)
        (xy -9.991 1.25)
        (xy -9.993 1.161)
        (xy -9.995 1.041)
        (xy -9.996 0.891)
        (xy -9.997 0.712)
        (xy -9.998 0.503)
        (xy -9.998 0.266)
        (xy -9.997 0)
        (xy -9.997 -0.189)
        (xy -9.024 -0.189)
        (xy -9.024 0.015)
        (xy -9.024 0.191)
        (xy -9.023 0.34)
        (xy -9.022 0.464)
        (xy -9.021 0.567)
        (xy -9.018 0.65)
        (xy -9.014 0.717)
        (xy -9.01 0.768)
        (xy -9.003 0.808)
        (xy -8.995 0.837)
        (xy -8.986 0.859)
        (xy -8.974 0.876)
        (xy -8.961 0.891)
        (xy -8.945 0.905)
        (xy -8.943 0.906)
        (xy -8.922 0.921)
        (xy -8.877 0.949)
        (xy -8.81 0.989)
        (xy -8.725 1.039)
        (xy -8.625 1.098)
        (xy -8.512 1.164)
        (xy -8.389 1.235)
        (xy -8.26 1.31)
        (xy -8.128 1.386)
        (xy -7.995 1.463)
        (xy -7.864 1.538)
        (xy -7.739 1.609)
        (xy -7.622 1.676)
        (xy -7.517 1.735)
        (xy -7.425 1.787)
        (xy -7.351 1.828)
        (xy -7.297 1.857)
        (xy -7.266 1.872)
        (xy -7.261 1.874)
        (xy -7.222 1.885)
        (xy -7.195 1.886)
        (xy -7.163 1.875)
        (xy -7.144 1.867)
        (xy -7.117 1.854)
        (xy -7.067 1.827)
        (xy -6.997 1.788)
        (xy -6.909 1.738)
        (xy -6.805 1.679)
        (xy -6.691 1.614)
        (xy -6.567 1.543)
        (xy -6.438 1.469)
        (xy -6.306 1.392)
        (xy -6.174 1.316)
        (xy -6.045 1.241)
        (xy -5.922 1.17)
        (xy -5.809 1.103)
        (xy -5.708 1.044)
        (xy -5.622 0.992)
        (xy -5.553 0.952)
        (xy -5.507 0.923)
        (xy -5.484 0.907)
        (xy -5.483 0.907)
        (xy -5.467 0.892)
        (xy -5.453 0.878)
        (xy -5.441 0.861)
        (xy -5.431 0.839)
        (xy -5.423 0.81)
        (xy -5.417 0.772)
        (xy -5.412 0.721)
        (xy -5.408 0.656)
        (xy -5.406 0.574)
        (xy -5.404 0.473)
        (xy -5.403 0.35)
        (xy -5.402 0.203)
        (xy -5.402 0.03)
        (xy -5.402 -0.172)
        (xy -5.402 -0.189)
        (xy -5.402 -0.395)
        (xy -5.402 -0.572)
        (xy -5.403 -0.721)
        (xy -5.404 -0.847)
        (xy -5.406 -0.95)
        (xy -5.408 -1.034)
        (xy -5.412 -1.101)
        (xy -5.418 -1.153)
        (xy -5.425 -1.193)
        (xy -5.434 -1.223)
        (xy -5.445 -1.245)
        (xy -5.458 -1.262)
        (xy -5.473 -1.276)
        (xy -5.491 -1.29)
        (xy -5.499 -1.295)
        (xy -5.522 -1.31)
        (xy -5.57 -1.339)
        (xy -5.64 -1.381)
        (xy -5.729 -1.433)
        (xy -5.835 -1.496)
        (xy -5.956 -1.566)
        (xy -6.088 -1.643)
        (xy -6.229 -1.725)
        (xy -6.348 -1.793)
        (xy -6.519 -1.891)
        (xy -6.664 -1.974)
        (xy -6.786 -2.044)
        (xy -6.888 -2.101)
        (xy -6.971 -2.147)
        (xy -7.038 -2.183)
        (xy -7.091 -2.21)
        (xy -7.132 -2.229)
        (xy -7.163 -2.242)
        (xy -7.187 -2.249)
        (xy -7.205 -2.252)
        (xy -7.211 -2.252)
        (xy -7.228 -2.251)
        (xy -7.249 -2.246)
        (xy -7.276 -2.236)
        (xy -7.312 -2.219)
        (xy -7.359 -2.196)
        (xy -7.419 -2.165)
        (xy -7.495 -2.123)
        (xy -7.587 -2.072)
        (xy -7.699 -2.008)
        (xy -7.832 -1.932)
        (xy -7.99 -1.842)
        (xy -8.1 -1.778)
        (xy -8.248 -1.693)
        (xy -8.388 -1.611)
        (xy -8.519 -1.535)
        (xy -8.637 -1.466)
        (xy -8.739 -1.406)
        (xy -8.825 -1.355)
        (xy -8.89 -1.316)
        (xy -8.933 -1.29)
        (xy -8.951 -1.278)
        (xy -8.966 -1.265)
        (xy -8.978 -1.251)
        (xy -8.989 -1.234)
        (xy -8.998 -1.212)
        (xy -9.005 -1.182)
        (xy -9.011 -1.141)
        (xy -9.015 -1.087)
        (xy -9.018 -1.019)
        (xy -9.021 -0.933)
        (xy -9.022 -0.827)
        (xy -9.023 -0.699)
        (xy -9.024 -0.546)
        (xy -9.024 -0.366)
        (xy -9.024 -0.189)
        (xy -9.997 -0.189)
        (xy -9.997 -0.224)
        (xy -9.996 -0.479)
        (xy -9.996 -0.705)
        (xy -9.995 -0.903)
        (xy -9.994 -1.075)
        (xy -9.993 -1.223)
        (xy -9.992 -1.35)
        (xy -9.99 -1.456)
        (xy -9.987 -1.545)
        (xy -9.984 -1.617)
        (xy -9.98 -1.675)
        (xy -9.974 -1.721)
        (xy -9.968 -1.757)
        (xy -9.961 -1.784)
        (xy -9.952 -1.805)
        (xy -9.941 -1.821)
        (xy -9.929 -1.834)
        (xy -9.915 -1.847)
        (xy -9.9 -1.86)
        (xy -9.893 -1.866)
        (xy -9.873 -1.88)
        (xy -9.828 -1.909)
        (xy -9.759 -1.951)
        (xy -9.669 -2.005)
        (xy -9.56 -2.07)
        (xy -9.433 -2.145)
        (xy -9.291 -2.228)
        (xy -9.136 -2.319)
        (xy -8.969 -2.416)
        (xy -8.793 -2.518)
        (xy -8.61 -2.624)
        (xy -8.59 -2.635)
        (xy -8.377 -2.759)
        (xy -8.189 -2.867)
        (xy -8.024 -2.962)
        (xy -7.882 -3.044)
        (xy -7.759 -3.114)
        (xy -7.656 -3.173)
        (xy -7.568 -3.221)
        (xy -7.496 -3.261)
        (xy -7.437 -3.293)
        (xy -7.389 -3.317)
        (xy -7.351 -3.336)
        (xy -7.321 -3.349)
        (xy -7.296 -3.357)
        (xy -7.276 -3.363)
        (xy -7.259 -3.366)
        (xy -7.242 -3.367)
        (xy -7.237 -3.368)
        (xy -7.153 -3.366)
      )

      (stroke (width 0.00186) (type solid)) (fill solid) (layer "F.Mask"))
    (fp_poly
      (pts
        (xy -7.128 -1.48)
        (xy -7.114 -1.475)
        (xy -7.042 -1.428)
        (xy -6.989 -1.361)
        (xy -6.96 -1.281)
        (xy -6.957 -1.196)
        (xy -6.961 -1.175)
        (xy -6.992 -1.094)
        (xy -7.046 -1.034)
        (xy -7.101 -1.001)
        (xy -7.166 -0.969)
        (xy -7.166 -0.599)
        (xy -6.891 -0.599)
        (xy -6.778 -0.711)
        (xy -6.665 -0.824)
        (xy -6.673 -0.905)
        (xy -6.673 -0.906)
        (xy -6.566 -0.906)
        (xy -6.549 -0.87)
        (xy -6.512 -0.853)
        (xy -6.467 -0.856)
        (xy -6.435 -0.876)
        (xy -6.412 -0.913)
        (xy -6.42 -0.95)
        (xy -6.441 -0.977)
        (xy -6.471 -1.002)
        (xy -6.496 -1.005)
        (xy -6.53 -0.986)
        (xy -6.532 -0.984)
        (xy -6.56 -0.949)
        (xy -6.566 -0.906)
        (xy -6.673 -0.906)
        (xy -6.676 -0.957)
        (xy -6.669 -0.992)
        (xy -6.648 -1.025)
        (xy -6.639 -1.036)
        (xy -6.582 -1.084)
        (xy -6.519 -1.106)
        (xy -6.456 -1.105)
        (xy -6.397 -1.084)
        (xy -6.349 -1.044)
        (xy -6.316 -0.99)
        (xy -6.304 -0.925)
        (xy -6.315 -0.859)
        (xy -6.351 -0.797)
        (xy -6.408 -0.757)
        (xy -6.484 -0.741)
        (xy -6.497 -0.741)
        (xy -6.529 -0.74)
        (xy -6.557 -0.734)
        (xy -6.585 -0.719)
        (xy -6.619 -0.693)
        (xy -6.667 -0.651)
        (xy -6.705 -0.615)
        (xy -6.84 -0.489)
        (xy -7.166 -0.489)
        (xy -7.166 -0.237)
        (xy -6.568 -0.237)
        (xy -6.545 -0.282)
        (xy -6.502 -0.333)
        (xy -6.443 -0.364)
        (xy -6.377 -0.373)
        (xy -6.311 -0.36)
        (xy -6.255 -0.322)
        (xy -6.249 -0.317)
        (xy -6.209 -0.253)
        (xy -6.195 -0.188)
        (xy -6.205 -0.126)
        (xy -6.234 -0.072)
        (xy -6.28 -0.03)
        (xy -6.337 -0.006)
        (xy -6.402 -0.002)
        (xy -6.472 -0.025)
        (xy -6.486 -0.033)
        (xy -6.523 -0.061)
        (xy -6.545 -0.091)
        (xy -6.547 -0.096)
        (xy -6.552 -0.106)
        (xy -6.561 -0.114)
        (xy -6.58 -0.12)
        (xy -6.613 -0.123)
        (xy -6.664 -0.125)
        (xy -6.737 -0.126)
        (xy -6.836 -0.126)
        (xy -6.861 -0.126)
        (xy -7.166 -0.126)
        (xy -7.166 0.11)
        (xy -6.842 0.11)
        (xy -6.581 0.373)
        (xy -6.507 0.366)
        (xy -6.428 0.372)
        (xy -6.367 0.402)
        (xy -6.325 0.457)
        (xy -6.314 0.486)
        (xy -6.304 0.561)
        (xy -6.322 0.626)
        (xy -6.361 0.678)
        (xy -6.422 0.72)
        (xy -6.487 0.736)
        (xy -6.55 0.727)
        (xy -6.605 0.697)
        (xy -6.648 0.648)
        (xy -6.671 0.583)
        (xy -6.672 0.536)
        (xy -6.564 0.536)
        (xy -6.559 0.575)
        (xy -6.544 0.597)
        (xy -6.508 0.625)
        (xy -6.474 0.623)
        (xy -6.441 0.598)
        (xy -6.414 0.56)
        (xy -6.417 0.525)
        (xy -6.44 0.497)
        (xy -6.48 0.476)
        (xy -6.518 0.48)
        (xy -6.549 0.502)
        (xy -6.564 0.536)
        (xy -6.672 0.536)
        (xy -6.673 0.52)
        (xy -6.664 0.445)
        (xy -6.891 0.22)
        (xy -7.166 0.22)
        (xy -7.166 0.593)
        (xy -7.101 0.622)
        (xy -7.033 0.668)
        (xy -6.986 0.732)
        (xy -6.96 0.805)
        (xy -6.956 0.883)
        (xy -6.973 0.959)
        (xy -7.013 1.026)
        (xy -7.074 1.079)
        (xy -7.088 1.087)
        (xy -7.171 1.112)
        (xy -7.258 1.112)
        (xy -7.34 1.087)
        (xy -7.341 1.086)
        (xy -7.406 1.036)
        (xy -7.448 0.97)
        (xy -7.469 0.895)
        (xy -7.468 0.858)
        (xy -7.361 0.858)
        (xy -7.355 0.905)
        (xy -7.331 0.942)
        (xy -7.31 0.962)
        (xy -7.252 0.999)
        (xy -7.195 1.005)
        (xy -7.137 0.979)
        (xy -7.116 0.962)
        (xy -7.08 0.923)
        (xy -7.066 0.883)
        (xy -7.065 0.858)
        (xy -7.079 0.801)
        (xy -7.116 0.751)
        (xy -7.167 0.718)
        (xy -7.213 0.708)
        (xy -7.27 0.722)
        (xy -7.319 0.76)
        (xy -7.352 0.812)
        (xy -7.361 0.858)
        (xy -7.468 0.858)
        (xy -7.468 0.817)
        (xy -7.445 0.742)
        (xy -7.401 0.677)
        (xy -7.336 0.628)
        (xy -7.325 0.622)
        (xy -7.26 0.593)
        (xy -7.26 0.22)
        (xy -7.535 0.22)
        (xy -7.762 0.445)
        (xy -7.753 0.52)
        (xy -7.757 0.595)
        (xy -7.785 0.658)
        (xy -7.83 0.703)
        (xy -7.887 0.73)
        (xy -7.951 0.735)
        (xy -8.015 0.715)
        (xy -8.065 0.678)
        (xy -8.109 0.617)
        (xy -8.123 0.551)
        (xy -8.12 0.532)
        (xy -8.012 0.532)
        (xy -8.009 0.566)
        (xy -7.985 0.598)
        (xy -7.946 0.625)
        (xy -7.912 0.623)
        (xy -7.883 0.599)
        (xy -7.863 0.558)
        (xy -7.868 0.517)
        (xy -7.896 0.486)
        (xy -7.915 0.478)
        (xy -7.961 0.48)
        (xy -7.985 0.496)
        (xy -8.012 0.532)
        (xy -8.12 0.532)
        (xy -8.112 0.486)
        (xy -8.079 0.422)
        (xy -8.025 0.381)
        (xy -7.953 0.365)
        (xy -7.919 0.366)
        (xy -7.845 0.373)
        (xy -7.584 0.11)
        (xy -7.26 0.11)
        (xy -7.26 -0.126)
        (xy -7.566 -0.126)
        (xy -7.672 -0.126)
        (xy -7.75 -0.126)
        (xy -7.805 -0.124)
        (xy -7.841 -0.121)
        (xy -7.863 -0.116)
        (xy -7.875 -0.108)
        (xy -7.881 -0.098)
        (xy -7.883 -0.094)
        (xy -7.908 -0.058)
        (xy -7.954 -0.026)
        (xy -8.009 -0.005)
        (xy -8.045 -0.001)
        (xy -8.117 -0.014)
        (xy -8.174 -0.049)
        (xy -8.213 -0.102)
        (xy -8.23 -0.164)
        (xy -8.228 -0.186)
        (xy -8.124 -0.186)
        (xy -8.12 -0.163)
        (xy -8.104 -0.143)
        (xy -8.063 -0.115)
        (xy -8.021 -0.117)
        (xy -7.994 -0.135)
        (xy -7.971 -0.176)
        (xy -7.976 -0.202)
        (xy -6.455 -0.202)
        (xy -6.449 -0.158)
        (xy -6.432 -0.135)
        (xy -6.392 -0.113)
        (xy -6.35 -0.121)
        (xy -6.322 -0.143)
        (xy -6.303 -0.169)
        (xy -6.304 -0.193)
        (xy -6.316 -0.218)
        (xy -6.35 -0.254)
        (xy -6.39 -0.265)
        (xy -6.429 -0.247)
        (xy -6.432 -0.244)
        (xy -6.455 -0.202)
        (xy -7.976 -0.202)
        (xy -7.979 -0.218)
        (xy -7.999 -0.244)
        (xy -8.04 -0.265)
        (xy -8.078 -0.255)
        (xy -8.11 -0.218)
        (xy -8.124 -0.186)
        (xy -8.228 -0.186)
        (xy -8.224 -0.232)
        (xy -8.192 -0.297)
        (xy -8.177 -0.317)
        (xy -8.121 -0.358)
        (xy -8.055 -0.374)
        (xy -7.988 -0.365)
        (xy -7.927 -0.333)
        (xy -7.885 -0.284)
        (xy -7.857 -0.237)
        (xy -7.26 -0.237)
        (xy -7.26 -0.489)
        (xy -7.586 -0.489)
        (xy -7.721 -0.615)
        (xy -7.779 -0.669)
        (xy -7.821 -0.704)
        (xy -7.852 -0.726)
        (xy -7.879 -0.737)
        (xy -7.908 -0.74)
        (xy -7.934 -0.741)
        (xy -8.011 -0.752)
        (xy -8.068 -0.787)
        (xy -8.105 -0.846)
        (xy -8.112 -0.866)
        (xy -8.119 -0.923)
        (xy -8.016 -0.923)
        (xy -8.003 -0.887)
        (xy -7.969 -0.862)
        (xy -7.928 -0.852)
        (xy -7.888 -0.861)
        (xy -7.878 -0.87)
        (xy -7.86 -0.907)
        (xy -7.866 -0.949)
        (xy -7.894 -0.984)
        (xy -7.924 -1.002)
        (xy -7.941 -1.008)
        (xy -7.964 -0.997)
        (xy -7.991 -0.969)
        (xy -8.011 -0.939)
        (xy -8.016 -0.923)
        (xy -8.119 -0.923)
        (xy -8.121 -0.94)
        (xy -8.105 -1.004)
        (xy -8.069 -1.055)
        (xy -8.018 -1.091)
        (xy -7.958 -1.108)
        (xy -7.894 -1.104)
        (xy -7.831 -1.076)
        (xy -7.787 -1.036)
        (xy -7.762 -1.001)
        (xy -7.751 -0.968)
        (xy -7.751 -0.923)
        (xy -7.753 -0.905)
        (xy -7.762 -0.824)
        (xy -7.648 -0.711)
        (xy -7.535 -0.599)
        (xy -7.26 -0.599)
        (xy -7.26 -0.971)
        (xy -7.323 -0.998)
        (xy -7.396 -1.046)
        (xy -7.446 -1.114)
        (xy -7.465 -1.166)
        (xy -7.472 -1.24)
        (xy -7.365 -1.24)
        (xy -7.359 -1.204)
        (xy -7.347 -1.177)
        (xy -7.307 -1.123)
        (xy -7.254 -1.093)
        (xy -7.194 -1.09)
        (xy -7.134 -1.116)
        (xy -7.127 -1.121)
        (xy -7.081 -1.171)
        (xy -7.065 -1.225)
        (xy -7.078 -1.283)
        (xy -7.116 -1.342)
        (xy -7.166 -1.375)
        (xy -7.222 -1.384)
        (xy -7.278 -1.368)
        (xy -7.326 -1.326)
        (xy -7.354 -1.278)
        (xy -7.365 -1.24)
        (xy -7.472 -1.24)
        (xy -7.474 -1.25)
        (xy -7.455 -1.328)
        (xy -7.416 -1.396)
        (xy -7.358 -1.449)
        (xy -7.288 -1.484)
        (xy -7.21 -1.495)
        (xy -7.128 -1.48)
      )

      (stroke (width 0.00186) (type solid)) (fill solid) (layer "F.Mask"))
  )

  (footprint "data-center-rdimm-ddr4-tester-footprints:C_1206_3216Metric" (layer "F.Cu")
    (at 111.7 102.647157)
    (descr "Capacitor SMD 1206")
    (tags "capacitor SMD 1206")
    (property "Author" "Antmicro")
    (property "Dielectric" "")
    (property "License" "Apache-2.0")
    (property "MPN" "C3216X5R1C476M160AB")
    (property "Manufacturer" "TDK")
    (property "Sheetfile" "supply.kicad_sch")
    (property "Sheetname" "Supply")
    (property "Val" "47u/16V")
    (property "Voltage" "")
    (property "ki_description" " ")
    (attr smd)
    (fp_text reference "C116" (at -2.756328 1.462843 90) (layer "F.SilkS")
        (effects (font (size 0.7 0.7) (thickness 0.15)) (justify left bottom))
    )
    (fp_text value "C_47u_16V_1206" (at 0 2.1) (layer "F.Fab") hide
        (effects (font (size 0.7 0.7) (thickness 0.15)) (justify left bottom))
    )
    (fp_text user "Author: Antmicro" (at -2.8 5.6) (layer "F.Fab") hide
        (effects (font (size 0.7 0.7) (thickness 0.15)) (justify left bottom))
    )
    (fp_text user "License: Apache-2.0" (at -2.8 6.6) (layer "F.Fab") hide
        (effects (font (size 0.7 0.7) (thickness 0.15)) (justify left bottom))
    )
    (fp_text user "${REFERENCE}" (at -2.8 4.6) (layer "F.Fab") hide
        (effects (font (size 0.7 0.7) (thickness 0.15)) (justify left bottom))
    )
    (fp_line (start -2.625 -0.3) (end -2.625 0.3)
      (stroke (width 0.15) (type solid)) (layer "F.SilkS"))
    (fp_line (start 0.5 -0.9) (end -0.5 -0.9)
      (stroke (width 0.15) (type solid)) (layer "F.SilkS"))
    (fp_line (start 0.5 0.9) (end -0.5 0.9)
      (stroke (width 0.15) (type solid)) (layer "F.SilkS"))
    (fp_line (start 2.625 -0.3) (end 2.625 0.3)
      (stroke (width 0.15) (type solid)) (layer "F.SilkS"))
    (fp_rect (start -2.8 -1.15) (end 2.8 1.15)
      (stroke (width 0.05) (type solid)) (fill none) (layer "F.CrtYd"))
    (fp_rect (start -1.6 -0.8) (end 1.6 0.8)
      (stroke (width 0.15) (type solid)) (fill none) (layer "F.Fab"))
    (pad "1" smd rect (at -1.8 0) (size 1.5 1.8) (layers "F.Cu" "F.Paste" "F.Mask")
      (net 103 "VIN") (pintype "passive"))
    (pad "2" smd rect (at 1.8 0) (size 1.5 1.8) (layers "F.Cu" "F.Paste" "F.Mask")
      (net 9 "GND") (pintype "passive"))
  )

  (footprint "data-center-rdimm-ddr4-tester-footprints:C_1206_3216Metric" (layer "F.Cu")
    (at 111.7 100.147157)
    (descr "Capacitor SMD 1206")
    (tags "capacitor SMD 1206")
    (property "Author" "Antmicro")
    (property "Dielectric" "")
    (property "License" "Apache-2.0")
    (property "MPN" "C3216X5R1C476M160AB")
    (property "Manufacturer" "TDK")
    (property "Sheetfile" "supply.kicad_sch")
    (property "Sheetname" "Supply")
    (property "Val" "47u/16V")
    (property "Voltage" "")
    (property "ki_description" " ")
    (attr smd)
    (fp_text reference "C117" (at -2.766328 1.302843 90) (layer "F.SilkS")
        (effects (font (size 0.7 0.7) (thickness 0.15)) (justify left bottom))
    )
    (fp_text value "C_47u_16V_1206" (at 0 2.1) (layer "F.Fab") hide
        (effects (font (size 0.7 0.7) (thickness 0.15)) (justify left bottom))
    )
    (fp_text user "License: Apache-2.0" (at -2.8 6.6) (layer "F.Fab") hide
        (effects (font (size 0.7 0.7) (thickness 0.15)) (justify left bottom))
    )
    (fp_text user "${REFERENCE}" (at -2.8 4.6) (layer "F.Fab") hide
        (effects (font (size 0.7 0.7) (thickness 0.15)) (justify left bottom))
    )
    (fp_text user "Author: Antmicro" (at -2.8 5.6) (layer "F.Fab") hide
        (effects (font (size 0.7 0.7) (thickness 0.15)) (justify left bottom))
    )
    (fp_line (start -2.625 -0.3) (end -2.625 0.3)
      (stroke (width 0.15) (type solid)) (layer "F.SilkS"))
    (fp_line (start 0.5 -0.9) (end -0.5 -0.9)
      (stroke (width 0.15) (type solid)) (layer "F.SilkS"))
    (fp_line (start 0.5 0.9) (end -0.5 0.9)
      (stroke (width 0.15) (type solid)) (layer "F.SilkS"))
    (fp_line (start 2.625 -0.3) (end 2.625 0.3)
      (stroke (width 0.15) (type solid)) (layer "F.SilkS"))
    (fp_rect (start -2.8 -1.15) (end 2.8 1.15)
      (stroke (width 0.05) (type solid)) (fill none) (layer "F.CrtYd"))
    (fp_rect (start -1.6 -0.8) (end 1.6 0.8)
      (stroke (width 0.15) (type solid)) (fill none) (layer "F.Fab"))
    (pad "1" smd rect (at -1.8 0) (size 1.5 1.8) (layers "F.Cu" "F.Paste" "F.Mask")
      (net 103 "VIN") (pintype "passive"))
    (pad "2" smd rect (at 1.8 0) (size 1.5 1.8) (layers "F.Cu" "F.Paste" "F.Mask")
      (net 9 "GND") (pintype "passive"))
  )

  (footprint "data-center-rdimm-ddr4-tester-footprints:C_1206_3216Metric" (layer "F.Cu")
    (at 111.7 105.147157)
    (descr "Capacitor SMD 1206")
    (tags "capacitor SMD 1206")
    (property "Author" "Antmicro")
    (property "Dielectric" "")
    (property "License" "Apache-2.0")
    (property "MPN" "C3216X5R1C476M160AB")
    (property "Manufacturer" "TDK")
    (property "Sheetfile" "supply.kicad_sch")
    (property "Sheetname" "Supply")
    (property "Val" "47u/16V")
    (property "Voltage" "")
    (property "ki_description" " ")
    (attr smd)
    (fp_text reference "C118" (at -2.76 1.652843 90) (layer "F.SilkS")
        (effects (font (size 0.7 0.7) (thickness 0.15)) (justify left bottom))
    )
    (fp_text value "C_47u_16V_1206" (at 0 2.1) (layer "F.Fab") hide
        (effects (font (size 0.7 0.7) (thickness 0.15)) (justify left bottom))
    )
    (fp_text user "${REFERENCE}" (at -2.8 4.6) (layer "F.Fab") hide
        (effects (font (size 0.7 0.7) (thickness 0.15)) (justify left bottom))
    )
    (fp_text user "Author: Antmicro" (at -2.8 5.6) (layer "F.Fab") hide
        (effects (font (size 0.7 0.7) (thickness 0.15)) (justify left bottom))
    )
    (fp_text user "License: Apache-2.0" (at -2.8 6.6) (layer "F.Fab") hide
        (effects (font (size 0.7 0.7) (thickness 0.15)) (justify left bottom))
    )
    (fp_line (start -2.625 -0.3) (end -2.625 0.3)
      (stroke (width 0.15) (type solid)) (layer "F.SilkS"))
    (fp_line (start 0.5 -0.9) (end -0.5 -0.9)
      (stroke (width 0.15) (type solid)) (layer "F.SilkS"))
    (fp_line (start 0.5 0.9) (end -0.5 0.9)
      (stroke (width 0.15) (type solid)) (layer "F.SilkS"))
    (fp_line (start 2.625 -0.3) (end 2.625 0.3)
      (stroke (width 0.15) (type solid)) (layer "F.SilkS"))
    (fp_rect (start -2.8 -1.15) (end 2.8 1.15)
      (stroke (width 0.05) (type solid)) (fill none) (layer "F.CrtYd"))
    (fp_rect (start -1.6 -0.8) (end 1.6 0.8)
      (stroke (width 0.15) (type solid)) (fill none) (layer "F.Fab"))
    (pad "1" smd rect (at -1.8 0) (size 1.5 1.8) (layers "F.Cu" "F.Paste" "F.Mask")
      (net 103 "VIN") (pintype "passive"))
    (pad "2" smd rect (at 1.8 0) (size 1.5 1.8) (layers "F.Cu" "F.Paste" "F.Mask")
      (net 9 "GND") (pintype "passive"))
  )

  (footprint "data-center-rdimm-ddr4-tester-footprints:PowerDI5" (layer "F.Cu")
    (at 110.9 122.3 90)
    (property "Author" "Antmicro")
    (property "License" "Apache-2.0")
    (property "MPN" "PDS760-13")
    (property "Manufacturer" "Diodes Incorporated")
    (property "Sheetfile" "supply.kicad_sch")
    (property "Sheetname" "Supply")
    (property "ki_description" "PDS760 Series 60 V 7 A Surface Mount Schottky Barrier Rectifier - PowerDI-5")
    (property "ki_keywords" "PDS760 Series 60 V 7 A Surface Mount Schottky Barrier Rectifier - PowerDI-5")
    (attr smd)
    (fp_text reference "D11" (at -3.78 -3.73 180) (layer "F.SilkS")
        (effects (font (size 0.7 0.7) (thickness 0.15)) (justify left bottom))
    )
    (fp_text value "PDS760" (at 0 3.4 90) (layer "F.Fab") hide
        (effects (font (size 0.7 0.7) (thickness 0.15)) (justify right bottom))
    )
    (fp_text user "License: Apache-2.0" (at -3.302 20.928 90) (layer "F.Fab") hide
        (effects (font (size 0.7 0.7) (thickness 0.15)) (justify left bottom))
    )
    (fp_text user "${REFERENCE}" (at -3.302 18.527 90) (layer "F.Fab") hide
        (effects (font (size 0.7 0.7) (thickness 0.15)) (justify left bottom))
    )
    (fp_text user "Author: Antmicro" (at -3.302 19.728 90) (layer "F.Fab") hide
        (effects (font (size 0.7 0.7) (thickness 0.15)) (justify left bottom))
    )
    (fp_line (start -2.7 -2) (end 2.7 -2)
      (stroke (width 0.12) (type solid)) (layer "F.SilkS"))
    (fp_line (start -2.7 -1.8) (end -2.7 -2)
      (stroke (width 0.12) (type solid)) (layer "F.SilkS"))
    (fp_line (start -2.7 2.023) (end -2.7 1.823)
      (stroke (width 0.12) (type solid)) (layer "F.SilkS"))
    (fp_line (start 2.7 -2) (end 2.7 -1.8)
      (stroke (width 0.12) (type solid)) (layer "F.SilkS"))
    (fp_line (start 2.7 1.823) (end 2.7 2.023)
      (stroke (width 0.12) (type solid)) (layer "F.SilkS"))
    (fp_line (start 2.7 2.023) (end -2.7 2.023)
      (stroke (width 0.12) (type solid)) (layer "F.SilkS"))
    (fp_rect (start -3.702 -2.3) (end 3.7 2.3)
      (stroke (width 0.05) (type solid)) (fill none) (layer "F.CrtYd"))
    (pad "A" smd roundrect (at -2.862 -0.94 180) (size 1.39 1.4) (layers "F.Cu" "F.Paste" "F.Mask") (roundrect_rratio 0.25)
      (net 626 "VIN_RAW") (pinfunction "A") (pintype "passive"))
    (pad "A" smd roundrect (at -2.862 0.941) (size 1.39 1.4) (layers "F.Cu" "F.Paste" "F.Mask") (roundrect_rratio 0.25)
      (net 626 "VIN_RAW") (pinfunction "A") (pintype "passive"))
    (pad "C" smd roundrect (at 1.1 0) (size 3.36 4.86) (layers "F.Cu" "F.Paste" "F.Mask") (roundrect_rratio 0.05)
      (net 103 "VIN") (pinfunction "C") (pintype "passive"))
  )

  (footprint "data-center-rdimm-ddr4-tester-footprints:R_0402_1005Metric" (layer "F.Cu")
    (at 235.767 117.001)
    (descr "Resistor SMD 0402")
    (tags "resistor SMD 0402")
    (property "Author" "Antmicro")
    (property "Current" "1A")
    (property "License" "Apache-2.0")
    (property "MPN" "ERJ2GE0R00X")
    (property "Manufacturer" "Panasonic")
    (property "Sheetfile" "config-spi.kicad_sch")
    (property "Sheetname" "Config SPI flash")
    (property "Tolerance" "")
    (property "Val" "0R")
    (property "ki_description" "0R resistor in 0402 package with unspecified tolerance")
    (attr smd)
    (fp_text reference "R26" (at -1.017 -3.641) (layer "F.SilkS")
        (effects (font (size 0.7 0.7) (thickness 0.15)) (justify left bottom))
    )
    (fp_text value "R_0R_0402" (at 0 1.4) (layer "F.Fab") hide
        (effects (font (size 0.7 0.7) (thickness 0.15)) (justify left bottom))
    )
    (fp_text user "${REFERENCE}" (at -0.95 3.168) (layer "F.Fab") hide
        (effects (font (size 0.7 0.7) (thickness 0.15)) (justify left bottom))
    )
    (fp_text user "License: Apache-2.0" (at -0.95 5.169) (layer "F.Fab") hide
        (effects (font (size 0.7 0.7) (thickness 0.15)) (justify left bottom))
    )
    (fp_text user "Author: Antmicro" (at -0.95 4.169) (layer "F.Fab") hide
        (effects (font (size 0.7 0.7) (thickness 0.15)) (justify left bottom))
    )
    (fp_rect (start -0.93 -0.47) (end 0.93 0.47)
      (stroke (width 0.05) (type solid)) (fill none) (layer "F.CrtYd"))
    (fp_rect (start -0.5 -0.25) (end 0.5 0.25)
      (stroke (width 0.15) (type solid)) (fill none) (layer "F.Fab"))
    (pad "1" smd roundrect (at -0.485 0) (size 0.59 0.64) (layers "F.Cu" "F.Paste" "F.Mask") (roundrect_rratio 0.25)
      (net 599 "Net-(U3-~{HOLD}{slash}IO3)") (pintype "passive"))
    (pad "2" smd roundrect (at 0.485 0) (size 0.59 0.64) (layers "F.Cu" "F.Paste" "F.Mask") (roundrect_rratio 0.25)
      (net 22 "QSPI_DQ3") (pintype "passive"))
  )

  (footprint "data-center-rdimm-ddr4-tester-footprints:LED_0603_1608Metric_G" (layer "F.Cu")
    (at 243.15 126.36 -90)
    (descr "LED SMD 0603 Green")
    (tags "LED SMD 0603 Green")
    (property "Author" "Antmicro")
    (property "License" "Apache-2.0")
    (property "MPN" "KP-1608CGCK")
    (property "Manufacturer" "Kingbright")
    (property "Sheetfile" "supply.kicad_sch")
    (property "Sheetname" "Supply")
    (attr smd)
    (fp_text reference "PWR1" (at 3.05 -2.43 -90) (layer "F.SilkS")
        (effects (font (size 0.7 0.7) (thickness 0.15)) (justify left bottom))
    )
    (fp_text value "LED_G_0603_KP-1608CGCK" (at 0 1.6 -90) (layer "F.Fab") hide
        (effects (font (size 0.7 0.7) (thickness 0.15)) (justify left bottom))
    )
    (fp_text user "License: Apache-2.0" (at -1.31 5.769 -90) (layer "F.Fab") hide
        (effects (font (size 0.7 0.7) (thickness 0.15)) (justify left bottom))
    )
    (fp_text user "${REFERENCE}" (at -1.31 3.769 -90) (layer "F.Fab") hide
        (effects (font (size 0.7 0.7) (thickness 0.15)) (justify left bottom))
    )
    (fp_text user "Author: Antmicro" (at -1.31 4.769 -90) (layer "F.Fab") hide
        (effects (font (size 0.7 0.7) (thickness 0.15)) (justify left bottom))
    )
    (fp_line (start -0.27 -0.35) (end 0.27 -0.35)
      (stroke (width 0.15) (type solid)) (layer "F.SilkS"))
    (fp_line (start -0.27 0.351) (end 0.27 0.351)
      (stroke (width 0.15) (type solid)) (layer "F.SilkS"))
    (fp_line (start -0.106328 -0.200008) (end -0.106328 0.199992)
      (stroke (width 0.1) (type solid)) (layer "F.SilkS"))
    (fp_line (start -0.106328 -0.200008) (end 0.093672 -0.000008)
      (stroke (width 0.1) (type solid)) (layer "F.SilkS"))
    (fp_line (start -0.106328 -0.000008) (end -0.29 0)
      (stroke (width 0.1) (type solid)) (layer "F.SilkS"))
    (fp_line (start 0.093672 -0.200008) (end 0.093672 0.199992)
      (stroke (width 0.1) (type solid)) (layer "F.SilkS"))
    (fp_line (start 0.093672 -0.000008) (end -0.106328 0.199992)
      (stroke (width 0.1) (type solid)) (layer "F.SilkS"))
    (fp_line (start 0.093672 -0.000008) (end 0.293672 -0.000008)
      (stroke (width 0.1) (type solid)) (layer "F.SilkS"))
    (fp_line (start 1.25 0.32) (end 1.25 -0.32)
      (stroke (width 0.15) (type solid)) (layer "F.SilkS"))
    (fp_rect (start 1.26 0.65) (end -1.26 -0.65)
      (stroke (width 0.05) (type solid)) (fill none) (layer "F.CrtYd"))
    (fp_line (start -0.599 0) (end -0.201 0)
      (stroke (width 0.15) (type solid)) (layer "F.Fab"))
    (fp_line (start -0.201 -0.2) (end -0.201 0)
      (stroke (width 0.15) (type solid)) (layer "F.Fab"))
    (fp_line (start -0.201 0) (end -0.201 0.202)
      (stroke (width 0.15) (type solid)) (layer "F.Fab"))
    (fp_line (start -0.201 0.202) (end 0.101 0)
      (stroke (width 0.15) (type solid)) (layer "F.Fab"))
    (fp_line (start 0.101 0) (end -0.201 -0.2)
      (stroke (width 0.15) (type solid)) (layer "F.Fab"))
    (fp_line (start 0.199 -0.2) (end 0.199 -0.1)
      (stroke (width 0.15) (type solid)) (layer "F.Fab"))
    (fp_line (start 0.199 0) (end 0.597 0)
      (stroke (width 0.15) (type solid)) (layer "F.Fab"))
    (fp_line (start 0.199 0.202) (end 0.199 -0.1)
      (stroke (width 0.15) (type solid)) (layer "F.Fab"))
    (fp_rect (start -0.848 -0.4) (end 0.85 0.402)
      (stroke (width 0.15) (type solid)) (fill none) (layer "F.Fab"))
    (pad "1" smd rect (at -0.75 0 90) (size 0.8 0.8) (layers "F.Cu" "F.Paste" "F.Mask")
      (net 143 "3V3_SYS") (pinfunction "1") (pintype "passive"))
    (pad "2" smd rect (at 0.75 0 90) (size 0.8 0.8) (layers "F.Cu" "F.Paste" "F.Mask")
      (net 115 "Net-(PWR1-Pad2)") (pinfunction "2") (pintype "passive"))
  )

  (footprint "data-center-rdimm-ddr4-tester-footprints:C_0402_1005Metric" (layer "F.Cu")
    (at 151.086328 91.874306 180)
    (descr "Capacitor SMD 0402")
    (tags "capacitor SMD 0402")
    (property "Author" "Antmicro")
    (property "Dielectric" "")
    (property "License" "Apache-2.0")
    (property "MPN" "GRM155R61A475MEAAD")
    (property "Manufacturer" "Murata")
    (property "Sheetfile" "ethernet.kicad_sch")
    (property "Sheetname" "Ethernet")
    (property "Val" "4u7")
    (property "Voltage" "")
    (property "ki_description" " ")
    (attr smd)
    (fp_text reference "C119" (at 1.386328 1.594306 180) (layer "F.SilkS")
        (effects (font (size 0.7 0.7) (thickness 0.15)) (justify left bottom))
    )
    (fp_text value "C_4u7_0402" (at 0 1.4 180) (layer "F.Fab") hide
        (effects (font (size 0.7 0.7) (thickness 0.15)) (justify left bottom))
    )
    (fp_text user "License: Apache-2.0" (at -0.932 5.17 180) (layer "F.Fab") hide
        (effects (font (size 0.7 0.7) (thickness 0.15)) (justify left bottom))
    )
    (fp_text user "Author: Antmicro" (at -0.932 4.17 180) (layer "F.Fab") hide
        (effects (font (size 0.7 0.7) (thickness 0.15)) (justify left bottom))
    )
    (fp_text user "${REFERENCE}" (at -0.932 3.168 180) (layer "F.Fab") hide
        (effects (font (size 0.7 0.7) (thickness 0.15)) (justify left bottom))
    )
    (fp_rect (start -0.94 -0.47) (end 0.94 0.47)
      (stroke (width 0.05) (type solid)) (fill none) (layer "F.CrtYd"))
    (fp_rect (start -0.499 -0.249) (end 0.499 0.249)
      (stroke (width 0.15) (type solid)) (fill none) (layer "F.Fab"))
    (pad "1" smd roundrect (at -0.484 0 180) (size 0.59 0.64) (layers "F.Cu" "F.Paste" "F.Mask") (roundrect_rratio 0.25)
      (net 306 "1V2_SYS") (pintype "passive"))
    (pad "2" smd roundrect (at 0.484 0 180) (size 0.59 0.64) (layers "F.Cu" "F.Paste" "F.Mask") (roundrect_rratio 0.25)
      (net 9 "GND") (pintype "passive"))
  )

  (footprint "data-center-rdimm-ddr4-tester-footprints:C_0402_1005Metric" (layer "F.Cu")
    (at 151.086328 92.874306 180)
    (descr "Capacitor SMD 0402")
    (tags "capacitor SMD 0402")
    (property "Author" "Antmicro")
    (property "Dielectric" "")
    (property "License" "Apache-2.0")
    (property "MPN" "C1005X5R1E474M050BB")
    (property "Manufacturer" "TDK")
    (property "Sheetfile" "ethernet.kicad_sch")
    (property "Sheetname" "Ethernet")
    (property "Val" "470n")
    (property "Voltage" "")
    (property "ki_description" " ")
    (attr smd)
    (fp_text reference "C120" (at 1.386328 1.594306 180) (layer "F.SilkS")
        (effects (font (size 0.7 0.7) (thickness 0.15)) (justify left bottom))
    )
    (fp_text value "C_470n_0402" (at 0 1.4 180) (layer "F.Fab") hide
        (effects (font (size 0.7 0.7) (thickness 0.15)) (justify left bottom))
    )
    (fp_text user "Author: Antmicro" (at -0.932 4.17 180) (layer "F.Fab") hide
        (effects (font (size 0.7 0.7) (thickness 0.15)) (justify left bottom))
    )
    (fp_text user "License: Apache-2.0" (at -0.932 5.17 180) (layer "F.Fab") hide
        (effects (font (size 0.7 0.7) (thickness 0.15)) (justify left bottom))
    )
    (fp_text user "${REFERENCE}" (at -0.932 3.168 180) (layer "F.Fab") hide
        (effects (font (size 0.7 0.7) (thickness 0.15)) (justify left bottom))
    )
    (fp_rect (start -0.94 -0.47) (end 0.94 0.47)
      (stroke (width 0.05) (type solid)) (fill none) (layer "F.CrtYd"))
    (fp_rect (start -0.499 -0.249) (end 0.499 0.249)
      (stroke (width 0.15) (type solid)) (fill none) (layer "F.Fab"))
    (pad "1" smd roundrect (at -0.484 0 180) (size 0.59 0.64) (layers "F.Cu" "F.Paste" "F.Mask") (roundrect_rratio 0.25)
      (net 306 "1V2_SYS") (pintype "passive"))
    (pad "2" smd roundrect (at 0.484 0 180) (size 0.59 0.64) (layers "F.Cu" "F.Paste" "F.Mask") (roundrect_rratio 0.25)
      (net 9 "GND") (pintype "passive"))
  )

  (footprint "data-center-rdimm-ddr4-tester-footprints:C_0402_1005Metric" (layer "F.Cu")
    (at 151.586328 94.374306 -90)
    (descr "Capacitor SMD 0402")
    (tags "capacitor SMD 0402")
    (property "Author" "Antmicro")
    (property "Dielectric" "")
    (property "License" "Apache-2.0")
    (property "MPN" "GRM155R61A475MEAAD")
    (property "Manufacturer" "Murata")
    (property "Sheetfile" "ethernet.kicad_sch")
    (property "Sheetname" "Ethernet")
    (property "Val" "4u7")
    (property "Voltage" "")
    (property "ki_description" " ")
    (attr smd)
    (fp_text reference "C124" (at -0.654306 2.356328 -90) (layer "F.SilkS")
        (effects (font (size 0.7 0.7) (thickness 0.15)) (justify left bottom))
    )
    (fp_text value "C_4u7_0402" (at 0 1.4 -90) (layer "F.Fab") hide
        (effects (font (size 0.7 0.7) (thickness 0.15)) (justify left bottom))
    )
    (fp_text user "${REFERENCE}" (at -0.932 3.168 -90) (layer "F.Fab") hide
        (effects (font (size 0.7 0.7) (thickness 0.15)) (justify left bottom))
    )
    (fp_text user "Author: Antmicro" (at -0.932 4.17 -90) (layer "F.Fab") hide
        (effects (font (size 0.7 0.7) (thickness 0.15)) (justify left bottom))
    )
    (fp_text user "License: Apache-2.0" (at -0.932 5.17 -90) (layer "F.Fab") hide
        (effects (font (size 0.7 0.7) (thickness 0.15)) (justify left bottom))
    )
    (fp_rect (start -0.94 -0.47) (end 0.94 0.47)
      (stroke (width 0.05) (type solid)) (fill none) (layer "F.CrtYd"))
    (fp_rect (start -0.499 -0.249) (end 0.499 0.249)
      (stroke (width 0.15) (type solid)) (fill none) (layer "F.Fab"))
    (pad "1" smd roundrect (at -0.484 0 270) (size 0.59 0.64) (layers "F.Cu" "F.Paste" "F.Mask") (roundrect_rratio 0.25)
      (net 9 "GND") (pintype "passive"))
    (pad "2" smd roundrect (at 0.484 0 270) (size 0.59 0.64) (layers "F.Cu" "F.Paste" "F.Mask") (roundrect_rratio 0.25)
      (net 178 "/Ethernet/AVDDL_PLL") (pintype "passive"))
  )

  (footprint "data-center-rdimm-ddr4-tester-footprints:C_0402_1005Metric" (layer "F.Cu")
    (at 163.486328 96.774306 90)
    (descr "Capacitor SMD 0402")
    (tags "capacitor SMD 0402")
    (property "Author" "Antmicro")
    (property "Dielectric" "")
    (property "License" "Apache-2.0")
    (property "MPN" "C1005X5R1E474M050BB")
    (property "Manufacturer" "TDK")
    (property "Sheetfile" "ethernet.kicad_sch")
    (property "Sheetname" "Ethernet")
    (property "Val" "470n")
    (property "Voltage" "")
    (property "ki_description" " ")
    (attr smd)
    (fp_text reference "C127" (at -0.825694 2.363672 90) (layer "F.SilkS")
        (effects (font (size 0.7 0.7) (thickness 0.15)) (justify left bottom))
    )
    (fp_text value "C_470n_0402" (at 0 1.4 90) (layer "F.Fab") hide
        (effects (font (size 0.7 0.7) (thickness 0.15)) (justify left bottom))
    )
    (fp_text user "${REFERENCE}" (at -0.932 3.168 90) (layer "F.Fab") hide
        (effects (font (size 0.7 0.7) (thickness 0.15)) (justify left bottom))
    )
    (fp_text user "Author: Antmicro" (at -0.932 4.17 90) (layer "F.Fab") hide
        (effects (font (size 0.7 0.7) (thickness 0.15)) (justify left bottom))
    )
    (fp_text user "License: Apache-2.0" (at -0.932 5.17 90) (layer "F.Fab") hide
        (effects (font (size 0.7 0.7) (thickness 0.15)) (justify left bottom))
    )
    (fp_rect (start -0.94 -0.47) (end 0.94 0.47)
      (stroke (width 0.05) (type solid)) (fill none) (layer "F.CrtYd"))
    (fp_rect (start -0.499 -0.249) (end 0.499 0.249)
      (stroke (width 0.15) (type solid)) (fill none) (layer "F.Fab"))
    (pad "1" smd roundrect (at -0.484 0 90) (size 0.59 0.64) (layers "F.Cu" "F.Paste" "F.Mask") (roundrect_rratio 0.25)
      (net 143 "3V3_SYS") (pintype "passive"))
    (pad "2" smd roundrect (at 0.484 0 90) (size 0.59 0.64) (layers "F.Cu" "F.Paste" "F.Mask") (roundrect_rratio 0.25)
      (net 9 "GND") (pintype "passive"))
  )

  (footprint "data-center-rdimm-ddr4-tester-footprints:C_0402_1005Metric" (layer "F.Cu")
    (at 150.486328 94.374306 -90)
    (descr "Capacitor SMD 0402")
    (tags "capacitor SMD 0402")
    (property "Author" "Antmicro")
    (property "Dielectric" "")
    (property "License" "Apache-2.0")
    (property "MPN" "MC0402B104K160CT")
    (property "Manufacturer" "Multicomp")
    (property "Sheetfile" "ethernet.kicad_sch")
    (property "Sheetname" "Ethernet")
    (property "Val" "100n")
    (property "Voltage" "")
    (property "ki_description" " ")
    (attr smd)
    (fp_text reference "C128" (at -0.654306 2.356328 -90) (layer "F.SilkS")
        (effects (font (size 0.7 0.7) (thickness 0.15)) (justify left bottom))
    )
    (fp_text value "C_100n_16V_0402" (at 0 1.4 -90) (layer "F.Fab") hide
        (effects (font (size 0.7 0.7) (thickness 0.15)) (justify left bottom))
    )
    (fp_text user "${REFERENCE}" (at -0.932 3.168 -90) (layer "F.Fab") hide
        (effects (font (size 0.7 0.7) (thickness 0.15)) (justify left bottom))
    )
    (fp_text user "License: Apache-2.0" (at -0.932 5.17 -90) (layer "F.Fab") hide
        (effects (font (size 0.7 0.7) (thickness 0.15)) (justify left bottom))
    )
    (fp_text user "Author: Antmicro" (at -0.932 4.17 -90) (layer "F.Fab") hide
        (effects (font (size 0.7 0.7) (thickness 0.15)) (justify left bottom))
    )
    (fp_rect (start -0.94 -0.47) (end 0.94 0.47)
      (stroke (width 0.05) (type solid)) (fill none) (layer "F.CrtYd"))
    (fp_rect (start -0.499 -0.249) (end 0.499 0.249)
      (stroke (width 0.15) (type solid)) (fill none) (layer "F.Fab"))
    (pad "1" smd roundrect (at -0.484 0 270) (size 0.59 0.64) (layers "F.Cu" "F.Paste" "F.Mask") (roundrect_rratio 0.25)
      (net 9 "GND") (pintype "passive"))
    (pad "2" smd roundrect (at 0.484 0 270) (size 0.59 0.64) (layers "F.Cu" "F.Paste" "F.Mask") (roundrect_rratio 0.25)
      (net 178 "/Ethernet/AVDDL_PLL") (pintype "passive"))
  )

  (footprint "data-center-rdimm-ddr4-tester-footprints:C_0402_1005Metric" (layer "F.Cu")
    (at 163.486328 99.1 -90)
    (descr "Capacitor SMD 0402")
    (tags "capacitor SMD 0402")
    (property "Author" "Antmicro")
    (property "Dielectric" "")
    (property "License" "Apache-2.0")
    (property "MPN" "C1005X5R1E474M050BB")
    (property "Manufacturer" "TDK")
    (property "Sheetfile" "ethernet.kicad_sch")
    (property "Sheetname" "Ethernet")
    (property "Val" "470n")
    (property "Voltage" "")
    (property "ki_description" " ")
    (attr smd)
    (fp_text reference "C130" (at 1.1 -2.363672 -90) (layer "F.SilkS")
        (effects (font (size 0.7 0.7) (thickness 0.15)) (justify left bottom))
    )
    (fp_text value "C_470n_0402" (at 0 1.4 -90) (layer "F.Fab") hide
        (effects (font (size 0.7 0.7) (thickness 0.15)) (justify left bottom))
    )
    (fp_text user "${REFERENCE}" (at -0.932 3.168 -90) (layer "F.Fab") hide
        (effects (font (size 0.7 0.7) (thickness 0.15)) (justify left bottom))
    )
    (fp_text user "Author: Antmicro" (at -0.932 4.17 -90) (layer "F.Fab") hide
        (effects (font (size 0.7 0.7) (thickness 0.15)) (justify left bottom))
    )
    (fp_text user "License: Apache-2.0" (at -0.932 5.17 -90) (layer "F.Fab") hide
        (effects (font (size 0.7 0.7) (thickness 0.15)) (justify left bottom))
    )
    (fp_rect (start -0.94 -0.47) (end 0.94 0.47)
      (stroke (width 0.05) (type solid)) (fill none) (layer "F.CrtYd"))
    (fp_rect (start -0.499 -0.249) (end 0.499 0.249)
      (stroke (width 0.15) (type solid)) (fill none) (layer "F.Fab"))
    (pad "1" smd roundrect (at -0.484 0 270) (size 0.59 0.64) (layers "F.Cu" "F.Paste" "F.Mask") (roundrect_rratio 0.25)
      (net 306 "1V2_SYS") (pintype "passive"))
    (pad "2" smd roundrect (at 0.484 0 270) (size 0.59 0.64) (layers "F.Cu" "F.Paste" "F.Mask") (roundrect_rratio 0.25)
      (net 9 "GND") (pintype "passive"))
  )

  (footprint "data-center-rdimm-ddr4-tester-footprints:C_0402_1005Metric" (layer "F.Cu")
    (at 149.386328 94.374306 -90)
    (descr "Capacitor SMD 0402")
    (tags "capacitor SMD 0402")
    (property "Author" "Antmicro")
    (property "Dielectric" "X7R")
    (property "License" "Apache-2.0")
    (property "MPN" "GRM155R71H103KA88D")
    (property "Manufacturer" "Murata")
    (property "Sheetfile" "ethernet.kicad_sch")
    (property "Sheetname" "Ethernet")
    (property "Val" "10n")
    (property "Voltage" "50V")
    (property "ki_description" " ")
    (attr smd)
    (fp_text reference "C133" (at -0.654306 2.356328 -90) (layer "F.SilkS")
        (effects (font (size 0.7 0.7) (thickness 0.15)) (justify left bottom))
    )
    (fp_text value "C_10n_0402" (at 0 1.4 -90) (layer "F.Fab") hide
        (effects (font (size 0.7 0.7) (thickness 0.15)) (justify left bottom))
    )
    (fp_text user "Author: Antmicro" (at -0.932 4.17 -90) (layer "F.Fab") hide
        (effects (font (size 0.7 0.7) (thickness 0.15)) (justify left bottom))
    )
    (fp_text user "License: Apache-2.0" (at -0.932 5.17 -90) (layer "F.Fab") hide
        (effects (font (size 0.7 0.7) (thickness 0.15)) (justify left bottom))
    )
    (fp_text user "${REFERENCE}" (at -0.932 3.168 -90) (layer "F.Fab") hide
        (effects (font (size 0.7 0.7) (thickness 0.15)) (justify left bottom))
    )
    (fp_rect (start -0.94 -0.47) (end 0.94 0.47)
      (stroke (width 0.05) (type solid)) (fill none) (layer "F.CrtYd"))
    (fp_rect (start -0.499 -0.249) (end 0.499 0.249)
      (stroke (width 0.15) (type solid)) (fill none) (layer "F.Fab"))
    (pad "1" smd roundrect (at -0.484 0 270) (size 0.59 0.64) (layers "F.Cu" "F.Paste" "F.Mask") (roundrect_rratio 0.25)
      (net 9 "GND") (pintype "passive"))
    (pad "2" smd roundrect (at 0.484 0 270) (size 0.59 0.64) (layers "F.Cu" "F.Paste" "F.Mask") (roundrect_rratio 0.25)
      (net 178 "/Ethernet/AVDDL_PLL") (pintype "passive"))
  )

  (footprint "data-center-rdimm-ddr4-tester-footprints:C_0402_1005Metric" (layer "F.Cu")
    (at 164.586328 93.374306 90)
    (descr "Capacitor SMD 0402")
    (tags "capacitor SMD 0402")
    (property "Author" "Antmicro")
    (property "Dielectric" "X7R")
    (property "License" "Apache-2.0")
    (property "MPN" "GRM155R71H103KA88D")
    (property "Manufacturer" "Murata")
    (property "Sheetfile" "ethernet.kicad_sch")
    (property "Sheetname" "Ethernet")
    (property "Val" "10n")
    (property "Voltage" "50V")
    (property "ki_description" " ")
    (attr smd)
    (fp_text reference "C135" (at -1.395694 1.313672 90) (layer "F.SilkS")
        (effects (font (size 0.7 0.7) (thickness 0.15)) (justify left bottom))
    )
    (fp_text value "C_10n_0402" (at 0 1.4 90) (layer "F.Fab") hide
        (effects (font (size 0.7 0.7) (thickness 0.15)) (justify left bottom))
    )
    (fp_text user "License: Apache-2.0" (at -0.932 5.17 90) (layer "F.Fab") hide
        (effects (font (size 0.7 0.7) (thickness 0.15)) (justify left bottom))
    )
    (fp_text user "Author: Antmicro" (at -0.932 4.17 90) (layer "F.Fab") hide
        (effects (font (size 0.7 0.7) (thickness 0.15)) (justify left bottom))
    )
    (fp_text user "${REFERENCE}" (at -0.932 3.168 90) (layer "F.Fab") hide
        (effects (font (size 0.7 0.7) (thickness 0.15)) (justify left bottom))
    )
    (fp_rect (start -0.94 -0.47) (end 0.94 0.47)
      (stroke (width 0.05) (type solid)) (fill none) (layer "F.CrtYd"))
    (fp_rect (start -0.499 -0.249) (end 0.499 0.249)
      (stroke (width 0.15) (type solid)) (fill none) (layer "F.Fab"))
    (pad "1" smd roundrect (at -0.484 0 90) (size 0.59 0.64) (layers "F.Cu" "F.Paste" "F.Mask") (roundrect_rratio 0.25)
      (net 306 "1V2_SYS") (pintype "passive"))
    (pad "2" smd roundrect (at 0.484 0 90) (size 0.59 0.64) (layers "F.Cu" "F.Paste" "F.Mask") (roundrect_rratio 0.25)
      (net 9 "GND") (pintype "passive"))
  )

  (footprint "data-center-rdimm-ddr4-tester-footprints:C_0402_1005Metric" (layer "F.Cu")
    (at 164.586328 96.774306 90)
    (descr "Capacitor SMD 0402")
    (tags "capacitor SMD 0402")
    (property "Author" "Antmicro")
    (property "Dielectric" "X7R")
    (property "License" "Apache-2.0")
    (property "MPN" "GRM155R71H103KA88D")
    (property "Manufacturer" "Murata")
    (property "Sheetfile" "ethernet.kicad_sch")
    (property "Sheetname" "Ethernet")
    (property "Val" "10n")
    (property "Voltage" "50V")
    (property "ki_description" " ")
    (attr smd)
    (fp_text reference "C139" (at -0.825694 2.363672 90) (layer "F.SilkS")
        (effects (font (size 0.7 0.7) (thickness 0.15)) (justify left bottom))
    )
    (fp_text value "C_10n_0402" (at 0 1.4 90) (layer "F.Fab") hide
        (effects (font (size 0.7 0.7) (thickness 0.15)) (justify left bottom))
    )
    (fp_text user "Author: Antmicro" (at -0.932 4.17 90) (layer "F.Fab") hide
        (effects (font (size 0.7 0.7) (thickness 0.15)) (justify left bottom))
    )
    (fp_text user "${REFERENCE}" (at -0.932 3.168 90) (layer "F.Fab") hide
        (effects (font (size 0.7 0.7) (thickness 0.15)) (justify left bottom))
    )
    (fp_text user "License: Apache-2.0" (at -0.932 5.17 90) (layer "F.Fab") hide
        (effects (font (size 0.7 0.7) (thickness 0.15)) (justify left bottom))
    )
    (fp_rect (start -0.94 -0.47) (end 0.94 0.47)
      (stroke (width 0.05) (type solid)) (fill none) (layer "F.CrtYd"))
    (fp_rect (start -0.499 -0.249) (end 0.499 0.249)
      (stroke (width 0.15) (type solid)) (fill none) (layer "F.Fab"))
    (pad "1" smd roundrect (at -0.484 0 90) (size 0.59 0.64) (layers "F.Cu" "F.Paste" "F.Mask") (roundrect_rratio 0.25)
      (net 143 "3V3_SYS") (pintype "passive"))
    (pad "2" smd roundrect (at 0.484 0 90) (size 0.59 0.64) (layers "F.Cu" "F.Paste" "F.Mask") (roundrect_rratio 0.25)
      (net 9 "GND") (pintype "passive"))
  )

  (footprint "data-center-rdimm-ddr4-tester-footprints:C_0402_1005Metric" (layer "F.Cu")
    (at 164.586328 99.1 -90)
    (descr "Capacitor SMD 0402")
    (tags "capacitor SMD 0402")
    (property "Author" "Antmicro")
    (property "Dielectric" "X7R")
    (property "License" "Apache-2.0")
    (property "MPN" "GRM155R71H103KA88D")
    (property "Manufacturer" "Murata")
    (property "Sheetfile" "ethernet.kicad_sch")
    (property "Sheetname" "Ethernet")
    (property "Val" "10n")
    (property "Voltage" "50V")
    (property "ki_description" " ")
    (attr smd)
    (fp_text reference "C142" (at 1.1 -2.363672 -90) (layer "F.SilkS")
        (effects (font (size 0.7 0.7) (thickness 0.15)) (justify left bottom))
    )
    (fp_text value "C_10n_0402" (at 0 1.4 -90) (layer "F.Fab") hide
        (effects (font (size 0.7 0.7) (thickness 0.15)) (justify left bottom))
    )
    (fp_text user "${REFERENCE}" (at -0.932 3.168 -90) (layer "F.Fab") hide
        (effects (font (size 0.7 0.7) (thickness 0.15)) (justify left bottom))
    )
    (fp_text user "License: Apache-2.0" (at -0.932 5.17 -90) (layer "F.Fab") hide
        (effects (font (size 0.7 0.7) (thickness 0.15)) (justify left bottom))
    )
    (fp_text user "Author: Antmicro" (at -0.932 4.17 -90) (layer "F.Fab") hide
        (effects (font (size 0.7 0.7) (thickness 0.15)) (justify left bottom))
    )
    (fp_rect (start -0.94 -0.47) (end 0.94 0.47)
      (stroke (width 0.05) (type solid)) (fill none) (layer "F.CrtYd"))
    (fp_rect (start -0.499 -0.249) (end 0.499 0.249)
      (stroke (width 0.15) (type solid)) (fill none) (layer "F.Fab"))
    (pad "1" smd roundrect (at -0.484 0 270) (size 0.59 0.64) (layers "F.Cu" "F.Paste" "F.Mask") (roundrect_rratio 0.25)
      (net 306 "1V2_SYS") (pintype "passive"))
    (pad "2" smd roundrect (at 0.484 0 270) (size 0.59 0.64) (layers "F.Cu" "F.Paste" "F.Mask") (roundrect_rratio 0.25)
      (net 9 "GND") (pintype "passive"))
  )

  (footprint "data-center-rdimm-ddr4-tester-footprints:C_0402_1005Metric" (layer "F.Cu")
    (at 149.186328 95.874306 180)
    (descr "Capacitor SMD 0402")
    (tags "capacitor SMD 0402")
    (property "Author" "Antmicro")
    (property "Dielectric" "")
    (property "License" "Apache-2.0")
    (property "MPN" "CC0402JRNPO9BN220")
    (property "Manufacturer" "Yaego")
    (property "Sheetfile" "ethernet.kicad_sch")
    (property "Sheetname" "Ethernet")
    (property "Val" "22p")
    (property "Voltage" "")
    (property "ki_description" " ")
    (attr smd)
    (fp_text reference "C147" (at -0.793672 -0.485694 180) (layer "F.SilkS")
        (effects (font (size 0.7 0.7) (thickness 0.15)) (justify left bottom))
    )
    (fp_text value "C_22p_0402" (at 0 1.4 180) (layer "F.Fab") hide
        (effects (font (size 0.7 0.7) (thickness 0.15)) (justify left bottom))
    )
    (fp_text user "${REFERENCE}" (at -0.932 3.168 180) (layer "F.Fab") hide
        (effects (font (size 0.7 0.7) (thickness 0.15)) (justify left bottom))
    )
    (fp_text user "Author: Antmicro" (at -0.932 4.17 180) (layer "F.Fab") hide
        (effects (font (size 0.7 0.7) (thickness 0.15)) (justify left bottom))
    )
    (fp_text user "License: Apache-2.0" (at -0.932 5.17 180) (layer "F.Fab") hide
        (effects (font (size 0.7 0.7) (thickness 0.15)) (justify left bottom))
    )
    (fp_rect (start -0.94 -0.47) (end 0.94 0.47)
      (stroke (width 0.05) (type solid)) (fill none) (layer "F.CrtYd"))
    (fp_rect (start -0.499 -0.249) (end 0.499 0.249)
      (stroke (width 0.15) (type solid)) (fill none) (layer "F.Fab"))
    (pad "1" smd roundrect (at -0.484 0 180) (size 0.59 0.64) (layers "F.Cu" "F.Paste" "F.Mask") (roundrect_rratio 0.25)
      (net 5 "Net-(U6-XO)") (pintype "passive"))
    (pad "2" smd roundrect (at 0.484 0 180) (size 0.59 0.64) (layers "F.Cu" "F.Paste" "F.Mask") (roundrect_rratio 0.25)
      (net 9 "GND") (pintype "passive"))
  )

  (footprint "data-center-rdimm-ddr4-tester-footprints:C_0402_1005Metric" (layer "F.Cu")
    (at 147.986328 100.674306)
    (descr "Capacitor SMD 0402")
    (tags "capacitor SMD 0402")
    (property "Author" "Antmicro")
    (property "Dielectric" "")
    (property "License" "Apache-2.0")
    (property "MPN" "CC0402JRNPO9BN220")
    (property "Manufacturer" "Yaego")
    (property "Sheetfile" "ethernet.kicad_sch")
    (property "Sheetname" "Ethernet")
    (property "Val" "22p")
    (property "Voltage" "")
    (property "ki_description" " ")
    (attr smd)
    (fp_text reference "C148" (at 0.803672 0.535694) (layer "F.SilkS")
        (effects (font (size 0.7 0.7) (thickness 0.15)) (justify left bottom))
    )
    (fp_text value "C_22p_0402" (at 0 1.4) (layer "F.Fab") hide
        (effects (font (size 0.7 0.7) (thickness 0.15)) (justify left bottom))
    )
    (fp_text user "Author: Antmicro" (at -0.932 4.17) (layer "F.Fab") hide
        (effects (font (size 0.7 0.7) (thickness 0.15)) (justify left bottom))
    )
    (fp_text user "License: Apache-2.0" (at -0.932 5.17) (layer "F.Fab") hide
        (effects (font (size 0.7 0.7) (thickness 0.15)) (justify left bottom))
    )
    (fp_text user "${REFERENCE}" (at -0.932 3.168) (layer "F.Fab") hide
        (effects (font (size 0.7 0.7) (thickness 0.15)) (justify left bottom))
    )
    (fp_rect (start -0.94 -0.47) (end 0.94 0.47)
      (stroke (width 0.05) (type solid)) (fill none) (layer "F.CrtYd"))
    (fp_rect (start -0.499 -0.249) (end 0.499 0.249)
      (stroke (width 0.15) (type solid)) (fill none) (layer "F.Fab"))
    (pad "1" smd roundrect (at -0.484 0) (size 0.59 0.64) (layers "F.Cu" "F.Paste" "F.Mask") (roundrect_rratio 0.25)
      (net 6 "Net-(U6-XI)") (pintype "passive"))
    (pad "2" smd roundrect (at 0.484 0) (size 0.59 0.64) (layers "F.Cu" "F.Paste" "F.Mask") (roundrect_rratio 0.25)
      (net 9 "GND") (pintype "passive"))
  )

  (footprint "data-center-rdimm-ddr4-tester-footprints:FB_0603_1608Metric" (layer "F.Cu")
    (at 147.486328 94.610008 180)
    (property "Author" "Antmicro")
    (property "License" "Apache-2.0")
    (property "MPN" "BLM18PG121SN1D")
    (property "Manufacturer" "Murata")
    (property "Sheetfile" "ethernet.kicad_sch")
    (property "Sheetname" "Ethernet")
    (property "ki_description" "Ferrite Beads WE-TMSB Suppression 240Ohm 200mA ")
    (property "ki_keywords" " Multilayer Suppression Beads ")
    (attr smd)
    (fp_text reference "FB2" (at 1.886328 -1.559992 180) (layer "F.SilkS")
        (effects (font (size 0.7 0.7) (thickness 0.15)) (justify left bottom))
    )
    (fp_text value "FB_120Z_2A_0603" (at 0 1.7 180) (layer "F.Fab") hide
        (effects (font (size 0.7 0.7) (thickness 0.15)) (justify left bottom))
    )
    (fp_text user "${REFERENCE}" (at -1.653 4.6 180) (layer "F.Fab") hide
        (effects (font (size 0.7 0.7) (thickness 0.15)) (justify left bottom))
    )
    (fp_text user "Author: Antmicro" (at -1.653 3.162 180) (layer "F.Fab") hide
        (effects (font (size 0.7 0.7) (thickness 0.15)) (justify left bottom))
    )
    (fp_text user "License: Apache-2.0" (at -1.653 5.9 180) (layer "F.Fab") hide
        (effects (font (size 0.7 0.7) (thickness 0.15)) (justify left bottom))
    )
    (fp_line (start -0.196 -0.408) (end 0.193 -0.408)
      (stroke (width 0.15) (type solid)) (layer "F.SilkS"))
    (fp_line (start -0.196 0.406) (end 0.193 0.406)
      (stroke (width 0.15) (type solid)) (layer "F.SilkS"))
    (fp_rect (start -1.3 -0.6) (end 1.3 0.6)
      (stroke (width 0.05) (type solid)) (fill none) (layer "F.CrtYd"))
    (fp_line (start -0.803 0.406) (end -0.803 -0.408)
      (stroke (width 0.15) (type solid)) (layer "F.Fab"))
    (fp_line (start 0.8 -0.408) (end -0.803 -0.408)
      (stroke (width 0.15) (type solid)) (layer "F.Fab"))
    (fp_line (start 0.8 -0.408) (end 0.8 0.406)
      (stroke (width 0.15) (type solid)) (layer "F.Fab"))
    (fp_line (start 0.8 0.406) (end -0.803 0.406)
      (stroke (width 0.15) (type solid)) (layer "F.Fab"))
    (pad "1" smd roundrect (at -0.891 0 180) (size 0.762 1.09) (layers "F.Cu" "F.Paste" "F.Mask") (roundrect_rratio 0.15)
      (net 178 "/Ethernet/AVDDL_PLL") (pintype "passive"))
    (pad "2" smd roundrect (at 0.888 0 180) (size 0.762 1.09) (layers "F.Cu" "F.Paste" "F.Mask") (roundrect_rratio 0.15)
      (net 306 "1V2_SYS") (pintype "passive"))
  )

  (footprint "data-center-rdimm-ddr4-tester-footprints:R_0402_1005Metric" (layer "F.Cu")
    (at 151.586328 99.474306 90)
    (descr "Resistor SMD 0402")
    (tags "resistor SMD 0402")
    (property "Author" "Antmicro")
    (property "License" "Apache-2.0")
    (property "MPN" "CR0402-FX-1212GLF")
    (property "Manufacturer" "Bourns")
    (property "Sheetfile" "ethernet.kicad_sch")
    (property "Sheetname" "Ethernet")
    (property "Tolerance" "1%")
    (property "Val" "12k1")
    (property "ki_description" "12k1 resistor in 0402 package with 1% tolerance")
    (attr smd)
    (fp_text reference "R68" (at -1.145694 1.283672 90) (layer "F.SilkS")
        (effects (font (size 0.7 0.7) (thickness 0.15)) (justify left bottom))
    )
    (fp_text value "R_12k1_0402" (at 0 1.4 90) (layer "F.Fab") hide
        (effects (font (size 0.7 0.7) (thickness 0.15)) (justify left bottom))
    )
    (fp_text user "Author: Antmicro" (at -0.95 4.169 90) (layer "F.Fab") hide
        (effects (font (size 0.7 0.7) (thickness 0.15)) (justify left bottom))
    )
    (fp_text user "${REFERENCE}" (at -0.95 3.168 90) (layer "F.Fab") hide
        (effects (font (size 0.7 0.7) (thickness 0.15)) (justify left bottom))
    )
    (fp_text user "License: Apache-2.0" (at -0.95 5.169 90) (layer "F.Fab") hide
        (effects (font (size 0.7 0.7) (thickness 0.15)) (justify left bottom))
    )
    (fp_rect (start -0.93 -0.47) (end 0.93 0.47)
      (stroke (width 0.05) (type solid)) (fill none) (layer "F.CrtYd"))
    (fp_rect (start -0.5 -0.25) (end 0.5 0.25)
      (stroke (width 0.15) (type solid)) (fill none) (layer "F.Fab"))
    (pad "1" smd roundrect (at -0.485 0 90) (size 0.59 0.64) (layers "F.Cu" "F.Paste" "F.Mask") (roundrect_rratio 0.25)
      (net 9 "GND") (pintype "passive"))
    (pad "2" smd roundrect (at 0.485 0 90) (size 0.59 0.64) (layers "F.Cu" "F.Paste" "F.Mask") (roundrect_rratio 0.25)
      (net 652 "Net-(U6-ISET)") (pintype "passive"))
  )

  (footprint "data-center-rdimm-ddr4-tester-footprints:R_0402_1005Metric" (layer "F.Cu")
    (at 151.586328 97.474306 -90)
    (descr "Resistor SMD 0402")
    (tags "resistor SMD 0402")
    (property "Author" "Antmicro")
    (property "License" "Apache-2.0")
    (property "MPN" "CR0402-FX-1804GLF")
    (property "Manufacturer" "Bourns")
    (property "Sheetfile" "ethernet.kicad_sch")
    (property "Sheetname" "Ethernet")
    (property "Tolerance" "1%")
    (property "Val" "1M8")
    (property "ki_description" "1M8 resistor in 0402 package with 1% tolerance")
    (attr smd)
    (fp_text reference "R69" (at 1.125694 -1.313672 -90) (layer "F.SilkS")
        (effects (font (size 0.7 0.7) (thickness 0.15)) (justify left bottom))
    )
    (fp_text value "R_1M8_0402" (at 0 1.4 -90) (layer "F.Fab") hide
        (effects (font (size 0.7 0.7) (thickness 0.15)) (justify left bottom))
    )
    (fp_text user "${REFERENCE}" (at -0.95 3.168 -90) (layer "F.Fab") hide
        (effects (font (size 0.7 0.7) (thickness 0.15)) (justify left bottom))
    )
    (fp_text user "License: Apache-2.0" (at -0.95 5.169 -90) (layer "F.Fab") hide
        (effects (font (size 0.7 0.7) (thickness 0.15)) (justify left bottom))
    )
    (fp_text user "Author: Antmicro" (at -0.95 4.169 -90) (layer "F.Fab") hide
        (effects (font (size 0.7 0.7) (thickness 0.15)) (justify left bottom))
    )
    (fp_rect (start -0.93 -0.47) (end 0.93 0.47)
      (stroke (width 0.05) (type solid)) (fill none) (layer "F.CrtYd"))
    (fp_rect (start -0.5 -0.25) (end 0.5 0.25)
      (stroke (width 0.15) (type solid)) (fill none) (layer "F.Fab"))
    (pad "1" smd roundrect (at -0.485 0 270) (size 0.59 0.64) (layers "F.Cu" "F.Paste" "F.Mask") (roundrect_rratio 0.25)
      (net 5 "Net-(U6-XO)") (pintype "passive"))
    (pad "2" smd roundrect (at 0.485 0 270) (size 0.59 0.64) (layers "F.Cu" "F.Paste" "F.Mask") (roundrect_rratio 0.25)
      (net 6 "Net-(U6-XI)") (pintype "passive"))
  )

  (footprint "data-center-rdimm-ddr4-tester-footprints:Oscillator_SMD_Geyer_KX-7-4Pin_3.2x2.5mm" (layer "F.Cu")
    (at 148.686328 98.274306 180)
    (property "Author" "Antmicro")
    (property "License" "Apache-2.0")
    (property "MPN" "ABM8G-25.000MHZ-18-D2Y-T")
    (property "Manufacturer" "Abracon")
    (property "Sheetfile" "ethernet.kicad_sch")
    (property "Sheetname" "Ethernet")
    (property "Val" "25MHz")
    (property "ki_description" "25 MHz ±20ppm Crystal 18pF 60 Ohms 4-SMD, No Lead")
    (attr smd)
    (fp_text reference "Y1" (at 3.286328 0.854306) (layer "F.SilkS")
        (effects (font (size 0.7 0.7) (thickness 0.15)) (justify left bottom))
    )
    (fp_text value "Oscillator_SMD_25MHz_KX-7" (at -1.75 2.548 180) (layer "F.Fab") hide
        (effects (font (size 0.7 0.7) (thickness 0.15)) (justify left bottom))
    )
    (fp_text user "License: Apache-2.0" (at -1.75 6.5 180) (layer "F.Fab") hide
        (effects (font (size 0.7 0.7) (thickness 0.15)) (justify left bottom))
    )
    (fp_text user "${REFERENCE}" (at -1.75 3.75 180) (layer "F.Fab") hide
        (effects (font (size 0.7 0.7) (thickness 0.15)) (justify left bottom))
    )
    (fp_text user "Author: Antmicro" (at -1.75 5 180) (layer "F.Fab") hide
        (effects (font (size 0.7 0.7) (thickness 0.15)) (justify left bottom))
    )
    (fp_line (start -1.6 0.3) (end -1.6 -0.2)
      (stroke (width 0.15) (type solid)) (layer "F.SilkS"))
    (fp_line (start -0.35 -1.25) (end 0.45 -1.25)
      (stroke (width 0.15) (type solid)) (layer "F.SilkS"))
    (fp_line (start -0.35 1.25) (end 0.45 1.25)
      (stroke (width 0.15) (type solid)) (layer "F.SilkS"))
    (fp_line (start 1.6 0.3) (end 1.6 -0.2)
      (stroke (width 0.15) (type solid)) (layer "F.SilkS"))
    (fp_circle (center -1.75 1.5) (end -1.7 1.5)
      (stroke (width 0.15) (type solid)) (fill none) (layer "F.SilkS"))
    (fp_rect (start -1.907 -1.55) (end 2.006 1.649)
      (stroke (width 0.05) (type solid)) (fill none) (layer "F.CrtYd"))
    (pad "1" smd roundrect (at -1.101 0.949 180) (size 1.3 1.1) (layers "F.Cu" "F.Paste" "F.Mask") (roundrect_rratio 0)
      (chamfer_ratio 0.2) (chamfer bottom_left)
      (net 5 "Net-(U6-XO)") (pintype "passive"))
    (pad "2" smd rect (at 1.199 0.949 180) (size 1.3 1.1) (layers "F.Cu" "F.Paste" "F.Mask")
      (net 9 "GND") (pinfunction "SH") (pintype "passive"))
    (pad "3" smd rect (at 1.199 -0.85 180) (size 1.3 1.1) (layers "F.Cu" "F.Paste" "F.Mask")
      (net 6 "Net-(U6-XI)") (pintype "passive"))
    (pad "4" smd rect (at -1.101 -0.85 180) (size 1.3 1.1) (layers "F.Cu" "F.Paste" "F.Mask")
      (net 9 "GND") (pinfunction "SH") (pintype "passive"))
  )

  (footprint "data-center-rdimm-ddr4-tester-footprints:QFN-48-1EP_7x7x0.9mm_P0.5mm_EP3.5x3.5mm" (layer "F.Cu")
    (at 158.436328 96.047157 90)
    (property "Author" "Antmicro")
    (property "License" "Apache-2.0")
    (property "MPN" "KSZ9031RNXCA")
    (property "Manufacturer" "Microchip Technology")
    (property "Sheetfile" "ethernet.kicad_sch")
    (property "Sheetname" "Ethernet")
    (property "ki_description" "Ethernet Controller, 1000 Mbps, IEEE 802.3, 1.14 V, 3.465 V, QFN, 48 Pins")
    (property "ki_keywords" "SMT, TRANSCEIVER, IC, ETHERNET, PHY")
    (attr smd)
    (fp_text reference "U6" (at -4.282843 -4.3 90) (layer "F.SilkS")
        (effects (font (size 0.7 0.7) (thickness 0.15)) (justify left bottom))
    )
    (fp_text value "KSZ9031RNXCA" (at 0 5.1 90) (layer "F.Fab") hide
        (effects (font (size 0.7 0.7) (thickness 0.15)) (justify left bottom))
    )
    (fp_text user "${REFERENCE}" (at -4.202 7.2 90) (layer "F.Fab") hide
        (effects (font (size 0.7 0.7) (thickness 0.15)) (justify left bottom))
    )
    (fp_text user "Author: Antmicro" (at -4.202 8.4 90) (layer "F.Fab") hide
        (effects (font (size 0.7 0.7) (thickness 0.15)) (justify left bottom))
    )
    (fp_text user "License: Apache-2.0" (at -4.202 9.598 90) (layer "F.Fab") hide
        (effects (font (size 0.7 0.7) (thickness 0.15)) (justify left bottom))
    )
    (fp_line (start -3.65 -3.3) (end -3.65 -3.65)
      (stroke (width 0.15) (type solid)) (layer "F.SilkS"))
    (fp_line (start -3.65 3.648) (end -3.65 3.249)
      (stroke (width 0.15) (type solid)) (layer "F.SilkS"))
    (fp_line (start -3.3 -3.65) (end -3.65 -3.65)
      (stroke (width 0.15) (type solid)) (layer "F.SilkS"))
    (fp_line (start -3.25 3.648) (end -3.65 3.648)
      (stroke (width 0.15) (type solid)) (layer "F.SilkS"))
    (fp_line (start 3.249 -3.65) (end 3.648 -3.65)
      (stroke (width 0.15) (type solid)) (layer "F.SilkS"))
    (fp_line (start 3.249 3.648) (end 3.648 3.648)
      (stroke (width 0.15) (type solid)) (layer "F.SilkS"))
    (fp_line (start 3.648 -3.65) (end 3.648 -3.25)
      (stroke (width 0.15) (type solid)) (layer "F.SilkS"))
    (fp_line (start 3.648 3.648) (end 3.648 3.249)
      (stroke (width 0.15) (type solid)) (layer "F.SilkS"))
    (fp_circle (center -3.7 -3.05) (end -3.65 -3.05)
      (stroke (width 0.15) (type solid)) (fill solid) (layer "F.SilkS"))
    (fp_rect (start -4.15 -4.15) (end 4.15 4.15)
      (stroke (width 0.05) (type solid)) (fill none) (layer "F.CrtYd"))
    (fp_line (start -3.5 -2.5) (end -3.5 3.499)
      (stroke (width 0.15) (type solid)) (layer "F.Fab"))
    (fp_line (start -3.5 3.499) (end 3.499 3.499)
      (stroke (width 0.15) (type solid)) (layer "F.Fab"))
    (fp_line (start -2.5 -3.5) (end -3.5 -2.5)
      (stroke (width 0.15) (type solid)) (layer "F.Fab"))
    (fp_line (start 3.499 -3.5) (end -2.5 -3.5)
      (stroke (width 0.15) (type solid)) (layer "F.Fab"))
    (fp_line (start 3.499 3.499) (end 3.499 -3.5)
      (stroke (width 0.15) (type solid)) (layer "F.Fab"))
    (pad "1" smd oval (at -3.5 -2.75 180) (size 0.3 0.9) (layers "F.Cu" "F.Paste" "F.Mask")
      (net 179 "/Ethernet/AVDDH") (pinfunction "AVDDH") (pintype "power_in"))
    (pad "2" smd oval (at -3.5 -2.25 180) (size 0.3 0.9) (layers "F.Cu" "F.Paste" "F.Mask")
      (net 170 "/Ethernet/ETH1_P") (pinfunction "TXRXP_A") (pintype "bidirectional"))
    (pad "3" smd oval (at -3.5 -1.75 180) (size 0.3 0.9) (layers "F.Cu" "F.Paste" "F.Mask")
      (net 173 "/Ethernet/ETH1_N") (pinfunction "TXRXM_A") (pintype "bidirectional"))
    (pad "4" smd oval (at -3.5 -1.25 180) (size 0.3 0.9) (layers "F.Cu" "F.Paste" "F.Mask")
      (net 177 "/Ethernet/AVDDL") (pinfunction "AVDDL") (pintype "power_in"))
    (pad "5" smd oval (at -3.5 -0.75 180) (size 0.3 0.9) (layers "F.Cu" "F.Paste" "F.Mask")
      (net 169 "/Ethernet/ETH2_P") (pinfunction "TXRXP_B") (pintype "bidirectional"))
    (pad "6" smd oval (at -3.5 -0.25 180) (size 0.3 0.9) (layers "F.Cu" "F.Paste" "F.Mask")
      (net 172 "/Ethernet/ETH2_N") (pinfunction "TXRXM_B") (pintype "bidirectional"))
    (pad "7" smd oval (at -3.5 0.248 180) (size 0.3 0.9) (layers "F.Cu" "F.Paste" "F.Mask")
      (net 168 "/Ethernet/ETH3_P") (pinfunction "TXRXP_C") (pintype "bidirectional"))
    (pad "8" smd oval (at -3.5 0.748 180) (size 0.3 0.9) (layers "F.Cu" "F.Paste" "F.Mask")
      (net 174 "/Ethernet/ETH3_N") (pinfunction "TXRXM_C") (pintype "bidirectional"))
    (pad "9" smd oval (at -3.5 1.249 180) (size 0.3 0.9) (layers "F.Cu" "F.Paste" "F.Mask")
      (net 177 "/Ethernet/AVDDL") (pinfunction "AVDDL") (pintype "passive"))
    (pad "10" smd oval (at -3.5 1.749 180) (size 0.3 0.9) (layers "F.Cu" "F.Paste" "F.Mask")
      (net 171 "/Ethernet/ETH4_P") (pinfunction "TXRXP_D") (pintype "bidirectional"))
    (pad "11" smd oval (at -3.5 2.249 180) (size 0.3 0.9) (layers "F.Cu" "F.Paste" "F.Mask")
      (net 175 "/Ethernet/ETH4_N") (pinfunction "TXRXM_D") (pintype "bidirectional"))
    (pad "12" smd oval (at -3.5 2.749 180) (size 0.3 0.9) (layers "F.Cu" "F.Paste" "F.Mask")
      (net 179 "/Ethernet/AVDDH") (pinfunction "AVDDH") (pintype "passive"))
    (pad "13" smd oval (at -2.75 3.499 90) (size 0.3 0.9) (layers "F.Cu" "F.Paste" "F.Mask")
      (net 670 "unconnected-(U6-NC-Pad13)") (pinfunction "NC") (pintype "no_connect"))
    (pad "14" smd oval (at -2.25 3.499 90) (size 0.3 0.9) (layers "F.Cu" "F.Paste" "F.Mask")
      (net 306 "1V2_SYS") (pinfunction "DVDDL") (pintype "power_in"))
    (pad "15" smd oval (at -1.75 3.499 90) (size 0.3 0.9) (layers "F.Cu" "F.Paste" "F.Mask")
      (net 17 "LED_SPD") (pinfunction "LED2/PHYAD1") (pintype "bidirectional"))
    (pad "16" smd oval (at -1.25 3.499 90) (size 0.3 0.9) (layers "F.Cu" "F.Paste" "F.Mask")
      (net 143 "3V3_SYS") (pinfunction "DVDDH") (pintype "power_in"))
    (pad "17" smd oval (at -0.75 3.499 90) (size 0.3 0.9) (layers "F.Cu" "F.Paste" "F.Mask")
      (net 16 "LED_LINK") (pinfunction "LED1/PHAD0/PME_N1") (pintype "bidirectional"))
    (pad "18" smd oval (at -0.25 3.499 90) (size 0.3 0.9) (layers "F.Cu" "F.Paste" "F.Mask")
      (net 306 "1V2_SYS") (pinfunction "DVDDL") (pintype "passive"))
    (pad "19" smd oval (at 0.248 3.499 90) (size 0.3 0.9) (layers "F.Cu" "F.Paste" "F.Mask")
      (net 36 "ETH_TXD0") (pinfunction "TXD0") (pintype "input"))
    (pad "20" smd oval (at 0.748 3.499 90) (size 0.3 0.9) (layers "F.Cu" "F.Paste" "F.Mask")
      (net 31 "ETH_TXD1") (pinfunction "TXD1") (pintype "input"))
    (pad "21" smd oval (at 1.249 3.499 90) (size 0.3 0.9) (layers "F.Cu" "F.Paste" "F.Mask")
      (net 32 "ETH_TXD2") (pinfunction "TXD2") (pintype "input"))
    (pad "22" smd oval (at 1.749 3.499 90) (size 0.3 0.9) (layers "F.Cu" "F.Paste" "F.Mask")
      (net 33 "ETH_TXD3") (pinfunction "TXD3") (pintype "input"))
    (pad "23" smd oval (at 2.249 3.499 90) (size 0.3 0.9) (layers "F.Cu" "F.Paste" "F.Mask")
      (net 306 "1V2_SYS") (pinfunction "DVDDL") (pintype "passive"))
    (pad "24" smd oval (at 2.749 3.499 90) (size 0.3 0.9) (layers "F.Cu" "F.Paste" "F.Mask")
      (net 34 "ETH_TX_CLK") (pinfunction "GTX_CLK") (pintype "input"))
    (pad "25" smd oval (at 3.499 2.749 180) (size 0.3 0.9) (layers "F.Cu" "F.Paste" "F.Mask")
      (net 35 "ETH_TX_EN") (pinfunction "TX_EN") (pintype "input"))
    (pad "26" smd oval (at 3.499 2.249 180) (size 0.3 0.9) (layers "F.Cu" "F.Paste" "F.Mask")
      (net 306 "1V2_SYS") (pinfunction "DVDDL") (pintype "passive"))
    (pad "27" smd oval (at 3.499 1.749 180) (size 0.3 0.9) (layers "F.Cu" "F.Paste" "F.Mask")
      (net 37 "ETH_RXD3") (pinfunction "RXD3/MODE3") (pintype "input"))
    (pad "28" smd oval (at 3.499 1.249 180) (size 0.3 0.9) (layers "F.Cu" "F.Paste" "F.Mask")
      (net 41 "ETH_RXD2") (pinfunction "RXD2/MODE2") (pintype "input"))
    (pad "29" smd oval (at 3.499 0.748 180) (size 0.3 0.9) (layers "F.Cu" "F.Paste" "F.Mask")
      (net 9 "GND") (pinfunction "VSS") (pintype "power_in"))
    (pad "30" smd oval (at 3.499 0.248 180) (size 0.3 0.9) (layers "F.Cu" "F.Paste" "F.Mask")
      (net 306 "1V2_SYS") (pinfunction "DVDDL") (pintype "passive"))
    (pad "31" smd oval (at 3.499 -0.25 180) (size 0.3 0.9) (layers "F.Cu" "F.Paste" "F.Mask")
      (net 27 "ETH_RXD1") (pinfunction "RXD1/MODE1") (pintype "input"))
    (pad "32" smd oval (at 3.499 -0.75 180) (size 0.3 0.9) (layers "F.Cu" "F.Paste" "F.Mask")
      (net 26 "ETH_RXD0") (pinfunction "RXD0/MODE0") (pintype "input"))
    (pad "33" smd oval (at 3.499 -1.25 180) (size 0.3 0.9) (layers "F.Cu" "F.Paste" "F.Mask")
      (net 38 "ETH_RX_DV") (pinfunction "RX_DV/CLK125_EN") (pintype "input"))
    (pad "34" smd oval (at 3.499 -1.75 180) (size 0.3 0.9) (layers "F.Cu" "F.Paste" "F.Mask")
      (net 143 "3V3_SYS") (pinfunction "DVDDH") (pintype "passive"))
    (pad "35" smd oval (at 3.499 -2.25 180) (size 0.3 0.9) (layers "F.Cu" "F.Paste" "F.Mask")
      (net 40 "ETH_RX_CLK") (pinfunction "RX_CLK/PHYAD2") (pintype "input"))
    (pad "36" smd oval (at 3.499 -2.75 180) (size 0.3 0.9) (layers "F.Cu" "F.Paste" "F.Mask")
      (net 39 "ETH_MDC") (pinfunction "MDC") (pintype "input"))
    (pad "37" smd oval (at 2.749 -3.5 90) (size 0.3 0.9) (layers "F.Cu" "F.Paste" "F.Mask")
      (net 29 "ETH_MDIO") (pinfunction "MDIO") (pintype "input"))
    (pad "38" smd oval (at 2.249 -3.5 90) (size 0.3 0.9) (layers "F.Cu" "F.Paste" "F.Mask")
      (net 183 "ETH_INT_N") (pinfunction "~{INT/PME}") (pintype "input"))
    (pad "39" smd oval (at 1.749 -3.5 90) (size 0.3 0.9) (layers "F.Cu" "F.Paste" "F.Mask")
      (net 306 "1V2_SYS") (pinfunction "DVDDL") (pintype "passive"))
    (pad "40" smd oval (at 1.249 -3.5 90) (size 0.3 0.9) (layers "F.Cu" "F.Paste" "F.Mask")
      (net 143 "3V3_SYS") (pinfunction "DVDDH") (pintype "passive"))
    (pad "41" smd oval (at 0.748 -3.5 90) (size 0.3 0.9) (layers "F.Cu" "F.Paste" "F.Mask")
      (net 30 "ETH_REF_CLK") (pinfunction "CLK125_NDO/LED_MODE") (pintype "input"))
    (pad "42" smd oval (at 0.248 -3.5 90) (size 0.3 0.9) (layers "F.Cu" "F.Paste" "F.Mask")
      (net 28 "ETH_RSTN") (pinfunction "~{RESET}") (pintype "input"))
    (pad "43" smd oval (at -0.25 -3.5 90) (size 0.3 0.9) (layers "F.Cu" "F.Paste" "F.Mask")
      (net 671 "unconnected-(U6-LDO_O-Pad43)") (pinfunction "LDO_O") (pintype "input+no_connect"))
    (pad "44" smd oval (at -0.75 -3.5 90) (size 0.3 0.9) (layers "F.Cu" "F.Paste" "F.Mask")
      (net 178 "/Ethernet/AVDDL_PLL") (pinfunction "AVDDL_PLL") (pintype "power_in"))
    (pad "45" smd oval (at -1.25 -3.5 90) (size 0.3 0.9) (layers "F.Cu" "F.Paste" "F.Mask")
      (net 5 "Net-(U6-XO)") (pinfunction "XO") (pintype "input"))
    (pad "46" smd oval (at -1.75 -3.5 90) (size 0.3 0.9) (layers "F.Cu" "F.Paste" "F.Mask")
      (net 6 "Net-(U6-XI)") (pinfunction "XI") (pintype "input"))
    (pad "47" smd oval (at -2.25 -3.5 90) (size 0.3 0.9) (layers "F.Cu" "F.Paste" "F.Mask")
      (net 672 "unconnected-(U6-NC-Pad47)") (pinfunction "NC") (pintype "no_connect"))
    (pad "48" smd oval (at -2.75 -3.5 90) (size 0.3 0.9) (layers "F.Cu" "F.Paste" "F.Mask")
      (net 652 "Net-(U6-ISET)") (pinfunction "ISET") (pintype "output"))
    (pad "49" smd rect (at 0 0 90) (size 3.5 3.5) (layers "F.Cu" "F.Paste" "F.Mask")
      (net 9 "GND") (pinfunction "PAD_GND") (pintype "power_in"))
  )

  (footprint "data-center-rdimm-ddr4-tester-footprints:R_0402_1005Metric" (layer "F.Cu")
    (at 208.63 113.135 -90)
    (descr "Resistor SMD 0402")
    (tags "resistor SMD 0402")
    (property "Author" "Antmicro")
    (property "Current" "1A")
    (property "License" "Apache-2.0")
    (property "MPN" "ERJ2GE0R00X")
    (property "Manufacturer" "Panasonic")
    (property "Sheetfile" "interfaces.kicad_sch")
    (property "Sheetname" "Interfaces")
    (property "Tolerance" "")
    (property "Val" "0R")
    (property "ki_description" "0R resistor in 0402 package with unspecified tolerance")
    (attr smd)
    (fp_text reference "R139" (at -3.515 -0.34 -90) (layer "F.SilkS")
        (effects (font (size 0.7 0.7) (thickness 0.15)) (justify left bottom))
    )
    (fp_text value "R_0R_0402" (at 0 1.4 -90) (layer "F.Fab") hide
        (effects (font (size 0.7 0.7) (thickness 0.15)) (justify left bottom))
    )
    (fp_text user "${REFERENCE}" (at -0.95 3.168 -90) (layer "F.Fab") hide
        (effects (font (size 0.7 0.7) (thickness 0.15)) (justify left bottom))
    )
    (fp_text user "License: Apache-2.0" (at -0.95 5.169 -90) (layer "F.Fab") hide
        (effects (font (size 0.7 0.7) (thickness 0.15)) (justify left bottom))
    )
    (fp_text user "Author: Antmicro" (at -0.95 4.169 -90) (layer "F.Fab") hide
        (effects (font (size 0.7 0.7) (thickness 0.15)) (justify left bottom))
    )
    (fp_rect (start -0.93 -0.47) (end 0.93 0.47)
      (stroke (width 0.05) (type solid)) (fill none) (layer "F.CrtYd"))
    (fp_rect (start -0.5 -0.25) (end 0.5 0.25)
      (stroke (width 0.15) (type solid)) (fill none) (layer "F.Fab"))
    (pad "1" smd roundrect (at -0.485 0 270) (size 0.59 0.64) (layers "F.Cu" "F.Paste" "F.Mask") (roundrect_rratio 0.25)
      (net 56 "TMDS_CLK_N") (pintype "passive"))
    (pad "2" smd roundrect (at 0.485 0 270) (size 0.59 0.64) (layers "F.Cu" "F.Paste" "F.Mask") (roundrect_rratio 0.25)
      (net 43 "C_TMDS_CLK_N") (pintype "passive"))
  )

  (footprint "data-center-rdimm-ddr4-tester-footprints:R_0402_1005Metric" (layer "F.Cu")
    (at 209.655 113.135 -90)
    (descr "Resistor SMD 0402")
    (tags "resistor SMD 0402")
    (property "Author" "Antmicro")
    (property "Current" "1A")
    (property "License" "Apache-2.0")
    (property "MPN" "ERJ2GE0R00X")
    (property "Manufacturer" "Panasonic")
    (property "Sheetfile" "interfaces.kicad_sch")
    (property "Sheetname" "Interfaces")
    (property "Tolerance" "")
    (property "Val" "0R")
    (property "ki_description" "0R resistor in 0402 package with unspecified tolerance")
    (attr smd)
    (fp_text reference "R140" (at -3.515 -0.34 -90) (layer "F.SilkS")
        (effects (font (size 0.7 0.7) (thickness 0.15)) (justify left bottom))
    )
    (fp_text value "R_0R_0402" (at 0 1.4 -90) (layer "F.Fab") hide
        (effects (font (size 0.7 0.7) (thickness 0.15)) (justify left bottom))
    )
    (fp_text user "Author: Antmicro" (at -0.95 4.169 -90) (layer "F.Fab") hide
        (effects (font (size 0.7 0.7) (thickness 0.15)) (justify left bottom))
    )
    (fp_text user "${REFERENCE}" (at -0.95 3.168 -90) (layer "F.Fab") hide
        (effects (font (size 0.7 0.7) (thickness 0.15)) (justify left bottom))
    )
    (fp_text user "License: Apache-2.0" (at -0.95 5.169 -90) (layer "F.Fab") hide
        (effects (font (size 0.7 0.7) (thickness 0.15)) (justify left bottom))
    )
    (fp_rect (start -0.93 -0.47) (end 0.93 0.47)
      (stroke (width 0.05) (type solid)) (fill none) (layer "F.CrtYd"))
    (fp_rect (start -0.5 -0.25) (end 0.5 0.25)
      (stroke (width 0.15) (type solid)) (fill none) (layer "F.Fab"))
    (pad "1" smd roundrect (at -0.485 0 270) (size 0.59 0.64) (layers "F.Cu" "F.Paste" "F.Mask") (roundrect_rratio 0.25)
      (net 55 "TMDS_CLK_P") (pintype "passive"))
    (pad "2" smd roundrect (at 0.485 0 270) (size 0.59 0.64) (layers "F.Cu" "F.Paste" "F.Mask") (roundrect_rratio 0.25)
      (net 42 "C_TMDS_CLK_P") (pintype "passive"))
  )

  (footprint "data-center-rdimm-ddr4-tester-footprints:R_0402_1005Metric" (layer "F.Cu")
    (at 210.14 115.35 -90)
    (descr "Resistor SMD 0402")
    (tags "resistor SMD 0402")
    (property "Author" "Antmicro")
    (property "Current" "1A")
    (property "License" "Apache-2.0")
    (property "MPN" "ERJ2GE0R00X")
    (property "Manufacturer" "Panasonic")
    (property "Sheetfile" "interfaces.kicad_sch")
    (property "Sheetname" "Interfaces")
    (property "Tolerance" "")
    (property "Val" "0R")
    (property "ki_description" "0R resistor in 0402 package with unspecified tolerance")
    (attr smd)
    (fp_text reference "R141" (at -3.105 -0.35 -90) (layer "F.SilkS")
        (effects (font (size 0.7 0.7) (thickness 0.15)) (justify left bottom))
    )
    (fp_text value "R_0R_0402" (at 0 1.4 -90) (layer "F.Fab") hide
        (effects (font (size 0.7 0.7) (thickness 0.15)) (justify left bottom))
    )
    (fp_text user "Author: Antmicro" (at -0.95 4.169 -90) (layer "F.Fab") hide
        (effects (font (size 0.7 0.7) (thickness 0.15)) (justify left bottom))
    )
    (fp_text user "License: Apache-2.0" (at -0.95 5.169 -90) (layer "F.Fab") hide
        (effects (font (size 0.7 0.7) (thickness 0.15)) (justify left bottom))
    )
    (fp_text user "${REFERENCE}" (at -0.95 3.168 -90) (layer "F.Fab") hide
        (effects (font (size 0.7 0.7) (thickness 0.15)) (justify left bottom))
    )
    (fp_rect (start -0.93 -0.47) (end 0.93 0.47)
      (stroke (width 0.05) (type solid)) (fill none) (layer "F.CrtYd"))
    (fp_rect (start -0.5 -0.25) (end 0.5 0.25)
      (stroke (width 0.15) (type solid)) (fill none) (layer "F.Fab"))
    (pad "1" smd roundrect (at -0.485 0 270) (size 0.59 0.64) (layers "F.Cu" "F.Paste" "F.Mask") (roundrect_rratio 0.25)
      (net 58 "TMDS_D0_N") (pintype "passive"))
    (pad "2" smd roundrect (at 0.485 0 270) (size 0.59 0.64) (layers "F.Cu" "F.Paste" "F.Mask") (roundrect_rratio 0.25)
      (net 44 "C_TMDS_D0_N") (pintype "passive"))
  )

  (footprint "data-center-rdimm-ddr4-tester-footprints:R_0402_1005Metric" (layer "F.Cu")
    (at 211.165 115.35 -90)
    (descr "Resistor SMD 0402")
    (tags "resistor SMD 0402")
    (property "Author" "Antmicro")
    (property "Current" "1A")
    (property "License" "Apache-2.0")
    (property "MPN" "ERJ2GE0R00X")
    (property "Manufacturer" "Panasonic")
    (property "Sheetfile" "interfaces.kicad_sch")
    (property "Sheetname" "Interfaces")
    (property "Tolerance" "")
    (property "Val" "0R")
    (property "ki_description" "0R resistor in 0402 package with unspecified tolerance")
    (attr smd)
    (fp_text reference "R142" (at -3.105 -0.35 -90) (layer "F.SilkS")
        (effects (font (size 0.7 0.7) (thickness 0.15)) (justify left bottom))
    )
    (fp_text value "R_0R_0402" (at 0 1.4 -90) (layer "F.Fab") hide
        (effects (font (size 0.7 0.7) (thickness 0.15)) (justify left bottom))
    )
    (fp_text user "License: Apache-2.0" (at -0.95 5.169 -90) (layer "F.Fab") hide
        (effects (font (size 0.7 0.7) (thickness 0.15)) (justify left bottom))
    )
    (fp_text user "${REFERENCE}" (at -0.95 3.168 -90) (layer "F.Fab") hide
        (effects (font (size 0.7 0.7) (thickness 0.15)) (justify left bottom))
    )
    (fp_text user "Author: Antmicro" (at -0.95 4.169 -90) (layer "F.Fab") hide
        (effects (font (size 0.7 0.7) (thickness 0.15)) (justify left bottom))
    )
    (fp_rect (start -0.93 -0.47) (end 0.93 0.47)
      (stroke (width 0.05) (type solid)) (fill none) (layer "F.CrtYd"))
    (fp_rect (start -0.5 -0.25) (end 0.5 0.25)
      (stroke (width 0.15) (type solid)) (fill none) (layer "F.Fab"))
    (pad "1" smd roundrect (at -0.485 0 270) (size 0.59 0.64) (layers "F.Cu" "F.Paste" "F.Mask") (roundrect_rratio 0.25)
      (net 57 "TMDS_D0_P") (pintype "passive"))
    (pad "2" smd roundrect (at 0.485 0 270) (size 0.59 0.64) (layers "F.Cu" "F.Paste" "F.Mask") (roundrect_rratio 0.25)
      (net 45 "C_TMDS_D0_P") (pintype "passive"))
  )

  (footprint "data-center-rdimm-ddr4-tester-footprints:R_0402_1005Metric" (layer "F.Cu")
    (at 211.64 113.135 -90)
    (descr "Resistor SMD 0402")
    (tags "resistor SMD 0402")
    (property "Author" "Antmicro")
    (property "Current" "1A")
    (property "License" "Apache-2.0")
    (property "MPN" "ERJ2GE0R00X")
    (property "Manufacturer" "Panasonic")
    (property "Sheetfile" "interfaces.kicad_sch")
    (property "Sheetname" "Interfaces")
    (property "Tolerance" "")
    (property "Val" "0R")
    (property "ki_description" "0R resistor in 0402 package with unspecified tolerance")
    (attr smd)
    (fp_text reference "R143" (at -3.515 -0.34 -90) (layer "F.SilkS")
        (effects (font (size 0.7 0.7) (thickness 0.15)) (justify left bottom))
    )
    (fp_text value "R_0R_0402" (at 0 1.4 -90) (layer "F.Fab") hide
        (effects (font (size 0.7 0.7) (thickness 0.15)) (justify left bottom))
    )
    (fp_text user "Author: Antmicro" (at -0.95 4.169 -90) (layer "F.Fab") hide
        (effects (font (size 0.7 0.7) (thickness 0.15)) (justify left bottom))
    )
    (fp_text user "${REFERENCE}" (at -0.95 3.168 -90) (layer "F.Fab") hide
        (effects (font (size 0.7 0.7) (thickness 0.15)) (justify left bottom))
    )
    (fp_text user "License: Apache-2.0" (at -0.95 5.169 -90) (layer "F.Fab") hide
        (effects (font (size 0.7 0.7) (thickness 0.15)) (justify left bottom))
    )
    (fp_rect (start -0.93 -0.47) (end 0.93 0.47)
      (stroke (width 0.05) (type solid)) (fill none) (layer "F.CrtYd"))
    (fp_rect (start -0.5 -0.25) (end 0.5 0.25)
      (stroke (width 0.15) (type solid)) (fill none) (layer "F.Fab"))
    (pad "1" smd roundrect (at -0.485 0 270) (size 0.59 0.64) (layers "F.Cu" "F.Paste" "F.Mask") (roundrect_rratio 0.25)
      (net 60 "TMDS_D1_N") (pintype "passive"))
    (pad "2" smd roundrect (at 0.485 0 270) (size 0.59 0.64) (layers "F.Cu" "F.Paste" "F.Mask") (roundrect_rratio 0.25)
      (net 54 "C_TMDS_D1_N") (pintype "passive"))
  )

  (footprint "data-center-rdimm-ddr4-tester-footprints:R_0402_1005Metric" (layer "F.Cu")
    (at 212.65 113.135 -90)
    (descr "Resistor SMD 0402")
    (tags "resistor SMD 0402")
    (property "Author" "Antmicro")
    (property "Current" "1A")
    (property "License" "Apache-2.0")
    (property "MPN" "ERJ2GE0R00X")
    (property "Manufacturer" "Panasonic")
    (property "Sheetfile" "interfaces.kicad_sch")
    (property "Sheetname" "Interfaces")
    (property "Tolerance" "")
    (property "Val" "0R")
    (property "ki_description" "0R resistor in 0402 package with unspecified tolerance")
    (attr smd)
    (fp_text reference "R144" (at -3.515 -0.34 -90) (layer "F.SilkS")
        (effects (font (size 0.7 0.7) (thickness 0.15)) (justify left bottom))
    )
    (fp_text value "R_0R_0402" (at 0 1.4 -90) (layer "F.Fab") hide
        (effects (font (size 0.7 0.7) (thickness 0.15)) (justify left bottom))
    )
    (fp_text user "${REFERENCE}" (at -0.95 3.168 -90) (layer "F.Fab") hide
        (effects (font (size 0.7 0.7) (thickness 0.15)) (justify left bottom))
    )
    (fp_text user "License: Apache-2.0" (at -0.95 5.169 -90) (layer "F.Fab") hide
        (effects (font (size 0.7 0.7) (thickness 0.15)) (justify left bottom))
    )
    (fp_text user "Author: Antmicro" (at -0.95 4.169 -90) (layer "F.Fab") hide
        (effects (font (size 0.7 0.7) (thickness 0.15)) (justify left bottom))
    )
    (fp_rect (start -0.93 -0.47) (end 0.93 0.47)
      (stroke (width 0.05) (type solid)) (fill none) (layer "F.CrtYd"))
    (fp_rect (start -0.5 -0.25) (end 0.5 0.25)
      (stroke (width 0.15) (type solid)) (fill none) (layer "F.Fab"))
    (pad "1" smd roundrect (at -0.485 0 270) (size 0.59 0.64) (layers "F.Cu" "F.Paste" "F.Mask") (roundrect_rratio 0.25)
      (net 59 "TMDS_D1_P") (pintype "passive"))
    (pad "2" smd roundrect (at 0.485 0 270) (size 0.59 0.64) (layers "F.Cu" "F.Paste" "F.Mask") (roundrect_rratio 0.25)
      (net 46 "C_TMDS_D1_P") (pintype "passive"))
  )

  (footprint "data-center-rdimm-ddr4-tester-footprints:R_0402_1005Metric" (layer "F.Cu")
    (at 213.14 115.35 -90)
    (descr "Resistor SMD 0402")
    (tags "resistor SMD 0402")
    (property "Author" "Antmicro")
    (property "Current" "1A")
    (property "License" "Apache-2.0")
    (property "MPN" "ERJ2GE0R00X")
    (property "Manufacturer" "Panasonic")
    (property "Sheetfile" "interfaces.kicad_sch")
    (property "Sheetname" "Interfaces")
    (property "Tolerance" "")
    (property "Val" "0R")
    (property "ki_description" "0R resistor in 0402 package with unspecified tolerance")
    (attr smd)
    (fp_text reference "R145" (at -3.105 -0.35 -90) (layer "F.SilkS")
        (effects (font (size 0.7 0.7) (thickness 0.15)) (justify left bottom))
    )
    (fp_text value "R_0R_0402" (at 0 1.4 -90) (layer "F.Fab") hide
        (effects (font (size 0.7 0.7) (thickness 0.15)) (justify left bottom))
    )
    (fp_text user "${REFERENCE}" (at -0.95 3.168 -90) (layer "F.Fab") hide
        (effects (font (size 0.7 0.7) (thickness 0.15)) (justify left bottom))
    )
    (fp_text user "License: Apache-2.0" (at -0.95 5.169 -90) (layer "F.Fab") hide
        (effects (font (size 0.7 0.7) (thickness 0.15)) (justify left bottom))
    )
    (fp_text user "Author: Antmicro" (at -0.95 4.169 -90) (layer "F.Fab") hide
        (effects (font (size 0.7 0.7) (thickness 0.15)) (justify left bottom))
    )
    (fp_rect (start -0.93 -0.47) (end 0.93 0.47)
      (stroke (width 0.05) (type solid)) (fill none) (layer "F.CrtYd"))
    (fp_rect (start -0.5 -0.25) (end 0.5 0.25)
      (stroke (width 0.15) (type solid)) (fill none) (layer "F.Fab"))
    (pad "1" smd roundrect (at -0.485 0 270) (size 0.59 0.64) (layers "F.Cu" "F.Paste" "F.Mask") (roundrect_rratio 0.25)
      (net 62 "TMDS_D2_N") (pintype "passive"))
    (pad "2" smd roundrect (at 0.485 0 270) (size 0.59 0.64) (layers "F.Cu" "F.Paste" "F.Mask") (roundrect_rratio 0.25)
      (net 47 "C_TMDS_D2_N") (pintype "passive"))
  )

  (footprint "data-center-rdimm-ddr4-tester-footprints:R_0402_1005Metric" (layer "F.Cu")
    (at 214.156 115.35 -90)
    (descr "Resistor SMD 0402")
    (tags "resistor SMD 0402")
    (property "Author" "Antmicro")
    (property "Current" "1A")
    (property "License" "Apache-2.0")
    (property "MPN" "ERJ2GE0R00X")
    (property "Manufacturer" "Panasonic")
    (property "Sheetfile" "interfaces.kicad_sch")
    (property "Sheetname" "Interfaces")
    (property "Tolerance" "")
    (property "Val" "0R")
    (property "ki_description" "0R resistor in 0402 package with unspecified tolerance")
    (attr smd)
    (fp_text reference "R146" (at -3.105 -0.35 -90) (layer "F.SilkS")
        (effects (font (size 0.7 0.7) (thickness 0.15)) (justify left bottom))
    )
    (fp_text value "R_0R_0402" (at 0 1.4 -90) (layer "F.Fab") hide
        (effects (font (size 0.7 0.7) (thickness 0.15)) (justify left bottom))
    )
    (fp_text user "Author: Antmicro" (at -0.95 4.169 -90) (layer "F.Fab") hide
        (effects (font (size 0.7 0.7) (thickness 0.15)) (justify left bottom))
    )
    (fp_text user "${REFERENCE}" (at -0.95 3.168 -90) (layer "F.Fab") hide
        (effects (font (size 0.7 0.7) (thickness 0.15)) (justify left bottom))
    )
    (fp_text user "License: Apache-2.0" (at -0.95 5.169 -90) (layer "F.Fab") hide
        (effects (font (size 0.7 0.7) (thickness 0.15)) (justify left bottom))
    )
    (fp_rect (start -0.93 -0.47) (end 0.93 0.47)
      (stroke (width 0.05) (type solid)) (fill none) (layer "F.CrtYd"))
    (fp_rect (start -0.5 -0.25) (end 0.5 0.25)
      (stroke (width 0.15) (type solid)) (fill none) (layer "F.Fab"))
    (pad "1" smd roundrect (at -0.485 0 270) (size 0.59 0.64) (layers "F.Cu" "F.Paste" "F.Mask") (roundrect_rratio 0.25)
      (net 61 "TMDS_D2_P") (pintype "passive"))
    (pad "2" smd roundrect (at 0.485 0 270) (size 0.59 0.64) (layers "F.Cu" "F.Paste" "F.Mask") (roundrect_rratio 0.25)
      (net 48 "C_TMDS_D2_P") (pintype "passive"))
  )

  (footprint "data-center-rdimm-ddr4-tester-footprints:Testpoint_smd_1mm" locked (layer "F.Cu")
    (at 206.5993 119.16 90)
    (property "Author" "Antmicro")
    (property "License" "Apache-2.0")
    (property "MPN" "")
    (property "Manufacturer" "")
    (property "Sheetfile" "interfaces.kicad_sch")
    (property "Sheetname" "Interfaces")
    (property "ki_description" "Test Point 1mm")
    (attr exclude_from_pos_files)
    (fp_text reference "TP1" (at 0.5 0.3707 90) (layer "F.SilkS")
        (effects (font (size 0.7 0.7) (thickness 0.15)) (justify left bottom))
    )
    (fp_text value "TP_1mm_SMD" (at 0 1.4 90) (layer "F.Fab") hide
        (effects (font (size 0.7 0.7) (thickness 0.15)) (justify left bottom))
    )
    (fp_text user "Author: Antmicro" (at -0.5 4 90) (layer "F.Fab") hide
        (effects (font (size 0.7 0.7) (thickness 0.15)) (justify left bottom))
    )
    (fp_text user "${REFERENCE}" (at -0.5 2.8 90) (layer "F.Fab") hide
        (effects (font (size 0.7 0.7) (thickness 0.15)) (justify left bottom))
    )
    (fp_text user "License: Apache-2.0" (at -0.5 5.2 90) (layer "F.Fab") hide
        (effects (font (size 0.7 0.7) (thickness 0.15)) (justify left bottom))
    )
    (pad "1" smd circle locked (at 0 0 90) (size 1 1) (layers "F.Cu" "F.Mask")
      (net 556 "Net-(J6-CEC)") (pinfunction "1") (pintype "passive"))
  )

  (footprint "data-center-rdimm-ddr4-tester-footprints:Testpoint_smd_1mm" locked (layer "F.Cu")
    (at 206.0725 121.16 90)
    (property "Author" "Antmicro")
    (property "License" "Apache-2.0")
    (property "MPN" "")
    (property "Manufacturer" "")
    (property "Sheetfile" "interfaces.kicad_sch")
    (property "Sheetname" "Interfaces")
    (property "ki_description" "Test Point 1mm")
    (attr exclude_from_pos_files)
    (fp_text reference "TP2" (at -0.97 1.4275 90) (layer "F.SilkS")
        (effects (font (size 0.7 0.7) (thickness 0.15)) (justify left bottom))
    )
    (fp_text value "TP_1mm_SMD" (at 0 1.4 90) (layer "F.Fab") hide
        (effects (font (size 0.7 0.7) (thickness 0.15)) (justify left bottom))
    )
    (fp_text user "License: Apache-2.0" (at -0.5 5.2 90) (layer "F.Fab") hide
        (effects (font (size 0.7 0.7) (thickness 0.15)) (justify left bottom))
    )
    (fp_text user "${REFERENCE}" (at -0.5 2.8 90) (layer "F.Fab") hide
        (effects (font (size 0.7 0.7) (thickness 0.15)) (justify left bottom))
    )
    (fp_text user "Author: Antmicro" (at -0.5 4 90) (layer "F.Fab") hide
        (effects (font (size 0.7 0.7) (thickness 0.15)) (justify left bottom))
    )
    (pad "1" smd circle locked (at 0 0 90) (size 1 1) (layers "F.Cu" "F.Mask")
      (net 560 "Net-(J6-SCL)") (pinfunction "1") (pintype "passive"))
  )

  (footprint "data-center-rdimm-ddr4-tester-footprints:Testpoint_smd_1mm" locked (layer "F.Cu")
    (at 203.1233 119.16 90)
    (property "Author" "Antmicro")
    (property "License" "Apache-2.0")
    (property "MPN" "")
    (property "Manufacturer" "")
    (property "Sheetfile" "interfaces.kicad_sch")
    (property "Sheetname" "Interfaces")
    (property "ki_description" "Test Point 1mm")
    (attr exclude_from_pos_files)
    (fp_text reference "TP3" (at 0.47 0.3467 90) (layer "F.SilkS")
        (effects (font (size 0.7 0.7) (thickness 0.15)) (justify left bottom))
    )
    (fp_text value "TP_1mm_SMD" (at 0 1.4 90) (layer "F.Fab") hide
        (effects (font (size 0.7 0.7) (thickness 0.15)) (justify left bottom))
    )
    (fp_text user "${REFERENCE}" (at -0.5 2.8 90) (layer "F.Fab") hide
        (effects (font (size 0.7 0.7) (thickness 0.15)) (justify left bottom))
    )
    (fp_text user "License: Apache-2.0" (at -0.5 5.2 90) (layer "F.Fab") hide
        (effects (font (size 0.7 0.7) (thickness 0.15)) (justify left bottom))
    )
    (fp_text user "Author: Antmicro" (at -0.5 4 90) (layer "F.Fab") hide
        (effects (font (size 0.7 0.7) (thickness 0.15)) (justify left bottom))
    )
    (pad "1" smd circle locked (at 0 0 90) (size 1 1) (layers "F.Cu" "F.Mask")
      (net 563 "Net-(J6-HPD{slash}HEAC-)") (pinfunction "1") (pintype "passive"))
  )

  (footprint "data-center-rdimm-ddr4-tester-footprints:Testpoint_smd_1mm" locked (layer "F.Cu")
    (at 205.0725 119.16 90)
    (property "Author" "Antmicro")
    (property "License" "Apache-2.0")
    (property "MPN" "")
    (property "Manufacturer" "")
    (property "Sheetfile" "interfaces.kicad_sch")
    (property "Sheetname" "Interfaces")
    (property "ki_description" "Test Point 1mm")
    (attr exclude_from_pos_files)
    (fp_text reference "TP4" (at 0.54 0.3775 90) (layer "F.SilkS")
        (effects (font (size 0.7 0.7) (thickness 0.15)) (justify left bottom))
    )
    (fp_text value "TP_1mm_SMD" (at 0 1.4 90) (layer "F.Fab") hide
        (effects (font (size 0.7 0.7) (thickness 0.15)) (justify left bottom))
    )
    (fp_text user "License: Apache-2.0" (at -0.5 5.2 90) (layer "F.Fab") hide
        (effects (font (size 0.7 0.7) (thickness 0.15)) (justify left bottom))
    )
    (fp_text user "Author: Antmicro" (at -0.5 4 90) (layer "F.Fab") hide
        (effects (font (size 0.7 0.7) (thickness 0.15)) (justify left bottom))
    )
    (fp_text user "${REFERENCE}" (at -0.5 2.8 90) (layer "F.Fab") hide
        (effects (font (size 0.7 0.7) (thickness 0.15)) (justify left bottom))
    )
    (pad "1" smd circle locked (at 0 0 90) (size 1 1) (layers "F.Cu" "F.Mask")
      (net 561 "Net-(J6-SDA)") (pinfunction "1") (pintype "passive"))
  )

  (footprint "data-center-rdimm-ddr4-tester-footprints:Testpoint_smd_1mm" locked (layer "F.Cu")
    (at 204.1233 121.16 90)
    (property "Author" "Antmicro")
    (property "License" "Apache-2.0")
    (property "MPN" "")
    (property "Manufacturer" "")
    (property "Sheetfile" "interfaces.kicad_sch")
    (property "Sheetname" "Interfaces")
    (property "ki_description" "Test Point 1mm")
    (attr exclude_from_pos_files)
    (fp_text reference "TP5" (at -0.9 -0.6933 90) (layer "F.SilkS")
        (effects (font (size 0.7 0.7) (thickness 0.15)) (justify left bottom))
    )
    (fp_text value "TP_1mm_SMD" (at 0 1.4 90) (layer "F.Fab") hide
        (effects (font (size 0.7 0.7) (thickness 0.15)) (justify left bottom))
    )
    (fp_text user "Author: Antmicro" (at -0.5 4 90) (layer "F.Fab") hide
        (effects (font (size 0.7 0.7) (thickness 0.15)) (justify left bottom))
    )
    (fp_text user "License: Apache-2.0" (at -0.5 5.2 90) (layer "F.Fab") hide
        (effects (font (size 0.7 0.7) (thickness 0.15)) (justify left bottom))
    )
    (fp_text user "${REFERENCE}" (at -0.5 2.8 90) (layer "F.Fab") hide
        (effects (font (size 0.7 0.7) (thickness 0.15)) (justify left bottom))
    )
    (pad "1" smd circle locked (at 0 0 90) (size 1 1) (layers "F.Cu" "F.Mask")
      (net 562 "Net-(J6-+5V)") (pinfunction "1") (pintype "passive"))
  )

  (footprint "data-center-rdimm-ddr4-tester-footprints:R-PDSO-N15" locked (layer "F.Cu")
    (at 211.3985 119.655 -90)
    (property "Author" "Antmicro")
    (property "License" "Apache-2.0")
    (property "MPN" "TPD8S009DSMR")
    (property "Manufacturer" "Texas Instruments")
    (property "Sheetfile" "interfaces.kicad_sch")
    (property "Sheetname" "Interfaces")
    (attr smd)
    (fp_text reference "IC3" (at 2.665 -3.5015 180) (layer "F.SilkS")
        (effects (font (size 0.7 0.7) (thickness 0.15)) (justify right bottom))
    )
    (fp_text value "TPD8S009DSMR" (at 0 4.4 90) (layer "F.Fab") hide
        (effects (font (size 0.7 0.7) (thickness 0.15)) (justify right bottom))
    )
    (fp_text user "${REFERENCE}" (at -4.1 4.95 90) (layer "F.Fab") hide
        (effects (font (size 0.7 0.7) (thickness 0.15)) (justify right bottom))
    )
    (fp_text user "Author: Antmicro" (at -4.1 7.35 90) (layer "F.Fab") hide
        (effects (font (size 0.7 0.7) (thickness 0.15)) (justify right bottom))
    )
    (fp_text user "License: Apache-2.0" (at -4.1 6.15 90) (layer "F.Fab") hide
        (effects (font (size 0.7 0.7) (thickness 0.15)) (justify right bottom))
    )
    (fp_circle (center -1.6 -3.2) (end -1.6 -3.15)
      (stroke (width 0.15) (type solid)) (fill solid) (layer "F.SilkS"))
    (fp_rect (start 1.8 -3.5) (end -1.89 3.49)
      (stroke (width 0.05) (type solid)) (fill none) (layer "F.CrtYd"))
    (fp_line (start -1.3 -3.051) (end -1.1 -3.25)
      (stroke (width 0.15) (type solid)) (layer "F.Fab"))
    (fp_rect (start 1.301 -3.25) (end -1.3 3.249)
      (stroke (width 0.15) (type solid)) (fill none) (layer "F.Fab"))
    (pad "1" smd roundrect locked (at -0.95 -2.75 180) (size 0.3 1.45) (layers "F.Cu" "F.Paste" "F.Mask") (roundrect_rratio 0.25)
      (net 48 "C_TMDS_D2_P") (pinfunction "D0+") (pintype "passive"))
    (pad "2" smd roundrect locked (at -0.95 -2.25 180) (size 0.3 1.45) (layers "F.Cu" "F.Paste" "F.Mask") (roundrect_rratio 0.25)
      (net 9 "GND") (pinfunction "GND") (pintype "passive"))
    (pad "3" smd roundrect locked (at -0.95 -1.75 180) (size 0.3 1.45) (layers "F.Cu" "F.Paste" "F.Mask") (roundrect_rratio 0.25)
      (net 47 "C_TMDS_D2_N") (pinfunction "D0-") (pintype "passive"))
    (pad "4" smd roundrect locked (at -0.95 -1.25 180) (size 0.3 1.45) (layers "F.Cu" "F.Paste" "F.Mask") (roundrect_rratio 0.25)
      (net 46 "C_TMDS_D1_P") (pinfunction "D1+") (pintype "passive"))
    (pad "5" smd roundrect locked (at -0.95 -0.75 180) (size 0.3 1.45) (layers "F.Cu" "F.Paste" "F.Mask") (roundrect_rratio 0.25)
      (net 9 "GND") (pinfunction "GND") (pintype "passive"))
    (pad "6" smd roundrect locked (at -0.95 -0.25 180) (size 0.3 1.45) (layers "F.Cu" "F.Paste" "F.Mask") (roundrect_rratio 0.25)
      (net 54 "C_TMDS_D1_N") (pinfunction "D1-") (pintype "passive"))
    (pad "7" smd roundrect locked (at -0.95 0.247 180) (size 0.3 1.45) (layers "F.Cu" "F.Paste" "F.Mask") (roundrect_rratio 0.25)
      (net 45 "C_TMDS_D0_P") (pinfunction "D2+") (pintype "passive"))
    (pad "8" smd roundrect locked (at -0.95 0.747 180) (size 0.3 1.45) (layers "F.Cu" "F.Paste" "F.Mask") (roundrect_rratio 0.25)
      (net 9 "GND") (pinfunction "GND") (pintype "passive"))
    (pad "9" smd roundrect locked (at -0.95 1.249 180) (size 0.3 1.45) (layers "F.Cu" "F.Paste" "F.Mask") (roundrect_rratio 0.25)
      (net 44 "C_TMDS_D0_N") (pinfunction "D2-") (pintype "passive"))
    (pad "10" smd roundrect locked (at -0.95 1.749 180) (size 0.3 1.45) (layers "F.Cu" "F.Paste" "F.Mask") (roundrect_rratio 0.25)
      (net 42 "C_TMDS_CLK_P") (pinfunction "D3+") (pintype "passive"))
    (pad "11" smd roundrect locked (at -0.95 2.249 180) (size 0.3 1.45) (layers "F.Cu" "F.Paste" "F.Mask") (roundrect_rratio 0.25)
      (net 9 "GND") (pinfunction "GND") (pintype "passive"))
    (pad "12" smd roundrect locked (at -0.95 2.749 180) (size 0.3 1.45) (layers "F.Cu" "F.Paste" "F.Mask") (roundrect_rratio 0.25)
      (net 43 "C_TMDS_CLK_N") (pinfunction "D3-") (pintype "passive"))
    (pad "13" smd roundrect locked (at 0.901 1.499 180) (size 0.3 1.45) (layers "F.Cu" "F.Paste" "F.Mask") (roundrect_rratio 0.25)
      (net 143 "3V3_SYS") (pinfunction "VCC") (pintype "power_in"))
    (pad "14" smd roundrect locked (at 0.901 0 180) (size 0.3 1.45) (layers "F.Cu" "F.Paste" "F.Mask") (roundrect_rratio 0.25)
      (net 111 "unconnected-(IC3-NC-Pad14)") (pinfunction "NC") (pintype "no_connect"))
    (pad "15" smd roundrect locked (at 0.901 -1.5 180) (size 0.3 1.45) (layers "F.Cu" "F.Paste" "F.Mask") (roundrect_rratio 0.25)
      (net 143 "3V3_SYS") (pinfunction "VCC") (pintype "passive"))
  )

  (footprint "data-center-rdimm-ddr4-tester-footprints:HDMI-A_Receptacle_WE_685119134923" locked (layer "F.Cu")
    (at 209.625 132.18 180)
    (property "Author" "Antmicro")
    (property "License" "Apache-2.0")
    (property "MPN" "685119134923")
    (property "Manufacturer" "Würth Elektronik")
    (property "Sheetfile" "interfaces.kicad_sch")
    (property "Sheetname" "Interfaces")
    (property "ki_description" "HDMI Receptacle Connector 19 Position Surface Mount, Right Angle; Through Hole")
    (property "ki_keywords" "HDMI, CONNECTOR, THT")
    (attr smd)
    (fp_text reference "J6" (at -6.275 7.72 180) (layer "F.SilkS")
        (effects (font (size 0.7 0.7) (thickness 0.15)) (justify left bottom))
    )
    (fp_text value "HDMI_A_Female_685119134923" (at 0 7.8 180) (layer "F.Fab")
        (effects (font (size 0.7 0.7) (thickness 0.15)) (justify left bottom))
    )
    (fp_text user "${REFERENCE}" (at -8 9.5 180) (layer "F.Fab") hide
        (effects (font (size 0.7 0.7) (thickness 0.15)) (justify left bottom))
    )
    (fp_text user "Author: Antmicro" (at -8 11 180) (layer "F.Fab") hide
        (effects (font (size 0.7 0.7) (thickness 0.15)) (justify left bottom))
    )
    (fp_text user "License: Apache-2.0" (at -8 12.5 180) (layer "F.Fab") hide
        (effects (font (size 0.7 0.7) (thickness 0.15)) (justify left bottom))
    )
    (fp_line (start -7.55 -0.125) (end -7.55 2.65)
      (stroke (width 0.12) (type solid)) (layer "F.SilkS"))
    (fp_line (start -4.85 5.65) (end -5.8 5.65)
      (stroke (width 0.12) (type solid)) (layer "F.SilkS"))
    (fp_line (start 5.7 5.65) (end 4.75 5.65)
      (stroke (width 0.12) (type solid)) (layer "F.SilkS"))
    (fp_line (start 7.55 2.75) (end 7.55 -0.15)
      (stroke (width 0.12) (type solid)) (layer "F.SilkS"))
    (fp_circle (center -4.9 5.9) (end -4.85 5.9)
      (stroke (width 0.15) (type solid)) (fill none) (layer "F.SilkS"))
    (fp_rect (start -8.05 -6.32) (end 7.949 6.78)
      (stroke (width 0.05) (type solid)) (fill none) (layer "F.CrtYd"))
    (fp_line (start -7.05 -5.616) (end 6.95 -5.616)
      (stroke (width 0.15) (type solid)) (layer "F.Fab"))
    (fp_line (start -7.05 5.525) (end -7.05 -5.616)
      (stroke (width 0.15) (type solid)) (layer "F.Fab"))
    (fp_line (start -7.05 5.525) (end -6.05 6.525)
      (stroke (width 0.15) (type solid)) (layer "F.Fab"))
    (fp_line (start 6.95 6.535) (end -6.05 6.535)
      (stroke (width 0.15) (type solid)) (layer "F.Fab"))
    (fp_line (start 6.95 6.535) (end 6.95 -5.616)
      (stroke (width 0.15) (type solid)) (layer "F.Fab"))
    (pad "1" smd rect locked (at -4.55 5.224 180) (size 0.28 2.6) (layers "F.Cu" "F.Paste" "F.Mask")
      (net 48 "C_TMDS_D2_P") (pinfunction "D2+") (pintype "bidirectional"))
    (pad "2" smd rect locked (at -4.05 5.224 180) (size 0.28 2.6) (layers "F.Cu" "F.Paste" "F.Mask")
      (net 9 "GND") (pinfunction "D2S") (pintype "passive"))
    (pad "3" smd rect locked (at -3.551 5.224 180) (size 0.28 2.6) (layers "F.Cu" "F.Paste" "F.Mask")
      (net 47 "C_TMDS_D2_N") (pinfunction "D2-") (pintype "bidirectional"))
    (pad "4" smd rect locked (at -3.051 5.224 180) (size 0.28 2.6) (layers "F.Cu" "F.Paste" "F.Mask")
      (net 46 "C_TMDS_D1_P") (pinfunction "D1+") (pintype "bidirectional"))
    (pad "5" smd rect locked (at -2.551 5.224 180) (size 0.28 2.6) (layers "F.Cu" "F.Paste" "F.Mask")
      (net 9 "GND") (pinfunction "D1S") (pintype "passive"))
    (pad "6" smd rect locked (at -2.05 5.224 180) (size 0.28 2.6) (layers "F.Cu" "F.Paste" "F.Mask")
      (net 54 "C_TMDS_D1_N") (pinfunction "D1-") (pintype "bidirectional"))
    (pad "7" smd rect locked (at -1.551 5.224 180) (size 0.28 2.6) (layers "F.Cu" "F.Paste" "F.Mask")
      (net 45 "C_TMDS_D0_P") (pinfunction "D0+") (pintype "bidirectional"))
    (pad "8" smd rect locked (at -1.051 5.224 180) (size 0.28 2.6) (layers "F.Cu" "F.Paste" "F.Mask")
      (net 9 "GND") (pinfunction "D0S") (pintype "passive"))
    (pad "9" smd rect locked (at -0.551 5.224 180) (size 0.28 2.6) (layers "F.Cu" "F.Paste" "F.Mask")
      (net 44 "C_TMDS_D0_N") (pinfunction "D0-") (pintype "bidirectional"))
    (pad "10" smd rect locked (at -0.051 5.224 180) (size 0.28 2.6) (layers "F.Cu" "F.Paste" "F.Mask")
      (net 42 "C_TMDS_CLK_P") (pinfunction "CK+") (pintype "bidirectional"))
    (pad "11" smd rect locked (at 0.45 5.224 180) (size 0.28 2.6) (layers "F.Cu" "F.Paste" "F.Mask")
      (net 9 "GND") (pinfunction "CKS") (pintype "passive"))
    (pad "12" smd rect locked (at 0.95 5.224 180) (size 0.28 2.6) (layers "F.Cu" "F.Paste" "F.Mask")
      (net 43 "C_TMDS_CLK_N") (pinfunction "CK-") (pintype "bidirectional"))
    (pad "13" smd rect locked (at 1.449 5.224 180) (size 0.28 2.6) (layers "F.Cu" "F.Paste" "F.Mask")
      (net 556 "Net-(J6-CEC)") (pinfunction "CEC") (pintype "bidirectional"))
    (pad "14" smd rect locked (at 1.949 5.224 180) (size 0.28 2.6) (layers "F.Cu" "F.Paste" "F.Mask")
      (net 557 "unconnected-(J6-UTILITY{slash}HEAC+-Pad14)") (pinfunction "UTILITY/HEAC+") (pintype "bidirectional+no_connect"))
    (pad "15" smd rect locked (at 2.45 5.224 180) (size 0.28 2.6) (layers "F.Cu" "F.Paste" "F.Mask")
      (net 560 "Net-(J6-SCL)") (pinfunction "SCL") (pintype "bidirectional"))
    (pad "16" smd rect locked (at 2.95 5.224 180) (size 0.28 2.6) (layers "F.Cu" "F.Paste" "F.Mask")
      (net 561 "Net-(J6-SDA)") (pinfunction "SDA") (pintype "bidirectional"))
    (pad "17" smd rect locked (at 3.45 5.224 180) (size 0.28 2.6) (layers "F.Cu" "F.Paste" "F.Mask")
      (net 9 "GND") (pinfunction "GND") (pintype "power_in"))
    (pad "18" smd rect locked (at 3.95 5.224 180) (size 0.28 2.6) (layers "F.Cu" "F.Paste" "F.Mask")
      (net 562 "Net-(J6-+5V)") (pinfunction "+5V") (pintype "power_in"))
    (pad "19" smd rect locked (at 4.45 5.224 180) (size 0.28 2.6) (layers "F.Cu" "F.Paste" "F.Mask")
      (net 563 "Net-(J6-HPD{slash}HEAC-)") (pinfunction "HPD/HEAC-") (pintype "bidirectional"))
    (pad "SH" thru_hole oval locked (at -7.3 -1.577 180) (size 1.5 2.7) (drill oval 0.9 2.1) (layers "*.Cu" "*.Mask")
      (net 863 "GND1") (pinfunction "SH") (pintype "passive"))
    (pad "SH" thru_hole oval locked (at -7.3 4.424 180) (size 1.5 3.3) (drill oval 0.9 2.7) (layers "*.Cu" "*.Mask")
      (net 863 "GND1") (pinfunction "SH") (pintype "passive"))
    (pad "SH" thru_hole oval locked (at 7.2 -1.577 180) (size 1.5 2.7) (drill oval 0.9 2.1) (layers "*.Cu" "*.Mask")
      (net 863 "GND1") (pinfunction "SH") (pintype "passive"))
    (pad "SH" thru_hole oval locked (at 7.2 4.424 180) (size 1.5 3.3) (drill oval 0.9 2.7) (layers "*.Cu" "*.Mask")
      (net 863 "GND1") (pinfunction "SH") (pintype "passive"))
  )

  (footprint "data-center-rdimm-ddr4-tester-footprints:SW_B3U-1000P_SMD" (layer "F.Cu")
    (at 222.225 82.975 180)
    (property "Author" "Antmicro")
    (property "License" "Apache-2.0")
    (property "MPN" "B3U-1000P")
    (property "Manufacturer" "Omron")
    (property "Sheetfile" "config-spi.kicad_sch")
    (property "Sheetname" "Config SPI flash")
    (property "ki_description" "Tactile Switch, B3U, Top Actuated, Surface Mount, Round Button, 153 gf, 50mA at 12VDC")
    (property "ki_keywords" "VERTICAL, SMT, SWITCH, MECHANICAL, TACTILE")
    (attr smd)
    (fp_text reference "PROG_B1" (at 2.385 -2.575 180) (layer "F.SilkS")
        (effects (font (size 0.7 0.7) (thickness 0.15)) (justify left bottom))
    )
    (fp_text value "SW_B3U-1000P" (at 0 2.5) (layer "F.Fab")
        (effects (font (size 0.7 0.7) (thickness 0.15)) (justify right bottom))
    )
    (fp_text user "Author: Antmicro" (at -2.249 5.7) (layer "F.Fab") hide
        (effects (font (size 0.7 0.7) (thickness 0.15)) (justify right bottom))
    )
    (fp_text user "${REFERENCE}" (at -2.249 4.5) (layer "F.Fab") hide
        (effects (font (size 0.7 0.7) (thickness 0.15)) (justify right bottom))
    )
    (fp_text user "License: Apache-2.0" (at -2.249 6.9) (layer "F.Fab") hide
        (effects (font (size 0.7 0.7) (thickness 0.15)) (justify right bottom))
    )
    (fp_line (start -1.601 -0.95) (end -2 -0.95)
      (stroke (width 0.15) (type solid)) (layer "F.SilkS"))
    (fp_line (start -1.6 -1.4) (end -1.601 -0.95)
      (stroke (width 0.15) (type solid)) (layer "F.SilkS"))
    (fp_line (start -1.6 -1.4) (end -1.1 -1.4)
      (stroke (width 0.15) (type solid)) (layer "F.SilkS"))
    (fp_line (start -1.6 1.4) (end -1.6 0.95)
      (stroke (width 0.15) (type solid)) (layer "F.SilkS"))
    (fp_line (start -1.6 1.4) (end -1.1 1.4)
      (stroke (width 0.15) (type solid)) (layer "F.SilkS"))
    (fp_line (start 1.6 -1.4) (end 1.1 -1.4)
      (stroke (width 0.15) (type solid)) (layer "F.SilkS"))
    (fp_line (start 1.6 -1.4) (end 1.6 -0.95)
      (stroke (width 0.15) (type solid)) (layer "F.SilkS"))
    (fp_line (start 1.6 1.4) (end 1.1 1.4)
      (stroke (width 0.15) (type solid)) (layer "F.SilkS"))
    (fp_line (start 1.6 1.4) (end 1.6 0.95)
      (stroke (width 0.15) (type solid)) (layer "F.SilkS"))
    (fp_rect (start -2.249 -1.55) (end 2.25 1.549)
      (stroke (width 0.05) (type solid)) (fill none) (layer "F.CrtYd"))
    (fp_rect (start -1.5 -1.29) (end 1.499 1.289)
      (stroke (width 0.15) (type solid)) (fill none) (layer "F.Fab"))
    (pad "1" smd rect (at -1.7 0 180) (size 0.8 1.7) (layers "F.Cu" "F.Paste" "F.Mask")
      (net 91 "PROGRAM_B") (pinfunction "1") (pintype "passive"))
    (pad "2" smd rect (at 1.699 0 180) (size 0.8 1.7) (layers "F.Cu" "F.Paste" "F.Mask")
      (net 9 "GND") (pinfunction "2") (pintype "passive"))
  )

  (footprint "data-center-rdimm-ddr4-tester-footprints:LED_0603_1608Metric_G" (layer "F.Cu")
    (at 251.7 107 180)
    (descr "LED SMD 0603 Green")
    (tags "LED SMD 0603 Green")
    (property "Author" "Antmicro")
    (property "License" "Apache-2.0")
    (property "MPN" "KP-1608CGCK")
    (property "Manufacturer" "Kingbright")
    (property "Sheetfile" "interfaces.kicad_sch")
    (property "Sheetname" "Interfaces")
    (attr smd)
    (fp_text reference "D5" (at 0.84 -1.33 180) (layer "F.SilkS")
        (effects (font (size 0.7 0.7) (thickness 0.15)) (justify left bottom))
    )
    (fp_text value "LED_G_0603_KP-1608CGCK" (at 0 1.6 180) (layer "F.Fab") hide
        (effects (font (size 0.7 0.7) (thickness 0.15)) (justify left bottom))
    )
    (fp_text user "${REFERENCE}" (at -1.31 3.769 180) (layer "F.Fab") hide
        (effects (font (size 0.7 0.7) (thickness 0.15)) (justify left bottom))
    )
    (fp_text user "Author: Antmicro" (at -1.31 4.769 180) (layer "F.Fab") hide
        (effects (font (size 0.7 0.7) (thickness 0.15)) (justify left bottom))
    )
    (fp_text user "License: Apache-2.0" (at -1.31 5.769 180) (layer "F.Fab") hide
        (effects (font (size 0.7 0.7) (thickness 0.15)) (justify left bottom))
    )
    (fp_line (start -0.27 -0.35) (end 0.27 -0.35)
      (stroke (width 0.15) (type solid)) (layer "F.SilkS"))
    (fp_line (start -0.27 0.351) (end 0.27 0.351)
      (stroke (width 0.15) (type solid)) (layer "F.SilkS"))
    (fp_line (start -0.106328 -0.200008) (end -0.106328 0.199992)
      (stroke (width 0.1) (type solid)) (layer "F.SilkS"))
    (fp_line (start -0.106328 -0.200008) (end 0.093672 -0.000008)
      (stroke (width 0.1) (type solid)) (layer "F.SilkS"))
    (fp_line (start -0.106328 -0.000008) (end -0.29 0)
      (stroke (width 0.1) (type solid)) (layer "F.SilkS"))
    (fp_line (start 0.093672 -0.200008) (end 0.093672 0.199992)
      (stroke (width 0.1) (type solid)) (layer "F.SilkS"))
    (fp_line (start 0.093672 -0.000008) (end -0.106328 0.199992)
      (stroke (width 0.1) (type solid)) (layer "F.SilkS"))
    (fp_line (start 0.093672 -0.000008) (end 0.293672 -0.000008)
      (stroke (width 0.1) (type solid)) (layer "F.SilkS"))
    (fp_line (start 1.25 0.32) (end 1.25 -0.32)
      (stroke (width 0.15) (type solid)) (layer "F.SilkS"))
    (fp_rect (start 1.26 0.65) (end -1.26 -0.65)
      (stroke (width 0.05) (type solid)) (fill none) (layer "F.CrtYd"))
    (fp_line (start -0.599 0) (end -0.201 0)
      (stroke (width 0.15) (type solid)) (layer "F.Fab"))
    (fp_line (start -0.201 -0.2) (end -0.201 0)
      (stroke (width 0.15) (type solid)) (layer "F.Fab"))
    (fp_line (start -0.201 0) (end -0.201 0.202)
      (stroke (width 0.15) (type solid)) (layer "F.Fab"))
    (fp_line (start -0.201 0.202) (end 0.101 0)
      (stroke (width 0.15) (type solid)) (layer "F.Fab"))
    (fp_line (start 0.101 0) (end -0.201 -0.2)
      (stroke (width 0.15) (type solid)) (layer "F.Fab"))
    (fp_line (start 0.199 -0.2) (end 0.199 -0.1)
      (stroke (width 0.15) (type solid)) (layer "F.Fab"))
    (fp_line (start 0.199 0) (end 0.597 0)
      (stroke (width 0.15) (type solid)) (layer "F.Fab"))
    (fp_line (start 0.199 0.202) (end 0.199 -0.1)
      (stroke (width 0.15) (type solid)) (layer "F.Fab"))
    (fp_rect (start -0.848 -0.4) (end 0.85 0.402)
      (stroke (width 0.15) (type solid)) (fill none) (layer "F.Fab"))
    (pad "1" smd rect (at -0.75 0) (size 0.8 0.8) (layers "F.Cu" "F.Paste" "F.Mask")
      (net 143 "3V3_SYS") (pinfunction "1") (pintype "passive"))
    (pad "2" smd rect (at 0.75 0) (size 0.8 0.8) (layers "F.Cu" "F.Paste" "F.Mask")
      (net 63 "Net-(D5-Pad2)") (pinfunction "2") (pintype "passive"))
  )

  (footprint "data-center-rdimm-ddr4-tester-footprints:LED_0603_1608Metric_G" (layer "F.Cu")
    (at 251.7 95 180)
    (descr "LED SMD 0603 Green")
    (tags "LED SMD 0603 Green")
    (property "Author" "Antmicro")
    (property "License" "Apache-2.0")
    (property "MPN" "KP-1608CGCK")
    (property "Manufacturer" "Kingbright")
    (property "Sheetfile" "interfaces.kicad_sch")
    (property "Sheetname" "Interfaces")
    (attr smd)
    (fp_text reference "D6" (at 0.79 -1.26 180) (layer "F.SilkS")
        (effects (font (size 0.7 0.7) (thickness 0.15)) (justify left bottom))
    )
    (fp_text value "LED_G_0603_KP-1608CGCK" (at 0 1.6 180) (layer "F.Fab") hide
        (effects (font (size 0.7 0.7) (thickness 0.15)) (justify left bottom))
    )
    (fp_text user "License: Apache-2.0" (at -1.31 5.769 180) (layer "F.Fab") hide
        (effects (font (size 0.7 0.7) (thickness 0.15)) (justify left bottom))
    )
    (fp_text user "${REFERENCE}" (at -1.31 3.769 180) (layer "F.Fab") hide
        (effects (font (size 0.7 0.7) (thickness 0.15)) (justify left bottom))
    )
    (fp_text user "Author: Antmicro" (at -1.31 4.769 180) (layer "F.Fab") hide
        (effects (font (size 0.7 0.7) (thickness 0.15)) (justify left bottom))
    )
    (fp_line (start -0.27 -0.35) (end 0.27 -0.35)
      (stroke (width 0.15) (type solid)) (layer "F.SilkS"))
    (fp_line (start -0.27 0.351) (end 0.27 0.351)
      (stroke (width 0.15) (type solid)) (layer "F.SilkS"))
    (fp_line (start -0.106328 -0.200008) (end -0.106328 0.199992)
      (stroke (width 0.1) (type solid)) (layer "F.SilkS"))
    (fp_line (start -0.106328 -0.200008) (end 0.093672 -0.000008)
      (stroke (width 0.1) (type solid)) (layer "F.SilkS"))
    (fp_line (start -0.106328 -0.000008) (end -0.29 0)
      (stroke (width 0.1) (type solid)) (layer "F.SilkS"))
    (fp_line (start 0.093672 -0.200008) (end 0.093672 0.199992)
      (stroke (width 0.1) (type solid)) (layer "F.SilkS"))
    (fp_line (start 0.093672 -0.000008) (end -0.106328 0.199992)
      (stroke (width 0.1) (type solid)) (layer "F.SilkS"))
    (fp_line (start 0.093672 -0.000008) (end 0.293672 -0.000008)
      (stroke (width 0.1) (type solid)) (layer "F.SilkS"))
    (fp_line (start 1.25 0.32) (end 1.25 -0.32)
      (stroke (width 0.15) (type solid)) (layer "F.SilkS"))
    (fp_rect (start 1.26 0.65) (end -1.26 -0.65)
      (stroke (width 0.05) (type solid)) (fill none) (layer "F.CrtYd"))
    (fp_line (start -0.599 0) (end -0.201 0)
      (stroke (width 0.15) (type solid)) (layer "F.Fab"))
    (fp_line (start -0.201 -0.2) (end -0.201 0)
      (stroke (width 0.15) (type solid)) (layer "F.Fab"))
    (fp_line (start -0.201 0) (end -0.201 0.202)
      (stroke (width 0.15) (type solid)) (layer "F.Fab"))
    (fp_line (start -0.201 0.202) (end 0.101 0)
      (stroke (width 0.15) (type solid)) (layer "F.Fab"))
    (fp_line (start 0.101 0) (end -0.201 -0.2)
      (stroke (width 0.15) (type solid)) (layer "F.Fab"))
    (fp_line (start 0.199 -0.2) (end 0.199 -0.1)
      (stroke (width 0.15) (type solid)) (layer "F.Fab"))
    (fp_line (start 0.199 0) (end 0.597 0)
      (stroke (width 0.15) (type solid)) (layer "F.Fab"))
    (fp_line (start 0.199 0.202) (end 0.199 -0.1)
      (stroke (width 0.15) (type solid)) (layer "F.Fab"))
    (fp_rect (start -0.848 -0.4) (end 0.85 0.402)
      (stroke (width 0.15) (type solid)) (fill none) (layer "F.Fab"))
    (pad "1" smd rect (at -0.75 0) (size 0.8 0.8) (layers "F.Cu" "F.Paste" "F.Mask")
      (net 143 "3V3_SYS") (pinfunction "1") (pintype "passive"))
    (pad "2" smd rect (at 0.75 0) (size 0.8 0.8) (layers "F.Cu" "F.Paste" "F.Mask")
      (net 64 "Net-(D6-Pad2)") (pinfunction "2") (pintype "passive"))
  )

  (footprint "data-center-rdimm-ddr4-tester-footprints:LED_0603_1608Metric_G" (layer "F.Cu")
    (at 251.7 101 180)
    (descr "LED SMD 0603 Green")
    (tags "LED SMD 0603 Green")
    (property "Author" "Antmicro")
    (property "License" "Apache-2.0")
    (property "MPN" "KP-1608CGCK")
    (property "Manufacturer" "Kingbright")
    (property "Sheetfile" "interfaces.kicad_sch")
    (property "Sheetname" "Interfaces")
    (attr smd)
    (fp_text reference "D7" (at 0.79 -1.35 180) (layer "F.SilkS")
        (effects (font (size 0.7 0.7) (thickness 0.15)) (justify left bottom))
    )
    (fp_text value "LED_G_0603_KP-1608CGCK" (at 0 1.6 180) (layer "F.Fab") hide
        (effects (font (size 0.7 0.7) (thickness 0.15)) (justify left bottom))
    )
    (fp_text user "License: Apache-2.0" (at -1.31 5.769 180) (layer "F.Fab") hide
        (effects (font (size 0.7 0.7) (thickness 0.15)) (justify left bottom))
    )
    (fp_text user "Author: Antmicro" (at -1.31 4.769 180) (layer "F.Fab") hide
        (effects (font (size 0.7 0.7) (thickness 0.15)) (justify left bottom))
    )
    (fp_text user "${REFERENCE}" (at -1.31 3.769 180) (layer "F.Fab") hide
        (effects (font (size 0.7 0.7) (thickness 0.15)) (justify left bottom))
    )
    (fp_line (start -0.27 -0.35) (end 0.27 -0.35)
      (stroke (width 0.15) (type solid)) (layer "F.SilkS"))
    (fp_line (start -0.27 0.351) (end 0.27 0.351)
      (stroke (width 0.15) (type solid)) (layer "F.SilkS"))
    (fp_line (start -0.106328 -0.200008) (end -0.106328 0.199992)
      (stroke (width 0.1) (type solid)) (layer "F.SilkS"))
    (fp_line (start -0.106328 -0.200008) (end 0.093672 -0.000008)
      (stroke (width 0.1) (type solid)) (layer "F.SilkS"))
    (fp_line (start -0.106328 -0.000008) (end -0.29 0)
      (stroke (width 0.1) (type solid)) (layer "F.SilkS"))
    (fp_line (start 0.093672 -0.200008) (end 0.093672 0.199992)
      (stroke (width 0.1) (type solid)) (layer "F.SilkS"))
    (fp_line (start 0.093672 -0.000008) (end -0.106328 0.199992)
      (stroke (width 0.1) (type solid)) (layer "F.SilkS"))
    (fp_line (start 0.093672 -0.000008) (end 0.293672 -0.000008)
      (stroke (width 0.1) (type solid)) (layer "F.SilkS"))
    (fp_line (start 1.25 0.32) (end 1.25 -0.32)
      (stroke (width 0.15) (type solid)) (layer "F.SilkS"))
    (fp_rect (start 1.26 0.65) (end -1.26 -0.65)
      (stroke (width 0.05) (type solid)) (fill none) (layer "F.CrtYd"))
    (fp_line (start -0.599 0) (end -0.201 0)
      (stroke (width 0.15) (type solid)) (layer "F.Fab"))
    (fp_line (start -0.201 -0.2) (end -0.201 0)
      (stroke (width 0.15) (type solid)) (layer "F.Fab"))
    (fp_line (start -0.201 0) (end -0.201 0.202)
      (stroke (width 0.15) (type solid)) (layer "F.Fab"))
    (fp_line (start -0.201 0.202) (end 0.101 0)
      (stroke (width 0.15) (type solid)) (layer "F.Fab"))
    (fp_line (start 0.101 0) (end -0.201 -0.2)
      (stroke (width 0.15) (type solid)) (layer "F.Fab"))
    (fp_line (start 0.199 -0.2) (end 0.199 -0.1)
      (stroke (width 0.15) (type solid)) (layer "F.Fab"))
    (fp_line (start 0.199 0) (end 0.597 0)
      (stroke (width 0.15) (type solid)) (layer "F.Fab"))
    (fp_line (start 0.199 0.202) (end 0.199 -0.1)
      (stroke (width 0.15) (type solid)) (layer "F.Fab"))
    (fp_rect (start -0.848 -0.4) (end 0.85 0.402)
      (stroke (width 0.15) (type solid)) (fill none) (layer "F.Fab"))
    (pad "1" smd rect (at -0.75 0) (size 0.8 0.8) (layers "F.Cu" "F.Paste" "F.Mask")
      (net 143 "3V3_SYS") (pinfunction "1") (pintype "passive"))
    (pad "2" smd rect (at 0.75 0) (size 0.8 0.8) (layers "F.Cu" "F.Paste" "F.Mask")
      (net 65 "Net-(D7-Pad2)") (pinfunction "2") (pintype "passive"))
  )

  (footprint "data-center-rdimm-ddr4-tester-footprints:LED_0603_1608Metric_G" (layer "F.Cu")
    (at 251.7 89 180)
    (descr "LED SMD 0603 Green")
    (tags "LED SMD 0603 Green")
    (property "Author" "Antmicro")
    (property "License" "Apache-2.0")
    (property "MPN" "KP-1608CGCK")
    (property "Manufacturer" "Kingbright")
    (property "Sheetfile" "interfaces.kicad_sch")
    (property "Sheetname" "Interfaces")
    (attr smd)
    (fp_text reference "D8" (at 0.8 -1.31 180) (layer "F.SilkS")
        (effects (font (size 0.7 0.7) (thickness 0.15)) (justify left bottom))
    )
    (fp_text value "LED_G_0603_KP-1608CGCK" (at 0 1.6 180) (layer "F.Fab") hide
        (effects (font (size 0.7 0.7) (thickness 0.15)) (justify left bottom))
    )
    (fp_text user "Author: Antmicro" (at -1.31 4.769 180) (layer "F.Fab") hide
        (effects (font (size 0.7 0.7) (thickness 0.15)) (justify left bottom))
    )
    (fp_text user "${REFERENCE}" (at -1.31 3.769 180) (layer "F.Fab") hide
        (effects (font (size 0.7 0.7) (thickness 0.15)) (justify left bottom))
    )
    (fp_text user "License: Apache-2.0" (at -1.31 5.769 180) (layer "F.Fab") hide
        (effects (font (size 0.7 0.7) (thickness 0.15)) (justify left bottom))
    )
    (fp_line (start -0.27 -0.35) (end 0.27 -0.35)
      (stroke (width 0.15) (type solid)) (layer "F.SilkS"))
    (fp_line (start -0.27 0.351) (end 0.27 0.351)
      (stroke (width 0.15) (type solid)) (layer "F.SilkS"))
    (fp_line (start -0.106328 -0.200008) (end -0.106328 0.199992)
      (stroke (width 0.1) (type solid)) (layer "F.SilkS"))
    (fp_line (start -0.106328 -0.200008) (end 0.093672 -0.000008)
      (stroke (width 0.1) (type solid)) (layer "F.SilkS"))
    (fp_line (start -0.106328 -0.000008) (end -0.29 0)
      (stroke (width 0.1) (type solid)) (layer "F.SilkS"))
    (fp_line (start 0.093672 -0.200008) (end 0.093672 0.199992)
      (stroke (width 0.1) (type solid)) (layer "F.SilkS"))
    (fp_line (start 0.093672 -0.000008) (end -0.106328 0.199992)
      (stroke (width 0.1) (type solid)) (layer "F.SilkS"))
    (fp_line (start 0.093672 -0.000008) (end 0.293672 -0.000008)
      (stroke (width 0.1) (type solid)) (layer "F.SilkS"))
    (fp_line (start 1.25 0.32) (end 1.25 -0.32)
      (stroke (width 0.15) (type solid)) (layer "F.SilkS"))
    (fp_rect (start 1.26 0.65) (end -1.26 -0.65)
      (stroke (width 0.05) (type solid)) (fill none) (layer "F.CrtYd"))
    (fp_line (start -0.599 0) (end -0.201 0)
      (stroke (width 0.15) (type solid)) (layer "F.Fab"))
    (fp_line (start -0.201 -0.2) (end -0.201 0)
      (stroke (width 0.15) (type solid)) (layer "F.Fab"))
    (fp_line (start -0.201 0) (end -0.201 0.202)
      (stroke (width 0.15) (type solid)) (layer "F.Fab"))
    (fp_line (start -0.201 0.202) (end 0.101 0)
      (stroke (width 0.15) (type solid)) (layer "F.Fab"))
    (fp_line (start 0.101 0) (end -0.201 -0.2)
      (stroke (width 0.15) (type solid)) (layer "F.Fab"))
    (fp_line (start 0.199 -0.2) (end 0.199 -0.1)
      (stroke (width 0.15) (type solid)) (layer "F.Fab"))
    (fp_line (start 0.199 0) (end 0.597 0)
      (stroke (width 0.15) (type solid)) (layer "F.Fab"))
    (fp_line (start 0.199 0.202) (end 0.199 -0.1)
      (stroke (width 0.15) (type solid)) (layer "F.Fab"))
    (fp_rect (start -0.848 -0.4) (end 0.85 0.402)
      (stroke (width 0.15) (type solid)) (fill none) (layer "F.Fab"))
    (pad "1" smd rect (at -0.75 0) (size 0.8 0.8) (layers "F.Cu" "F.Paste" "F.Mask")
      (net 143 "3V3_SYS") (pinfunction "1") (pintype "passive"))
    (pad "2" smd rect (at 0.75 0) (size 0.8 0.8) (layers "F.Cu" "F.Paste" "F.Mask")
      (net 66 "Net-(D8-Pad2)") (pinfunction "2") (pintype "passive"))
  )

  (footprint "data-center-rdimm-ddr4-tester-footprints:LED_0603_1608Metric_G" (layer "F.Cu")
    (at 251.7 83.1 180)
    (descr "LED SMD 0603 Green")
    (tags "LED SMD 0603 Green")
    (property "Author" "Antmicro")
    (property "License" "Apache-2.0")
    (property "MPN" "KP-1608CGCK")
    (property "Manufacturer" "Kingbright")
    (property "Sheetfile" "interfaces.kicad_sch")
    (property "Sheetname" "Interfaces")
    (attr smd)
    (fp_text reference "D9" (at 0.75 -1.32 180) (layer "F.SilkS")
        (effects (font (size 0.7 0.7) (thickness 0.15)) (justify left bottom))
    )
    (fp_text value "LED_G_0603_KP-1608CGCK" (at 0 1.6 180) (layer "F.Fab") hide
        (effects (font (size 0.7 0.7) (thickness 0.15)) (justify left bottom))
    )
    (fp_text user "License: Apache-2.0" (at -1.31 5.769 180) (layer "F.Fab") hide
        (effects (font (size 0.7 0.7) (thickness 0.15)) (justify left bottom))
    )
    (fp_text user "${REFERENCE}" (at -1.31 3.769 180) (layer "F.Fab") hide
        (effects (font (size 0.7 0.7) (thickness 0.15)) (justify left bottom))
    )
    (fp_text user "Author: Antmicro" (at -1.31 4.769 180) (layer "F.Fab") hide
        (effects (font (size 0.7 0.7) (thickness 0.15)) (justify left bottom))
    )
    (fp_line (start -0.27 -0.35) (end 0.27 -0.35)
      (stroke (width 0.15) (type solid)) (layer "F.SilkS"))
    (fp_line (start -0.27 0.351) (end 0.27 0.351)
      (stroke (width 0.15) (type solid)) (layer "F.SilkS"))
    (fp_line (start -0.106328 -0.200008) (end -0.106328 0.199992)
      (stroke (width 0.1) (type solid)) (layer "F.SilkS"))
    (fp_line (start -0.106328 -0.200008) (end 0.093672 -0.000008)
      (stroke (width 0.1) (type solid)) (layer "F.SilkS"))
    (fp_line (start -0.106328 -0.000008) (end -0.29 0)
      (stroke (width 0.1) (type solid)) (layer "F.SilkS"))
    (fp_line (start 0.093672 -0.200008) (end 0.093672 0.199992)
      (stroke (width 0.1) (type solid)) (layer "F.SilkS"))
    (fp_line (start 0.093672 -0.000008) (end -0.106328 0.199992)
      (stroke (width 0.1) (type solid)) (layer "F.SilkS"))
    (fp_line (start 0.093672 -0.000008) (end 0.293672 -0.000008)
      (stroke (width 0.1) (type solid)) (layer "F.SilkS"))
    (fp_line (start 1.25 0.32) (end 1.25 -0.32)
      (stroke (width 0.15) (type solid)) (layer "F.SilkS"))
    (fp_rect (start 1.26 0.65) (end -1.26 -0.65)
      (stroke (width 0.05) (type solid)) (fill none) (layer "F.CrtYd"))
    (fp_line (start -0.599 0) (end -0.201 0)
      (stroke (width 0.15) (type solid)) (layer "F.Fab"))
    (fp_line (start -0.201 -0.2) (end -0.201 0)
      (stroke (width 0.15) (type solid)) (layer "F.Fab"))
    (fp_line (start -0.201 0) (end -0.201 0.202)
      (stroke (width 0.15) (type solid)) (layer "F.Fab"))
    (fp_line (start -0.201 0.202) (end 0.101 0)
      (stroke (width 0.15) (type solid)) (layer "F.Fab"))
    (fp_line (start 0.101 0) (end -0.201 -0.2)
      (stroke (width 0.15) (type solid)) (layer "F.Fab"))
    (fp_line (start 0.199 -0.2) (end 0.199 -0.1)
      (stroke (width 0.15) (type solid)) (layer "F.Fab"))
    (fp_line (start 0.199 0) (end 0.597 0)
      (stroke (width 0.15) (type solid)) (layer "F.Fab"))
    (fp_line (start 0.199 0.202) (end 0.199 -0.1)
      (stroke (width 0.15) (type solid)) (layer "F.Fab"))
    (fp_rect (start -0.848 -0.4) (end 0.85 0.402)
      (stroke (width 0.15) (type solid)) (fill none) (layer "F.Fab"))
    (pad "1" smd rect (at -0.75 0) (size 0.8 0.8) (layers "F.Cu" "F.Paste" "F.Mask")
      (net 143 "3V3_SYS") (pinfunction "1") (pintype "passive"))
    (pad "2" smd rect (at 0.75 0) (size 0.8 0.8) (layers "F.Cu" "F.Paste" "F.Mask")
      (net 78 "Net-(D9-Pad2)") (pinfunction "2") (pintype "passive"))
  )

  (footprint "data-center-rdimm-ddr4-tester-footprints:USON-14_3.5X1.3X0.5mm_P0.5mm" (layer "F.Cu")
    (at 229.37 80.45 90)
    (property "Author" "Antmicro")
    (property "DNP" "DNP")
    (property "License" "Apache-2.0")
    (property "MPN" "TPD6E05U06RVZR")
    (property "Manufacturer" "Texas Instruments")
    (property "Sheetfile" "config-spi.kicad_sch")
    (property "Sheetname" "Config SPI flash")
    (property "dnp" "")
    (property "exclude_from_bom" "")
    (attr exclude_from_pos_files exclude_from_bom)
    (fp_text reference "D4" (at -2.97 -0.77) (layer "F.SilkS")
        (effects (font (size 0.7 0.7) (thickness 0.15)) (justify left bottom))
    )
    (fp_text value "TPD6E05U06RVZR" (at 0 2.2 90) (layer "F.Fab") hide
        (effects (font (size 0.7 0.7) (thickness 0.15)) (justify left bottom))
    )
    (fp_text user "${REFERENCE}" (at -1.851 4.498 90) (layer "F.Fab") hide
        (effects (font (size 0.7 0.7) (thickness 0.15)) (justify left bottom))
    )
    (fp_text user "License: Apache-2.0" (at -1.851 6.9 90) (layer "F.Fab") hide
        (effects (font (size 0.7 0.7) (thickness 0.15)) (justify left bottom))
    )
    (fp_text user "Author: Antmicro" (at -1.851 5.7 90) (layer "F.Fab") hide
        (effects (font (size 0.7 0.7) (thickness 0.15)) (justify left bottom))
    )
    (fp_line (start -1.86 -0.96) (end 1.85 -0.96)
      (stroke (width 0.15) (type solid)) (layer "F.SilkS"))
    (fp_line (start -1.86 0.69) (end -1.86 -0.96)
      (stroke (width 0.15) (type solid)) (layer "F.SilkS"))
    (fp_line (start -1.59 0.96) (end -1.86 0.69)
      (stroke (width 0.15) (type solid)) (layer "F.SilkS"))
    (fp_line (start 1.85 -0.96) (end 1.85 0.96)
      (stroke (width 0.15) (type solid)) (layer "F.SilkS"))
    (fp_line (start 1.85 0.96) (end -1.59 0.96)
      (stroke (width 0.15) (type solid)) (layer "F.SilkS"))
    (fp_circle (center -1.86 0.98) (end -1.81 0.98)
      (stroke (width 0.15) (type solid)) (fill none) (layer "F.SilkS"))
    (fp_rect (start -2 -1.125) (end 2 1.125)
      (stroke (width 0.05) (type solid)) (fill none) (layer "F.CrtYd"))
    (fp_line (start -1.86 -0.96) (end -1.86 0.69)
      (stroke (width 0.15) (type solid)) (layer "F.Fab"))
    (fp_line (start -1.845 0.705) (end -1.595 0.955)
      (stroke (width 0.15) (type solid)) (layer "F.Fab"))
    (fp_line (start -1.58 0.96) (end 1.85 0.96)
      (stroke (width 0.15) (type solid)) (layer "F.Fab"))
    (fp_line (start 1.85 -0.96) (end -1.86 -0.96)
      (stroke (width 0.15) (type solid)) (layer "F.Fab"))
    (fp_line (start 1.85 0.96) (end 1.85 -0.96)
      (stroke (width 0.15) (type solid)) (layer "F.Fab"))
    (pad "1" smd roundrect (at -1.5 0.623 90) (size 0.2 0.5) (layers "F.Cu" "F.Paste" "F.Mask") (roundrect_rratio 0.25)
      (net 13 "TMS_JTAG") (pinfunction "D1+") (pintype "passive"))
    (pad "2" smd roundrect (at -1 0.623 90) (size 0.2 0.5) (layers "F.Cu" "F.Paste" "F.Mask") (roundrect_rratio 0.25)
      (net 12 "TCK_JTAG") (pinfunction "D1-") (pintype "passive"))
    (pad "3" smd roundrect (at -0.5 0.623 90) (size 0.2 0.5) (layers "F.Cu" "F.Paste" "F.Mask") (roundrect_rratio 0.25)
      (net 97 "unconnected-(D4-D2+-Pad12)") (pinfunction "D2+") (pintype "passive+no_connect"))
    (pad "4" smd roundrect (at 0 0.623 90) (size 0.2 0.5) (layers "F.Cu" "F.Paste" "F.Mask") (roundrect_rratio 0.25)
      (net 98 "unconnected-(D4-D2--Pad11)") (pinfunction "D2-") (pintype "passive+no_connect"))
    (pad "5" smd roundrect (at 0.498 0.623 90) (size 0.2 0.5) (layers "F.Cu" "F.Paste" "F.Mask") (roundrect_rratio 0.25)
      (net 9 "GND") (pinfunction "GND") (pintype "power_in"))
    (pad "6" smd roundrect (at 0.998 0.623 90) (size 0.2 0.5) (layers "F.Cu" "F.Paste" "F.Mask") (roundrect_rratio 0.25)
      (net 15 "TDO_JTAG") (pinfunction "D3+") (pintype "passive"))
    (pad "7" smd roundrect (at 1.499 0.623 90) (size 0.2 0.5) (layers "F.Cu" "F.Paste" "F.Mask") (roundrect_rratio 0.25)
      (net 14 "TDI_JTAG") (pinfunction "D3-") (pintype "passive"))
    (pad "8" smd roundrect (at 1.499 -0.625 90) (size 0.2 0.5) (layers "F.Cu" "F.Paste" "F.Mask") (roundrect_rratio 0.25)
      (net 14 "TDI_JTAG") (pinfunction "D3-") (pintype "passive"))
    (pad "9" smd roundrect (at 0.998 -0.625 90) (size 0.2 0.5) (layers "F.Cu" "F.Paste" "F.Mask") (roundrect_rratio 0.25)
      (net 15 "TDO_JTAG") (pinfunction "D3+") (pintype "passive"))
    (pad "10" smd roundrect (at 0.498 -0.625 90) (size 0.2 0.5) (layers "F.Cu" "F.Paste" "F.Mask") (roundrect_rratio 0.25)
      (net 9 "GND") (pinfunction "GND") (pintype "passive"))
    (pad "11" smd roundrect (at 0 -0.625 90) (size 0.2 0.5) (layers "F.Cu" "F.Paste" "F.Mask") (roundrect_rratio 0.25)
      (net 98 "unconnected-(D4-D2--Pad11)") (pinfunction "D2-") (pintype "passive+no_connect"))
    (pad "12" smd roundrect (at -0.5 -0.625 90) (size 0.2 0.5) (layers "F.Cu" "F.Paste" "F.Mask") (roundrect_rratio 0.25)
      (net 97 "unconnected-(D4-D2+-Pad12)") (pinfunction "D2+") (pintype "passive+no_connect"))
    (pad "13" smd roundrect (at -1 -0.625 90) (size 0.2 0.5) (layers "F.Cu" "F.Paste" "F.Mask") (roundrect_rratio 0.25)
      (net 12 "TCK_JTAG") (pinfunction "D1-") (pintype "passive"))
    (pad "14" smd roundrect (at -1.5 -0.625 90) (size 0.2 0.5) (layers "F.Cu" "F.Paste" "F.Mask") (roundrect_rratio 0.25)
      (net 13 "TMS_JTAG") (pinfunction "D1+") (pintype "passive"))
  )

  (footprint "data-center-rdimm-ddr4-tester-footprints:LED_0603_1608Metric_G" (layer "F.Cu")
    (at 243.15 128.9 -90)
    (descr "LED SMD 0603 Green")
    (tags "LED SMD 0603 Green")
    (property "Author" "Antmicro")
    (property "License" "Apache-2.0")
    (property "MPN" "KP-1608CGCK")
    (property "Manufacturer" "Kingbright")
    (property "Sheetfile" "config-spi.kicad_sch")
    (property "Sheetname" "Config SPI flash")
    (attr smd)
    (fp_text reference "D1" (at 2.02 -2.42 -90) (layer "F.SilkS")
        (effects (font (size 0.7 0.7) (thickness 0.15)) (justify left bottom))
    )
    (fp_text value "LED_G_0603_KP-1608CGCK" (at 0 1.6 -90) (layer "F.Fab") hide
        (effects (font (size 0.7 0.7) (thickness 0.15)) (justify left bottom))
    )
    (fp_text user "License: Apache-2.0" (at -1.31 5.769 -90) (layer "F.Fab") hide
        (effects (font (size 0.7 0.7) (thickness 0.15)) (justify left bottom))
    )
    (fp_text user "Author: Antmicro" (at -1.31 4.769 -90) (layer "F.Fab") hide
        (effects (font (size 0.7 0.7) (thickness 0.15)) (justify left bottom))
    )
    (fp_text user "${REFERENCE}" (at -1.31 3.769 -90) (layer "F.Fab") hide
        (effects (font (size 0.7 0.7) (thickness 0.15)) (justify left bottom))
    )
    (fp_line (start -0.27 -0.35) (end 0.27 -0.35)
      (stroke (width 0.15) (type solid)) (layer "F.SilkS"))
    (fp_line (start -0.27 0.351) (end 0.27 0.351)
      (stroke (width 0.15) (type solid)) (layer "F.SilkS"))
    (fp_line (start -0.106328 -0.200008) (end -0.106328 0.199992)
      (stroke (width 0.1) (type solid)) (layer "F.SilkS"))
    (fp_line (start -0.106328 -0.200008) (end 0.093672 -0.000008)
      (stroke (width 0.1) (type solid)) (layer "F.SilkS"))
    (fp_line (start -0.106328 -0.000008) (end -0.29 0)
      (stroke (width 0.1) (type solid)) (layer "F.SilkS"))
    (fp_line (start 0.093672 -0.200008) (end 0.093672 0.199992)
      (stroke (width 0.1) (type solid)) (layer "F.SilkS"))
    (fp_line (start 0.093672 -0.000008) (end -0.106328 0.199992)
      (stroke (width 0.1) (type solid)) (layer "F.SilkS"))
    (fp_line (start 0.093672 -0.000008) (end 0.293672 -0.000008)
      (stroke (width 0.1) (type solid)) (layer "F.SilkS"))
    (fp_line (start 1.25 0.32) (end 1.25 -0.32)
      (stroke (width 0.15) (type solid)) (layer "F.SilkS"))
    (fp_rect (start 1.26 0.65) (end -1.26 -0.65)
      (stroke (width 0.05) (type solid)) (fill none) (layer "F.CrtYd"))
    (fp_line (start -0.599 0) (end -0.201 0)
      (stroke (width 0.15) (type solid)) (layer "F.Fab"))
    (fp_line (start -0.201 -0.2) (end -0.201 0)
      (stroke (width 0.15) (type solid)) (layer "F.Fab"))
    (fp_line (start -0.201 0) (end -0.201 0.202)
      (stroke (width 0.15) (type solid)) (layer "F.Fab"))
    (fp_line (start -0.201 0.202) (end 0.101 0)
      (stroke (width 0.15) (type solid)) (layer "F.Fab"))
    (fp_line (start 0.101 0) (end -0.201 -0.2)
      (stroke (width 0.15) (type solid)) (layer "F.Fab"))
    (fp_line (start 0.199 -0.2) (end 0.199 -0.1)
      (stroke (width 0.15) (type solid)) (layer "F.Fab"))
    (fp_line (start 0.199 0) (end 0.597 0)
      (stroke (width 0.15) (type solid)) (layer "F.Fab"))
    (fp_line (start 0.199 0.202) (end 0.199 -0.1)
      (stroke (width 0.15) (type solid)) (layer "F.Fab"))
    (fp_rect (start -0.848 -0.4) (end 0.85 0.402)
      (stroke (width 0.15) (type solid)) (fill none) (layer "F.Fab"))
    (pad "1" smd rect (at -0.75 0 90) (size 0.8 0.8) (layers "F.Cu" "F.Paste" "F.Mask")
      (net 143 "3V3_SYS") (pinfunction "1") (pintype "passive"))
    (pad "2" smd rect (at 0.75 0 90) (size 0.8 0.8) (layers "F.Cu" "F.Paste" "F.Mask")
      (net 89 "Net-(D1-Pad2)") (pinfunction "2") (pintype "passive"))
  )

  (footprint "data-center-rdimm-ddr4-tester-footprints:LED_0603_1608Metric_G" (layer "F.Cu")
    (at 243.15 131.44 -90)
    (descr "LED SMD 0603 Green")
    (tags "LED SMD 0603 Green")
    (property "Author" "Antmicro")
    (property "License" "Apache-2.0")
    (property "MPN" "KP-1608CGCK")
    (property "Manufacturer" "Kingbright")
    (property "Sheetfile" "config-spi.kicad_sch")
    (property "Sheetname" "Config SPI flash")
    (attr smd)
    (fp_text reference "D10" (at 1.58 -2.42 -90) (layer "F.SilkS")
        (effects (font (size 0.7 0.7) (thickness 0.15)) (justify left bottom))
    )
    (fp_text value "LED_G_0603_KP-1608CGCK" (at 0 1.6 -90) (layer "F.Fab") hide
        (effects (font (size 0.7 0.7) (thickness 0.15)) (justify left bottom))
    )
    (fp_text user "${REFERENCE}" (at -1.31 3.769 -90) (layer "F.Fab") hide
        (effects (font (size 0.7 0.7) (thickness 0.15)) (justify left bottom))
    )
    (fp_text user "Author: Antmicro" (at -1.31 4.769 -90) (layer "F.Fab") hide
        (effects (font (size 0.7 0.7) (thickness 0.15)) (justify left bottom))
    )
    (fp_text user "License: Apache-2.0" (at -1.31 5.769 -90) (layer "F.Fab") hide
        (effects (font (size 0.7 0.7) (thickness 0.15)) (justify left bottom))
    )
    (fp_line (start -0.27 -0.35) (end 0.27 -0.35)
      (stroke (width 0.15) (type solid)) (layer "F.SilkS"))
    (fp_line (start -0.27 0.351) (end 0.27 0.351)
      (stroke (width 0.15) (type solid)) (layer "F.SilkS"))
    (fp_line (start -0.106328 -0.200008) (end -0.106328 0.199992)
      (stroke (width 0.1) (type solid)) (layer "F.SilkS"))
    (fp_line (start -0.106328 -0.200008) (end 0.093672 -0.000008)
      (stroke (width 0.1) (type solid)) (layer "F.SilkS"))
    (fp_line (start -0.106328 -0.000008) (end -0.29 0)
      (stroke (width 0.1) (type solid)) (layer "F.SilkS"))
    (fp_line (start 0.093672 -0.200008) (end 0.093672 0.199992)
      (stroke (width 0.1) (type solid)) (layer "F.SilkS"))
    (fp_line (start 0.093672 -0.000008) (end -0.106328 0.199992)
      (stroke (width 0.1) (type solid)) (layer "F.SilkS"))
    (fp_line (start 0.093672 -0.000008) (end 0.293672 -0.000008)
      (stroke (width 0.1) (type solid)) (layer "F.SilkS"))
    (fp_line (start 1.25 0.32) (end 1.25 -0.32)
      (stroke (width 0.15) (type solid)) (layer "F.SilkS"))
    (fp_rect (start 1.26 0.65) (end -1.26 -0.65)
      (stroke (width 0.05) (type solid)) (fill none) (layer "F.CrtYd"))
    (fp_line (start -0.599 0) (end -0.201 0)
      (stroke (width 0.15) (type solid)) (layer "F.Fab"))
    (fp_line (start -0.201 -0.2) (end -0.201 0)
      (stroke (width 0.15) (type solid)) (layer "F.Fab"))
    (fp_line (start -0.201 0) (end -0.201 0.202)
      (stroke (width 0.15) (type solid)) (layer "F.Fab"))
    (fp_line (start -0.201 0.202) (end 0.101 0)
      (stroke (width 0.15) (type solid)) (layer "F.Fab"))
    (fp_line (start 0.101 0) (end -0.201 -0.2)
      (stroke (width 0.15) (type solid)) (layer "F.Fab"))
    (fp_line (start 0.199 -0.2) (end 0.199 -0.1)
      (stroke (width 0.15) (type solid)) (layer "F.Fab"))
    (fp_line (start 0.199 0) (end 0.597 0)
      (stroke (width 0.15) (type solid)) (layer "F.Fab"))
    (fp_line (start 0.199 0.202) (end 0.199 -0.1)
      (stroke (width 0.15) (type solid)) (layer "F.Fab"))
    (fp_rect (start -0.848 -0.4) (end 0.85 0.402)
      (stroke (width 0.15) (type solid)) (fill none) (layer "F.Fab"))
    (pad "1" smd rect (at -0.75 0 90) (size 0.8 0.8) (layers "F.Cu" "F.Paste" "F.Mask")
      (net 143 "3V3_SYS") (pinfunction "1") (pintype "passive"))
    (pad "2" smd rect (at 0.75 0 90) (size 0.8 0.8) (layers "F.Cu" "F.Paste" "F.Mask")
      (net 90 "Net-(D10-Pad2)") (pinfunction "2") (pintype "passive"))
  )

  (footprint "data-center-rdimm-ddr4-tester-footprints:R_0402_1005Metric" (layer "F.Cu")
    (at 220.15 86.75)
    (descr "Resistor SMD 0402")
    (tags "resistor SMD 0402")
    (property "Author" "Antmicro")
    (property "Current" "1A")
    (property "License" "Apache-2.0")
    (property "MPN" "ERJ2GE0R00X")
    (property "Manufacturer" "Panasonic")
    (property "Sheetfile" "config-spi.kicad_sch")
    (property "Sheetname" "Config SPI flash")
    (property "Tolerance" "")
    (property "Val" "0R")
    (property "ki_description" "0R resistor in 0402 package with unspecified tolerance")
    (attr smd)
    (fp_text reference "R9" (at -1.14 2.49) (layer "F.SilkS")
        (effects (font (size 0.7 0.7) (thickness 0.15)) (justify left bottom))
    )
    (fp_text value "R_0R_0402" (at 0 1.4) (layer "F.Fab") hide
        (effects (font (size 0.7 0.7) (thickness 0.15)) (justify left bottom))
    )
    (fp_text user "${REFERENCE}" (at -0.95 3.168) (layer "F.Fab") hide
        (effects (font (size 0.7 0.7) (thickness 0.15)) (justify left bottom))
    )
    (fp_text user "License: Apache-2.0" (at -0.95 5.169) (layer "F.Fab") hide
        (effects (font (size 0.7 0.7) (thickness 0.15)) (justify left bottom))
    )
    (fp_text user "Author: Antmicro" (at -0.95 4.169) (layer "F.Fab") hide
        (effects (font (size 0.7 0.7) (thickness 0.15)) (justify left bottom))
    )
    (fp_rect (start -0.93 -0.47) (end 0.93 0.47)
      (stroke (width 0.05) (type solid)) (fill none) (layer "F.CrtYd"))
    (fp_rect (start -0.5 -0.25) (end 0.5 0.25)
      (stroke (width 0.15) (type solid)) (fill none) (layer "F.Fab"))
    (pad "1" smd roundrect (at -0.485 0) (size 0.59 0.64) (layers "F.Cu" "F.Paste" "F.Mask") (roundrect_rratio 0.25)
      (net 23 "MODE0") (pintype "passive"))
    (pad "2" smd roundrect (at 0.485 0) (size 0.59 0.64) (layers "F.Cu" "F.Paste" "F.Mask") (roundrect_rratio 0.25)
      (net 143 "3V3_SYS") (pintype "passive"))
  )

  (footprint "data-center-rdimm-ddr4-tester-footprints:R_0402_1005Metric" (layer "F.Cu")
    (at 220.135 87.85)
    (descr "Resistor SMD 0402")
    (tags "resistor SMD 0402")
    (property "Author" "Antmicro")
    (property "Current" "1A")
    (property "DNP" "DNP")
    (property "License" "Apache-2.0")
    (property "MPN" "ERJ2GE0R00X")
    (property "Manufacturer" "Panasonic")
    (property "Sheetfile" "config-spi.kicad_sch")
    (property "Sheetname" "Config SPI flash")
    (property "Tolerance" "")
    (property "Val" "0R")
    (property "dnp" "")
    (property "exclude_from_bom" "")
    (property "ki_description" "0R resistor in 0402 package with unspecified tolerance")
    (attr exclude_from_pos_files exclude_from_bom)
    (fp_text reference "R11" (at -1.14 2.49) (layer "F.SilkS")
        (effects (font (size 0.7 0.7) (thickness 0.15)) (justify left bottom))
    )
    (fp_text value "R_0R_0402" (at 0 1.4) (layer "F.Fab") hide
        (effects (font (size 0.7 0.7) (thickness 0.15)) (justify left bottom))
    )
    (fp_text user "Author: Antmicro" (at -0.95 4.169) (layer "F.Fab") hide
        (effects (font (size 0.7 0.7) (thickness 0.15)) (justify left bottom))
    )
    (fp_text user "${REFERENCE}" (at -0.95 3.168) (layer "F.Fab") hide
        (effects (font (size 0.7 0.7) (thickness 0.15)) (justify left bottom))
    )
    (fp_text user "License: Apache-2.0" (at -0.95 5.169) (layer "F.Fab") hide
        (effects (font (size 0.7 0.7) (thickness 0.15)) (justify left bottom))
    )
    (fp_rect (start -0.93 -0.47) (end 0.93 0.47)
      (stroke (width 0.05) (type solid)) (fill none) (layer "F.CrtYd"))
    (fp_rect (start -0.5 -0.25) (end 0.5 0.25)
      (stroke (width 0.15) (type solid)) (fill none) (layer "F.Fab"))
    (pad "1" smd roundrect (at -0.485 0) (size 0.59 0.64) (layers "F.Cu" "F.Paste" "F.Mask") (roundrect_rratio 0.25)
      (net 23 "MODE0") (pintype "passive"))
    (pad "2" smd roundrect (at 0.485 0) (size 0.59 0.64) (layers "F.Cu" "F.Paste" "F.Mask") (roundrect_rratio 0.25)
      (net 9 "GND") (pintype "passive"))
  )

  (footprint "data-center-rdimm-ddr4-tester-footprints:R_0402_1005Metric" (layer "F.Cu")
    (at 222.225 86.75)
    (descr "Resistor SMD 0402")
    (tags "resistor SMD 0402")
    (property "Author" "Antmicro")
    (property "Current" "1A")
    (property "DNP" "DNP")
    (property "License" "Apache-2.0")
    (property "MPN" "ERJ2GE0R00X")
    (property "Manufacturer" "Panasonic")
    (property "Sheetfile" "config-spi.kicad_sch")
    (property "Sheetname" "Config SPI flash")
    (property "Tolerance" "")
    (property "Val" "0R")
    (property "dnp" "")
    (property "exclude_from_bom" "")
    (property "ki_description" "0R resistor in 0402 package with unspecified tolerance")
    (attr exclude_from_pos_files exclude_from_bom)
    (fp_text reference "R12" (at -1.135 2.51) (layer "F.SilkS")
        (effects (font (size 0.7 0.7) (thickness 0.15)) (justify left bottom))
    )
    (fp_text value "R_0R_0402" (at 0 1.4) (layer "F.Fab") hide
        (effects (font (size 0.7 0.7) (thickness 0.15)) (justify left bottom))
    )
    (fp_text user "License: Apache-2.0" (at -0.95 5.169) (layer "F.Fab") hide
        (effects (font (size 0.7 0.7) (thickness 0.15)) (justify left bottom))
    )
    (fp_text user "${REFERENCE}" (at -0.95 3.168) (layer "F.Fab") hide
        (effects (font (size 0.7 0.7) (thickness 0.15)) (justify left bottom))
    )
    (fp_text user "Author: Antmicro" (at -0.95 4.169) (layer "F.Fab") hide
        (effects (font (size 0.7 0.7) (thickness 0.15)) (justify left bottom))
    )
    (fp_rect (start -0.93 -0.47) (end 0.93 0.47)
      (stroke (width 0.05) (type solid)) (fill none) (layer "F.CrtYd"))
    (fp_rect (start -0.5 -0.25) (end 0.5 0.25)
      (stroke (width 0.15) (type solid)) (fill none) (layer "F.Fab"))
    (pad "1" smd roundrect (at -0.485 0) (size 0.59 0.64) (layers "F.Cu" "F.Paste" "F.Mask") (roundrect_rratio 0.25)
      (net 24 "MODE1") (pintype "passive"))
    (pad "2" smd roundrect (at 0.485 0) (size 0.59 0.64) (layers "F.Cu" "F.Paste" "F.Mask") (roundrect_rratio 0.25)
      (net 143 "3V3_SYS") (pintype "passive"))
  )

  (footprint "data-center-rdimm-ddr4-tester-footprints:R_0402_1005Metric" (layer "F.Cu")
    (at 222.225 87.85)
    (descr "Resistor SMD 0402")
    (tags "resistor SMD 0402")
    (property "Author" "Antmicro")
    (property "Current" "1A")
    (property "License" "Apache-2.0")
    (property "MPN" "ERJ2GE0R00X")
    (property "Manufacturer" "Panasonic")
    (property "Sheetfile" "config-spi.kicad_sch")
    (property "Sheetname" "Config SPI flash")
    (property "Tolerance" "")
    (property "Val" "0R")
    (property "ki_description" "0R resistor in 0402 package with unspecified tolerance")
    (attr smd)
    (fp_text reference "R13" (at -1.135 2.51) (layer "F.SilkS")
        (effects (font (size 0.7 0.7) (thickness 0.15)) (justify left bottom))
    )
    (fp_text value "R_0R_0402" (at 0 1.4) (layer "F.Fab") hide
        (effects (font (size 0.7 0.7) (thickness 0.15)) (justify left bottom))
    )
    (fp_text user "License: Apache-2.0" (at -0.95 5.169) (layer "F.Fab") hide
        (effects (font (size 0.7 0.7) (thickness 0.15)) (justify left bottom))
    )
    (fp_text user "${REFERENCE}" (at -0.95 3.168) (layer "F.Fab") hide
        (effects (font (size 0.7 0.7) (thickness 0.15)) (justify left bottom))
    )
    (fp_text user "Author: Antmicro" (at -0.95 4.169) (layer "F.Fab") hide
        (effects (font (size 0.7 0.7) (thickness 0.15)) (justify left bottom))
    )
    (fp_rect (start -0.93 -0.47) (end 0.93 0.47)
      (stroke (width 0.05) (type solid)) (fill none) (layer "F.CrtYd"))
    (fp_rect (start -0.5 -0.25) (end 0.5 0.25)
      (stroke (width 0.15) (type solid)) (fill none) (layer "F.Fab"))
    (pad "1" smd roundrect (at -0.485 0) (size 0.59 0.64) (layers "F.Cu" "F.Paste" "F.Mask") (roundrect_rratio 0.25)
      (net 24 "MODE1") (pintype "passive"))
    (pad "2" smd roundrect (at 0.485 0) (size 0.59 0.64) (layers "F.Cu" "F.Paste" "F.Mask") (roundrect_rratio 0.25)
      (net 9 "GND") (pintype "passive"))
  )

  (footprint "data-center-rdimm-ddr4-tester-footprints:R_0402_1005Metric" (layer "F.Cu")
    (at 224.295 87.85)
    (descr "Resistor SMD 0402")
    (tags "resistor SMD 0402")
    (property "Author" "Antmicro")
    (property "License" "Apache-2.0")
    (property "MPN" "CR0402-FX-4701GLF")
    (property "Manufacturer" "Bourns")
    (property "Sheetfile" "config-spi.kicad_sch")
    (property "Sheetname" "Config SPI flash")
    (property "Tolerance" "1%")
    (property "Val" "4k7")
    (property "ki_description" "4k7 resistor in 0402 package with 1% tolerance")
    (attr smd)
    (fp_text reference "R32" (at -1.095 2.51) (layer "F.SilkS")
        (effects (font (size 0.7 0.7) (thickness 0.15)) (justify left bottom))
    )
    (fp_text value "R_4k7_0402" (at 0 1.4) (layer "F.Fab") hide
        (effects (font (size 0.7 0.7) (thickness 0.15)) (justify left bottom))
    )
    (fp_text user "${REFERENCE}" (at -0.95 3.168) (layer "F.Fab") hide
        (effects (font (size 0.7 0.7) (thickness 0.15)) (justify left bottom))
    )
    (fp_text user "License: Apache-2.0" (at -0.95 5.169) (layer "F.Fab") hide
        (effects (font (size 0.7 0.7) (thickness 0.15)) (justify left bottom))
    )
    (fp_text user "Author: Antmicro" (at -0.95 4.169) (layer "F.Fab") hide
        (effects (font (size 0.7 0.7) (thickness 0.15)) (justify left bottom))
    )
    (fp_rect (start -0.93 -0.47) (end 0.93 0.47)
      (stroke (width 0.05) (type solid)) (fill none) (layer "F.CrtYd"))
    (fp_rect (start -0.5 -0.25) (end 0.5 0.25)
      (stroke (width 0.15) (type solid)) (fill none) (layer "F.Fab"))
    (pad "1" smd roundrect (at -0.485 0) (size 0.59 0.64) (layers "F.Cu" "F.Paste" "F.Mask") (roundrect_rratio 0.25)
      (net 143 "3V3_SYS") (pintype "passive"))
    (pad "2" smd roundrect (at 0.485 0) (size 0.59 0.64) (layers "F.Cu" "F.Paste" "F.Mask") (roundrect_rratio 0.25)
      (net 91 "PROGRAM_B") (pintype "passive"))
  )

  (footprint "data-center-rdimm-ddr4-tester-footprints:Testpoint_smd_1mm" (layer "F.Cu")
    (at 110 98.1 90)
    (property "Author" "Antmicro")
    (property "License" "Apache-2.0")
    (property "MPN" "")
    (property "Manufacturer" "")
    (property "Sheetfile" "supply.kicad_sch")
    (property "Sheetname" "Supply")
    (property "ki_description" "Test Point 1mm")
    (attr exclude_from_pos_files)
    (fp_text reference "VIN1" (at -0.34 0.65 180) (layer "F.SilkS")
        (effects (font (size 0.7 0.7) (thickness 0.15)) (justify left bottom))
    )
    (fp_text value "TP_1mm_SMD" (at 0 1.4 90) (layer "F.Fab") hide
        (effects (font (size 0.7 0.7) (thickness 0.15)) (justify left bottom))
    )
    (fp_text user "${REFERENCE}" (at -0.5 2.8 90) (layer "F.Fab") hide
        (effects (font (size 0.7 0.7) (thickness 0.15)) (justify left bottom))
    )
    (fp_text user "License: Apache-2.0" (at -0.5 5.2 90) (layer "F.Fab") hide
        (effects (font (size 0.7 0.7) (thickness 0.15)) (justify left bottom))
    )
    (fp_text user "Author: Antmicro" (at -0.5 4 90) (layer "F.Fab") hide
        (effects (font (size 0.7 0.7) (thickness 0.15)) (justify left bottom))
    )
    (pad "1" smd circle (at 0 0 90) (size 1 1) (layers "F.Cu" "F.Mask")
      (net 103 "VIN") (pinfunction "1") (pintype "passive"))
  )

  (footprint "data-center-rdimm-ddr4-tester-footprints:Testpoint_smd_1mm" (layer "F.Cu")
    (at 129.986328 79.560008 90)
    (property "Author" "Antmicro")
    (property "License" "Apache-2.0")
    (property "MPN" "")
    (property "Manufacturer" "")
    (property "Sheetfile" "supply.kicad_sch")
    (property "Sheetname" "Supply")
    (property "ki_description" "Test Point 1mm")
    (attr exclude_from_pos_files)
    (fp_text reference "1V8" (at 0.560008 -1.046328 180) (layer "F.SilkS")
        (effects (font (size 0.7 0.7) (thickness 0.15)) (justify left bottom))
    )
    (fp_text value "TP_1mm_SMD" (at 0 1.4 90) (layer "F.Fab") hide
        (effects (font (size 0.7 0.7) (thickness 0.15)) (justify left bottom))
    )
    (fp_text user "${REFERENCE}" (at -0.5 2.8 90) (layer "F.Fab") hide
        (effects (font (size 0.7 0.7) (thickness 0.15)) (justify left bottom))
    )
    (fp_text user "Author: Antmicro" (at -0.5 4 90) (layer "F.Fab") hide
        (effects (font (size 0.7 0.7) (thickness 0.15)) (justify left bottom))
    )
    (fp_text user "License: Apache-2.0" (at -0.5 5.2 90) (layer "F.Fab") hide
        (effects (font (size 0.7 0.7) (thickness 0.15)) (justify left bottom))
    )
    (pad "1" smd circle (at 0 0 90) (size 1 1) (layers "F.Cu" "F.Mask")
      (net 302 "VCC1V8") (pinfunction "1") (pintype "passive"))
  )

  (footprint "data-center-rdimm-ddr4-tester-footprints:Testpoint_smd_1mm" (layer "F.Cu")
    (at 132.786328 109.710008 180)
    (property "Author" "Antmicro")
    (property "License" "Apache-2.0")
    (property "MPN" "")
    (property "Manufacturer" "")
    (property "Sheetfile" "supply.kicad_sch")
    (property "Sheetname" "Supply")
    (property "ki_description" "Test Point 1mm")
    (attr exclude_from_pos_files)
    (fp_text reference "5V0" (at -0.653672 -0.359992 180) (layer "F.SilkS")
        (effects (font (size 0.7 0.7) (thickness 0.15)) (justify left bottom))
    )
    (fp_text value "TP_1mm_SMD" (at 0 1.4 180) (layer "F.Fab") hide
        (effects (font (size 0.7 0.7) (thickness 0.15)) (justify left bottom))
    )
    (fp_text user "License: Apache-2.0" (at -0.5 5.2 180) (layer "F.Fab") hide
        (effects (font (size 0.7 0.7) (thickness 0.15)) (justify left bottom))
    )
    (fp_text user "${REFERENCE}" (at -0.5 2.8 180) (layer "F.Fab") hide
        (effects (font (size 0.7 0.7) (thickness 0.15)) (justify left bottom))
    )
    (fp_text user "Author: Antmicro" (at -0.5 4 180) (layer "F.Fab") hide
        (effects (font (size 0.7 0.7) (thickness 0.15)) (justify left bottom))
    )
    (pad "1" smd circle (at 0 0 180) (size 1 1) (layers "F.Cu" "F.Mask")
      (net 104 "VCC5V0") (pinfunction "1") (pintype "passive"))
  )

  (footprint "data-center-rdimm-ddr4-tester-footprints:C_0603_1608Metric" (layer "F.Cu")
    (at 115.786328 80.560008 180)
    (descr "Capacitor SMD 0603")
    (tags "capacitor 0603")
    (property "Author" "Antmicro")
    (property "Dielectric" "")
    (property "License" "Apache-2.0")
    (property "MPN" "06031C103JAT2A")
    (property "Manufacturer" "AVX")
    (property "Sheetfile" "supply.kicad_sch")
    (property "Sheetname" "Supply")
    (property "Val" "10n")
    (property "Voltage" "")
    (property "ki_description" " ")
    (attr smd)
    (fp_text reference "C106" (at 1.446328 9.710008 180) (layer "F.SilkS")
        (effects (font (size 0.7 0.7) (thickness 0.15)) (justify left bottom))
    )
    (fp_text value "C_10n_0603" (at 0 1.6 180) (layer "F.Fab") hide
        (effects (font (size 0.7 0.7) (thickness 0.15)) (justify left bottom))
    )
    (fp_text user "Author: Antmicro" (at -1.682 4.894 180) (layer "F.Fab") hide
        (effects (font (size 0.7 0.7) (thickness 0.15)) (justify left bottom))
    )
    (fp_text user "${REFERENCE}" (at -1.682 3.895 180) (layer "F.Fab") hide
        (effects (font (size 0.7 0.7) (thickness 0.15)) (justify left bottom))
    )
    (fp_text user "License: Apache-2.0" (at -1.682 5.895 180) (layer "F.Fab") hide
        (effects (font (size 0.7 0.7) (thickness 0.15)) (justify left bottom))
    )
    (fp_line (start -0.3 -0.3) (end 0.3 -0.3)
      (stroke (width 0.15) (type solid)) (layer "F.SilkS"))
    (fp_line (start -0.3 0.3) (end 0.3 0.3)
      (stroke (width 0.15) (type solid)) (layer "F.SilkS"))
    (fp_rect (start -1.24 -0.7) (end 1.24 0.7)
      (stroke (width 0.05) (type solid)) (fill none) (layer "F.CrtYd"))
    (fp_rect (start -0.8 -0.4) (end 0.8 0.4)
      (stroke (width 0.15) (type solid)) (fill none) (layer "F.Fab"))
    (pad "1" smd roundrect (at -0.7 0 180) (size 0.6 0.8) (layers "F.Cu" "F.Paste" "F.Mask") (roundrect_rratio 0.2)
      (net 77 "VDDQ") (pintype "passive"))
    (pad "2" smd roundrect (at 0.7 0 180) (size 0.6 0.8) (layers "F.Cu" "F.Paste" "F.Mask") (roundrect_rratio 0.2)
      (net 9 "GND") (pintype "passive"))
  )

  (footprint "data-center-rdimm-ddr4-tester-footprints:C_0603_1608Metric" (layer "F.Cu")
    (at 115.786328 79.060008 180)
    (descr "Capacitor SMD 0603")
    (tags "capacitor 0603")
    (property "Author" "Antmicro")
    (property "Dielectric" "")
    (property "License" "Apache-2.0")
    (property "MPN" "06031C103JAT2A")
    (property "Manufacturer" "AVX")
    (property "Sheetfile" "supply.kicad_sch")
    (property "Sheetname" "Supply")
    (property "Val" "10n")
    (property "Voltage" "")
    (property "ki_description" " ")
    (attr smd)
    (fp_text reference "C108" (at 1.436328 9.150008 180) (layer "F.SilkS")
        (effects (font (size 0.7 0.7) (thickness 0.15)) (justify left bottom))
    )
    (fp_text value "C_10n_0603" (at 0 1.6 180) (layer "F.Fab") hide
        (effects (font (size 0.7 0.7) (thickness 0.15)) (justify left bottom))
    )
    (fp_text user "Author: Antmicro" (at -1.682 4.894 180) (layer "F.Fab") hide
        (effects (font (size 0.7 0.7) (thickness 0.15)) (justify left bottom))
    )
    (fp_text user "License: Apache-2.0" (at -1.682 5.895 180) (layer "F.Fab") hide
        (effects (font (size 0.7 0.7) (thickness 0.15)) (justify left bottom))
    )
    (fp_text user "${REFERENCE}" (at -1.682 3.895 180) (layer "F.Fab") hide
        (effects (font (size 0.7 0.7) (thickness 0.15)) (justify left bottom))
    )
    (fp_line (start -0.3 -0.3) (end 0.3 -0.3)
      (stroke (width 0.15) (type solid)) (layer "F.SilkS"))
    (fp_line (start -0.3 0.3) (end 0.3 0.3)
      (stroke (width 0.15) (type solid)) (layer "F.SilkS"))
    (fp_rect (start -1.24 -0.7) (end 1.24 0.7)
      (stroke (width 0.05) (type solid)) (fill none) (layer "F.CrtYd"))
    (fp_rect (start -0.8 -0.4) (end 0.8 0.4)
      (stroke (width 0.15) (type solid)) (fill none) (layer "F.Fab"))
    (pad "1" smd roundrect (at -0.7 0 180) (size 0.6 0.8) (layers "F.Cu" "F.Paste" "F.Mask") (roundrect_rratio 0.2)
      (net 77 "VDDQ") (pintype "passive"))
    (pad "2" smd roundrect (at 0.7 0 180) (size 0.6 0.8) (layers "F.Cu" "F.Paste" "F.Mask") (roundrect_rratio 0.2)
      (net 9 "GND") (pintype "passive"))
  )

  (footprint "data-center-rdimm-ddr4-tester-footprints:C_0603_1608Metric" (layer "F.Cu")
    (at 125.686328 82.860008)
    (descr "Capacitor SMD 0603")
    (tags "capacitor 0603")
    (property "Author" "Antmicro")
    (property "Dielectric" "")
    (property "License" "Apache-2.0")
    (property "MPN" "06031C103JAT2A")
    (property "Manufacturer" "AVX")
    (property "Sheetfile" "supply.kicad_sch")
    (property "Sheetname" "Supply")
    (property "Val" "10n")
    (property "Voltage" "")
    (property "ki_description" " ")
    (attr smd)
    (fp_text reference "C110" (at -1.406328 -3.230008) (layer "F.SilkS")
        (effects (font (size 0.7 0.7) (thickness 0.15)) (justify left bottom))
    )
    (fp_text value "C_10n_0603" (at 0 1.6) (layer "F.Fab") hide
        (effects (font (size 0.7 0.7) (thickness 0.15)) (justify left bottom))
    )
    (fp_text user "${REFERENCE}" (at -1.682 3.895) (layer "F.Fab") hide
        (effects (font (size 0.7 0.7) (thickness 0.15)) (justify left bottom))
    )
    (fp_text user "Author: Antmicro" (at -1.682 4.894) (layer "F.Fab") hide
        (effects (font (size 0.7 0.7) (thickness 0.15)) (justify left bottom))
    )
    (fp_text user "License: Apache-2.0" (at -1.682 5.895) (layer "F.Fab") hide
        (effects (font (size 0.7 0.7) (thickness 0.15)) (justify left bottom))
    )
    (fp_line (start -0.3 -0.3) (end 0.3 -0.3)
      (stroke (width 0.15) (type solid)) (layer "F.SilkS"))
    (fp_line (start -0.3 0.3) (end 0.3 0.3)
      (stroke (width 0.15) (type solid)) (layer "F.SilkS"))
    (fp_rect (start -1.24 -0.7) (end 1.24 0.7)
      (stroke (width 0.05) (type solid)) (fill none) (layer "F.CrtYd"))
    (fp_rect (start -0.8 -0.4) (end 0.8 0.4)
      (stroke (width 0.15) (type solid)) (fill none) (layer "F.Fab"))
    (pad "1" smd roundrect (at -0.7 0) (size 0.6 0.8) (layers "F.Cu" "F.Paste" "F.Mask") (roundrect_rratio 0.2)
      (net 184 "VPP") (pintype "passive"))
    (pad "2" smd roundrect (at 0.7 0) (size 0.6 0.8) (layers "F.Cu" "F.Paste" "F.Mask") (roundrect_rratio 0.2)
      (net 9 "GND") (pintype "passive"))
  )

  (footprint "data-center-rdimm-ddr4-tester-footprints:C_0603_1608Metric" (layer "F.Cu")
    (at 125.686328 87.310008)
    (descr "Capacitor SMD 0603")
    (tags "capacitor 0603")
    (property "Author" "Antmicro")
    (property "Dielectric" "")
    (property "License" "Apache-2.0")
    (property "MPN" "06031C103JAT2A")
    (property "Manufacturer" "AVX")
    (property "Sheetfile" "supply.kicad_sch")
    (property "Sheetname" "Supply")
    (property "Val" "10n")
    (property "Voltage" "")
    (property "ki_description" " ")
    (attr smd)
    (fp_text reference "C111" (at -1.386328 -5.000008) (layer "F.SilkS")
        (effects (font (size 0.7 0.7) (thickness 0.15)) (justify left bottom))
    )
    (fp_text value "C_10n_0603" (at 0 1.6) (layer "F.Fab") hide
        (effects (font (size 0.7 0.7) (thickness 0.15)) (justify left bottom))
    )
    (fp_text user "Author: Antmicro" (at -1.682 4.894) (layer "F.Fab") hide
        (effects (font (size 0.7 0.7) (thickness 0.15)) (justify left bottom))
    )
    (fp_text user "${REFERENCE}" (at -1.682 3.895) (layer "F.Fab") hide
        (effects (font (size 0.7 0.7) (thickness 0.15)) (justify left bottom))
    )
    (fp_text user "License: Apache-2.0" (at -1.682 5.895) (layer "F.Fab") hide
        (effects (font (size 0.7 0.7) (thickness 0.15)) (justify left bottom))
    )
    (fp_line (start -0.3 -0.3) (end 0.3 -0.3)
      (stroke (width 0.15) (type solid)) (layer "F.SilkS"))
    (fp_line (start -0.3 0.3) (end 0.3 0.3)
      (stroke (width 0.15) (type solid)) (layer "F.SilkS"))
    (fp_rect (start -1.24 -0.7) (end 1.24 0.7)
      (stroke (width 0.05) (type solid)) (fill none) (layer "F.CrtYd"))
    (fp_rect (start -0.8 -0.4) (end 0.8 0.4)
      (stroke (width 0.15) (type solid)) (fill none) (layer "F.Fab"))
    (pad "1" smd roundrect (at -0.7 0) (size 0.6 0.8) (layers "F.Cu" "F.Paste" "F.Mask") (roundrect_rratio 0.2)
      (net 184 "VPP") (pintype "passive"))
    (pad "2" smd roundrect (at 0.7 0) (size 0.6 0.8) (layers "F.Cu" "F.Paste" "F.Mask") (roundrect_rratio 0.2)
      (net 9 "GND") (pintype "passive"))
  )

  (footprint "data-center-rdimm-ddr4-tester-footprints:C_0603_1608Metric" (layer "F.Cu")
    (at 125.686328 84.343341)
    (descr "Capacitor SMD 0603")
    (tags "capacitor 0603")
    (property "Author" "Antmicro")
    (property "Dielectric" "")
    (property "License" "Apache-2.0")
    (property "MPN" "06031C103JAT2A")
    (property "Manufacturer" "AVX")
    (property "Sheetfile" "supply.kicad_sch")
    (property "Sheetname" "Supply")
    (property "Val" "10n")
    (property "Voltage" "")
    (property "ki_description" " ")
    (attr smd)
    (fp_text reference "C112" (at -1.396328 -3.833341) (layer "F.SilkS")
        (effects (font (size 0.7 0.7) (thickness 0.15)) (justify left bottom))
    )
    (fp_text value "C_10n_0603" (at 0 1.6) (layer "F.Fab") hide
        (effects (font (size 0.7 0.7) (thickness 0.15)) (justify left bottom))
    )
    (fp_text user "License: Apache-2.0" (at -1.682 5.895) (layer "F.Fab") hide
        (effects (font (size 0.7 0.7) (thickness 0.15)) (justify left bottom))
    )
    (fp_text user "${REFERENCE}" (at -1.682 3.895) (layer "F.Fab") hide
        (effects (font (size 0.7 0.7) (thickness 0.15)) (justify left bottom))
    )
    (fp_text user "Author: Antmicro" (at -1.682 4.894) (layer "F.Fab") hide
        (effects (font (size 0.7 0.7) (thickness 0.15)) (justify left bottom))
    )
    (fp_line (start -0.3 -0.3) (end 0.3 -0.3)
      (stroke (width 0.15) (type solid)) (layer "F.SilkS"))
    (fp_line (start -0.3 0.3) (end 0.3 0.3)
      (stroke (width 0.15) (type solid)) (layer "F.SilkS"))
    (fp_rect (start -1.24 -0.7) (end 1.24 0.7)
      (stroke (width 0.05) (type solid)) (fill none) (layer "F.CrtYd"))
    (fp_rect (start -0.8 -0.4) (end 0.8 0.4)
      (stroke (width 0.15) (type solid)) (fill none) (layer "F.Fab"))
    (pad "1" smd roundrect (at -0.7 0) (size 0.6 0.8) (layers "F.Cu" "F.Paste" "F.Mask") (roundrect_rratio 0.2)
      (net 184 "VPP") (pintype "passive"))
    (pad "2" smd roundrect (at 0.7 0) (size 0.6 0.8) (layers "F.Cu" "F.Paste" "F.Mask") (roundrect_rratio 0.2)
      (net 9 "GND") (pintype "passive"))
  )

  (footprint "data-center-rdimm-ddr4-tester-footprints:C_0603_1608Metric" (layer "F.Cu")
    (at 115.936328 84.660008 180)
    (descr "Capacitor SMD 0603")
    (tags "capacitor 0603")
    (property "Author" "Antmicro")
    (property "Dielectric" "")
    (property "License" "Apache-2.0")
    (property "MPN" "GRM188R60J226MEA0D")
    (property "Manufacturer" "Murata")
    (property "Sheetfile" "supply.kicad_sch")
    (property "Sheetname" "Supply")
    (property "Val" "22u")
    (property "Voltage" "")
    (property "ki_description" " ")
    (attr smd)
    (fp_text reference "C159" (at 1.576328 11.840008 180) (layer "F.SilkS")
        (effects (font (size 0.7 0.7) (thickness 0.15)) (justify left bottom))
    )
    (fp_text value "C_22u_0603" (at 0 1.6 180) (layer "F.Fab") hide
        (effects (font (size 0.7 0.7) (thickness 0.15)) (justify left bottom))
    )
    (fp_text user "License: Apache-2.0" (at -1.682 5.895 180) (layer "F.Fab") hide
        (effects (font (size 0.7 0.7) (thickness 0.15)) (justify left bottom))
    )
    (fp_text user "Author: Antmicro" (at -1.682 4.894 180) (layer "F.Fab") hide
        (effects (font (size 0.7 0.7) (thickness 0.15)) (justify left bottom))
    )
    (fp_text user "${REFERENCE}" (at -1.682 3.895 180) (layer "F.Fab") hide
        (effects (font (size 0.7 0.7) (thickness 0.15)) (justify left bottom))
    )
    (fp_line (start -0.3 -0.3) (end 0.3 -0.3)
      (stroke (width 0.15) (type solid)) (layer "F.SilkS"))
    (fp_line (start -0.3 0.3) (end 0.3 0.3)
      (stroke (width 0.15) (type solid)) (layer "F.SilkS"))
    (fp_rect (start -1.24 -0.7) (end 1.24 0.7)
      (stroke (width 0.05) (type solid)) (fill none) (layer "F.CrtYd"))
    (fp_rect (start -0.8 -0.4) (end 0.8 0.4)
      (stroke (width 0.15) (type solid)) (fill none) (layer "F.Fab"))
    (pad "1" smd roundrect (at -0.7 0 180) (size 0.6 0.8) (layers "F.Cu" "F.Paste" "F.Mask") (roundrect_rratio 0.2)
      (net 301 "VDD1V2") (pintype "passive"))
    (pad "2" smd roundrect (at 0.7 0 180) (size 0.6 0.8) (layers "F.Cu" "F.Paste" "F.Mask") (roundrect_rratio 0.2)
      (net 9 "GND") (pintype "passive"))
  )

  (footprint "data-center-rdimm-ddr4-tester-footprints:Testpoint_smd_1mm" (layer "F.Cu")
    (at 146.05 124.2 90)
    (property "Author" "Antmicro")
    (property "License" "Apache-2.0")
    (property "MPN" "")
    (property "Manufacturer" "")
    (property "Sheetfile" "supply.kicad_sch")
    (property "Sheetname" "Supply")
    (property "ki_description" "Test Point 1mm")
    (attr exclude_from_pos_files)
    (fp_text reference "PHY1" (at -0.36 -3.35 180) (layer "F.SilkS")
        (effects (font (size 0.7 0.7) (thickness 0.15)) (justify left bottom))
    )
    (fp_text value "TP_1mm_SMD" (at 0 1.4 90) (layer "F.Fab") hide
        (effects (font (size 0.7 0.7) (thickness 0.15)) (justify left bottom))
    )
    (fp_text user "Author: Antmicro" (at -0.5 4 90) (layer "F.Fab") hide
        (effects (font (size 0.7 0.7) (thickness 0.15)) (justify left bottom))
    )
    (fp_text user "${REFERENCE}" (at -0.5 2.8 90) (layer "F.Fab") hide
        (effects (font (size 0.7 0.7) (thickness 0.15)) (justify left bottom))
    )
    (fp_text user "License: Apache-2.0" (at -0.5 5.2 90) (layer "F.Fab") hide
        (effects (font (size 0.7 0.7) (thickness 0.15)) (justify left bottom))
    )
    (pad "1" smd circle (at 0 0 90) (size 1 1) (layers "F.Cu" "F.Mask")
      (net 306 "1V2_SYS") (pinfunction "1") (pintype "passive"))
  )

  (footprint "data-center-rdimm-ddr4-tester-footprints:TPS65295RJET" (layer "F.Cu")
    (at 119.606328 99.280008)
    (property "Author" "Antmicro")
    (property "License" "Apache-2.0")
    (property "MPN" "TPS65295RJET")
    (property "Manufacturer" "Texas Instruments")
    (property "Sheetfile" "supply.kicad_sch")
    (property "Sheetname" "Supply")
    (attr smd)
    (fp_text reference "U2" (at -0.496328 -2.150008) (layer "F.SilkS")
        (effects (font (size 0.7 0.7) (thickness 0.15)) (justify left bottom))
    )
    (fp_text value "TPS65295RJE" (at 0 3.1) (layer "F.Fab") hide
        (effects (font (size 0.7 0.7) (thickness 0.15)) (justify left bottom))
    )
    (fp_text user "${REFERENCE}" (at -2.301 5.108) (layer "F.Fab") hide
        (effects (font (size 0.7 0.7) (thickness 0.15)) (justify left bottom))
    )
    (fp_text user "Author: Antmicro" (at -2.301 6.108) (layer "F.Fab") hide
        (effects (font (size 0.7 0.7) (thickness 0.15)) (justify left bottom))
    )
    (fp_text user "License: Apache-2.0" (at -2.301 7.108) (layer "F.Fab") hide
        (effects (font (size 0.7 0.7) (thickness 0.15)) (justify left bottom))
    )
    (fp_poly
      (pts
        (xy -0.352 0.484)
        (xy -0.551 0.484)
        (xy -0.551 -0.535)
        (xy -0.352 -0.535)
      )

      (stroke (width 0.001) (type solid)) (fill solid) (layer "F.Paste"))
    (fp_poly
      (pts
        (xy -0.352 1.703)
        (xy -0.551 1.703)
        (xy -0.551 0.685)
        (xy -0.352 0.685)
      )

      (stroke (width 0.001) (type solid)) (fill solid) (layer "F.Paste"))
    (fp_poly
      (pts
        (xy 0.099 -0.687)
        (xy -0.1 -0.687)
        (xy -0.1 -1.706)
        (xy 0.099 -1.706)
      )

      (stroke (width 0.001) (type solid)) (fill solid) (layer "F.Paste"))
    (fp_poly
      (pts
        (xy 0.099 0.535)
        (xy -0.1 0.535)
        (xy -0.1 -0.485)
        (xy 0.099 -0.485)
      )

      (stroke (width 0.001) (type solid)) (fill solid) (layer "F.Paste"))
    (fp_poly
      (pts
        (xy 0.548 0.484)
        (xy 0.349 0.484)
        (xy 0.349 -0.535)
        (xy 0.548 -0.535)
      )

      (stroke (width 0.001) (type solid)) (fill solid) (layer "F.Paste"))
    (fp_poly
      (pts
        (xy 0.548 1.703)
        (xy 0.349 1.703)
        (xy 0.349 0.685)
        (xy 0.548 0.685)
      )

      (stroke (width 0.001) (type solid)) (fill solid) (layer "F.Paste"))
    (fp_poly
      (pts
        (xy -1.103 -1.706)
        (xy -1.355 -1.706)
        (xy -1.355 -1.351)
        (xy -1.702 -1.351)
        (xy -1.702 -1.127)
        (xy -1.103 -1.127)
      )

      (stroke (width 0.001) (type solid)) (fill solid) (layer "F.Paste"))
    (fp_poly
      (pts
        (xy -1.101 1.705)
        (xy -1.355 1.703)
        (xy -1.355 1.348)
        (xy -1.7 1.35)
        (xy -1.7 1.124)
        (xy -1.101 1.124)
      )

      (stroke (width 0.001) (type solid)) (fill solid) (layer "F.Paste"))
    (fp_poly
      (pts
        (xy 1.1 -1.706)
        (xy 1.352 -1.706)
        (xy 1.352 -1.351)
        (xy 1.699 -1.351)
        (xy 1.699 -1.125)
        (xy 1.1 -1.125)
      )

      (stroke (width 0.001) (type solid)) (fill solid) (layer "F.Paste"))
    (fp_poly
      (pts
        (xy 1.1 1.705)
        (xy 1.352 1.703)
        (xy 1.352 1.348)
        (xy 1.699 1.35)
        (xy 1.699 1.124)
        (xy 1.1 1.124)
      )

      (stroke (width 0.001) (type solid)) (fill solid) (layer "F.Paste"))
    (fp_line (start -1.932 -1.932) (end -1.932 -1.597)
      (stroke (width 0.15) (type solid)) (layer "F.SilkS"))
    (fp_line (start -1.932 1.596) (end -1.932 1.929)
      (stroke (width 0.15) (type solid)) (layer "F.SilkS"))
    (fp_line (start -1.932 1.929) (end -1.621 1.929)
      (stroke (width 0.15) (type solid)) (layer "F.SilkS"))
    (fp_line (start -1.621 -1.932) (end -1.932 -1.932)
      (stroke (width 0.15) (type solid)) (layer "F.SilkS"))
    (fp_line (start 1.618 1.929) (end 1.929 1.929)
      (stroke (width 0.15) (type solid)) (layer "F.SilkS"))
    (fp_line (start 1.929 -1.932) (end 1.618 -1.932)
      (stroke (width 0.15) (type solid)) (layer "F.SilkS"))
    (fp_line (start 1.929 -1.597) (end 1.929 -1.932)
      (stroke (width 0.15) (type solid)) (layer "F.SilkS"))
    (fp_line (start 1.929 1.929) (end 1.929 1.596)
      (stroke (width 0.15) (type solid)) (layer "F.SilkS"))
    (fp_circle (center -2.3 -1.25) (end -2.25 -1.2)
      (stroke (width 0.15) (type solid)) (fill solid) (layer "F.SilkS"))
    (fp_circle (center -2.246 -1.258) (end -2.19 -1.258)
      (stroke (width 0.15) (type solid)) (fill none) (layer "F.SilkS"))
    (fp_rect (start -2 -2) (end 2 2)
      (stroke (width 0.05) (type solid)) (fill none) (layer "F.CrtYd"))
    (fp_line (start -1.551 -0.802) (end -1.551 1.548)
      (stroke (width 0.15) (type solid)) (layer "F.Fab"))
    (fp_line (start -1.551 -0.802) (end -0.802 -1.551)
      (stroke (width 0.15) (type solid)) (layer "F.Fab"))
    (fp_line (start -1.551 1.548) (end 1.548 1.548)
      (stroke (width 0.15) (type solid)) (layer "F.Fab"))
    (fp_line (start 1.548 -1.551) (end -0.802 -1.551)
      (stroke (width 0.15) (type solid)) (layer "F.Fab"))
    (fp_line (start 1.548 1.548) (end 1.548 -1.551)
      (stroke (width 0.15) (type solid)) (layer "F.Fab"))
    (pad "1" smd custom (at -1.401 -1.25 90) (size 0.25 0.6) (layers "F.Cu" "F.Mask")
      (net 301 "VDD1V2") (pinfunction "VLDOIN") (pintype "power_in")
      (options (clearance outline) (anchor rect))
      (primitives
        (gr_poly
          (pts
            (xy 0.4548 0.3)
            (xy 0.454997 0.016207)
            (xy 0.124997 0.016207)
            (xy 0.125 -0.3)
            (xy -0.125 -0.3)
            (xy -0.125 0.3)
          )
          (width 0.001) (fill yes))
        (gr_poly
          (pts
            (xy 0.4548 0.3)
            (xy 0.454997 0.016207)
            (xy 0.124997 0.016207)
            (xy 0.125 -0.3)
            (xy -0.125 -0.3)
            (xy -0.125 0.3)
          )
          (width 0.001) (fill yes))
      ))
    (pad "2" smd rect (at -1.401 -0.751 90) (size 0.25 0.6) (layers "F.Cu" "F.Paste" "F.Mask")
      (net 299 "VCC0V6") (pinfunction "VTT") (pintype "input"))
    (pad "3" smd rect (at -1.401 -0.25 90) (size 0.25 0.6) (layers "F.Cu" "F.Paste" "F.Mask")
      (net 9 "GND") (pinfunction "AGND") (pintype "power_in"))
    (pad "4" smd rect (at -1.401 0.248 90) (size 0.25 0.6) (layers "F.Cu" "F.Paste" "F.Mask")
      (net 616 "Net-(U2-VTTSNS)") (pinfunction "VTTSNS") (pintype "input"))
    (pad "5" smd rect (at -1.401 0.749 90) (size 0.25 0.6) (layers "F.Cu" "F.Paste" "F.Mask")
      (net 301 "VDD1V2") (pinfunction "VDDQSNS") (pintype "input"))
    (pad "6" smd custom (at -1.401 1.249 90) (size 0.25 0.6) (layers "F.Cu" "F.Paste" "F.Mask")
      (net 305 "/Supply/VTTREF") (pinfunction "VTTREF") (pintype "input")
      (options (clearance outline) (anchor rect))
      (primitives
        (gr_poly
          (pts
            (xy -0.4548 0.3)
            (xy -0.454997 0.016207)
            (xy -0.124997 0.016207)
            (xy -0.125 -0.3)
            (xy 0.125 -0.3)
            (xy 0.125 0.3)
          )
          (width 0.001) (fill yes))
        (gr_poly
          (pts
            (xy -0.4548 0.3)
            (xy -0.454997 0.016207)
            (xy -0.124997 0.016207)
            (xy -0.125 -0.3)
            (xy 0.125 -0.3)
            (xy 0.125 0.3)
          )
          (width 0.001) (fill yes))
      ))
    (pad "7" smd rect (at -0.452 0.583) (size 0.2 2.238) (layers "F.Cu" "F.Mask")
      (net 103 "VIN") (pinfunction "PVIN") (pintype "power_in"))
    (pad "8" smd rect (at 0 1.354) (size 0.2 0.7) (layers "F.Cu" "F.Paste" "F.Mask")
      (net 613 "Net-(U2-PGOOD)") (pinfunction "PGOOD") (pintype "output"))
    (pad "9" smd rect (at 0.45 0.583) (size 0.2 2.238) (layers "F.Cu" "F.Mask")
      (net 9 "GND") (pinfunction "PGND") (pintype "power_in"))
    (pad "10" smd custom (at 1.398 1.249 270) (size 0.25 0.6) (layers "F.Cu" "F.Mask")
      (net 793 "/Supply/VTT_CNTL") (pinfunction "VTT_CNTL") (pintype "input")
      (options (clearance outline) (anchor rect))
      (primitives
        (gr_poly
          (pts
            (xy 0.4548 0.3)
            (xy 0.454997 0.016207)
            (xy 0.124997 0.016207)
            (xy 0.125 -0.3)
            (xy -0.125 -0.3)
            (xy -0.125 0.3)
          )
          (width 0.001) (fill yes))
        (gr_poly
          (pts
            (xy 0.4548 0.3)
            (xy 0.454997 0.016207)
            (xy 0.124997 0.016207)
            (xy 0.125 -0.3)
            (xy -0.125 -0.3)
            (xy -0.125 0.3)
          )
          (width 0.001) (fill yes))
      ))
    (pad "11" smd rect (at 1.398 0.749 90) (size 0.25 0.6096) (layers "F.Cu" "F.Paste" "F.Mask")
      (net 794 "/Supply/SLP_S4") (pinfunction "SLP_S4") (pintype "input"))
    (pad "12" smd rect (at 1.398 0.248 90) (size 0.25 0.6096) (layers "F.Cu" "F.Paste" "F.Mask")
      (net 303 "VCC2V5") (pinfunction "VPPSNS") (pintype "input"))
    (pad "13" smd rect (at 1.398 -0.25 90) (size 0.25 0.6096) (layers "F.Cu" "F.Paste" "F.Mask")
      (net 307 "5V0_SYS") (pinfunction "VCC_5V") (pintype "power_in"))
    (pad "14" smd rect (at 1.398 -0.751 90) (size 0.25 0.6) (layers "F.Cu" "F.Paste" "F.Mask")
      (net 307 "5V0_SYS") (pinfunction "PVIN_VPP") (pintype "power_in"))
    (pad "15" smd custom (at 1.398 -1.25 270) (size 0.25 0.6) (layers "F.Cu" "F.Mask")
      (net 571 "Net-(U2-SW_VPP)") (pinfunction "SW_VPP") (pintype "input")
      (options (clearance outline) (anchor rect))
      (primitives
        (gr_poly
          (pts
            (xy -0.4548 0.3)
            (xy -0.454997 0.016207)
            (xy -0.124997 0.016207)
            (xy -0.125 -0.3)
            (xy 0.125 -0.3)
            (xy 0.125 0.3)
          )
          (width 0.001) (fill yes))
        (gr_poly
          (pts
            (xy -0.4548 0.3)
            (xy -0.454997 0.016207)
            (xy -0.124997 0.016207)
            (xy -0.125 -0.3)
            (xy 0.125 -0.3)
            (xy 0.125 0.3)
          )
          (width 0.001) (fill yes))
      ))
    (pad "16" smd rect (at 0.65 -1.401) (size 0.2 0.6096) (layers "F.Cu" "F.Paste" "F.Mask")
      (net 9 "GND") (pinfunction "PGND") (pintype "passive"))
    (pad "17" smd rect (at 0 -0.585) (size 0.2 2.243) (layers "F.Cu" "F.Mask")
      (net 1 "Net-(U2-SW)") (pinfunction "SW") (pintype "input"))
    (pad "18" smd rect (at -0.652 -1.401) (size 0.2 0.6096) (layers "F.Cu" "F.Paste" "F.Mask")
      (net 601 "Net-(U2-BST)") (pinfunction "BST") (pintype "input"))
  )

  (footprint "data-center-rdimm-ddr4-tester-footprints:KEMET_D" (layer "F.Cu")
    (at 141.186328 78.810008 180)
    (descr "Capacitor SMD KEMET_D")
    (tags "capacitor SMD KEMET_D")
    (property "Author" "Antmicro")
    (property "Dielectric" "")
    (property "License" "Apache-2.0")
    (property "MPN" "T520D337M006ATE045")
    (property "Manufacturer" "KEMET")
    (property "Sheetfile" "fpga-power.kicad_sch")
    (property "Sheetname" "FPGA power")
    (property "Val" "330u")
    (property "Voltage" "")
    (property "ki_description" " ")
    (attr smd)
    (fp_text reference "C26" (at -3.683672 1.470008 180) (layer "F.SilkS")
        (effects (font (size 0.7 0.7) (thickness 0.15)) (justify left bottom))
    )
    (fp_text value "C_330u_KEMET_D" (at 0 3.6 180) (layer "F.Fab") hide
        (effects (font (size 0.7 0.7) (thickness 0.15)) (justify left bottom))
    )
    (fp_text user "Author: Antmicro" (at -4.5 7.6 180) (layer "F.Fab") hide
        (effects (font (size 0.7 0.7) (thickness 0.15)) (justify left bottom))
    )
    (fp_text user "${REFERENCE}" (at -4.5 5.6 180) (layer "F.Fab") hide
        (effects (font (size 0.7 0.7) (thickness 0.15)) (justify left bottom))
    )
    (fp_text user "License: Apache-2.0" (at -4.5 6.6 180) (layer "F.Fab") hide
        (effects (font (size 0.7 0.7) (thickness 0.15)) (justify left bottom))
    )
    (fp_line (start -4.2 -1.55) (end -3.8 -1.55)
      (stroke (width 0.12) (type solid)) (layer "F.SilkS"))
    (fp_line (start -4 -1.75) (end -4 -1.35)
      (stroke (width 0.12) (type solid)) (layer "F.SilkS"))
    (fp_line (start -3.65 -2.15) (end 3.65 -2.15)
      (stroke (width 0.15) (type solid)) (layer "F.SilkS"))
    (fp_line (start -3.65 -1.6) (end -3.65 -2.15)
      (stroke (width 0.15) (type solid)) (layer "F.SilkS"))
    (fp_line (start -3.65 1.6) (end -3.65 2.15)
      (stroke (width 0.15) (type solid)) (layer "F.SilkS"))
    (fp_line (start -3.65 2.15) (end 3.65 2.15)
      (stroke (width 0.15) (type solid)) (layer "F.SilkS"))
    (fp_line (start 3.65 -2.15) (end 3.65 -1.6)
      (stroke (width 0.15) (type solid)) (layer "F.SilkS"))
    (fp_line (start 3.65 2.15) (end 3.65 1.6)
      (stroke (width 0.15) (type solid)) (layer "F.SilkS"))
    (fp_rect (start -4.3 -2.5) (end 4.3 2.5)
      (stroke (width 0.05) (type solid)) (fill none) (layer "F.CrtYd"))
    (fp_rect (start -3.65 -2.15) (end 3.65 2.15)
      (stroke (width 0.15) (type solid)) (fill none) (layer "F.Fab"))
    (pad "1" smd rect (at -3.1 0 180) (size 2.31 2.52) (layers "F.Cu" "F.Paste" "F.Mask")
      (net 147 "1V0_SYS") (pintype "passive"))
    (pad "2" smd rect (at 3.1 0 180) (size 2.31 2.52) (layers "F.Cu" "F.Paste" "F.Mask")
      (net 9 "GND") (pintype "passive"))
  )

  (footprint "data-center-rdimm-ddr4-tester-footprints:C_0603_1608Metric" (layer "F.Cu")
    (at 115.836328 77.560008 180)
    (descr "Capacitor SMD 0603")
    (tags "capacitor 0603")
    (property "Author" "Antmicro")
    (property "Dielectric" "")
    (property "License" "Apache-2.0")
    (property "MPN" "06031C103JAT2A")
    (property "Manufacturer" "AVX")
    (property "Sheetfile" "supply.kicad_sch")
    (property "Sheetname" "Supply")
    (property "Val" "10n")
    (property "Voltage" "")
    (property "ki_description" " ")
    (attr smd)
    (fp_text reference "C109" (at 1.486328 8.600008 180) (layer "F.SilkS")
        (effects (font (size 0.7 0.7) (thickness 0.15)) (justify left bottom))
    )
    (fp_text value "C_10n_0603" (at 0 1.6 180) (layer "F.Fab") hide
        (effects (font (size 0.7 0.7) (thickness 0.15)) (justify left bottom))
    )
    (fp_text user "${REFERENCE}" (at -1.682 3.895 180) (layer "F.Fab") hide
        (effects (font (size 0.7 0.7) (thickness 0.15)) (justify left bottom))
    )
    (fp_text user "Author: Antmicro" (at -1.682 4.894 180) (layer "F.Fab") hide
        (effects (font (size 0.7 0.7) (thickness 0.15)) (justify left bottom))
    )
    (fp_text user "License: Apache-2.0" (at -1.682 5.895 180) (layer "F.Fab") hide
        (effects (font (size 0.7 0.7) (thickness 0.15)) (justify left bottom))
    )
    (fp_line (start -0.3 -0.3) (end 0.3 -0.3)
      (stroke (width 0.15) (type solid)) (layer "F.SilkS"))
    (fp_line (start -0.3 0.3) (end 0.3 0.3)
      (stroke (width 0.15) (type solid)) (layer "F.SilkS"))
    (fp_rect (start -1.24 -0.7) (end 1.24 0.7)
      (stroke (width 0.05) (type solid)) (fill none) (layer "F.CrtYd"))
    (fp_rect (start -0.8 -0.4) (end 0.8 0.4)
      (stroke (width 0.15) (type solid)) (fill none) (layer "F.Fab"))
    (pad "1" smd roundrect (at -0.7 0 180) (size 0.6 0.8) (layers "F.Cu" "F.Paste" "F.Mask") (roundrect_rratio 0.2)
      (net 77 "VDDQ") (pintype "passive"))
    (pad "2" smd roundrect (at 0.7 0 180) (size 0.6 0.8) (layers "F.Cu" "F.Paste" "F.Mask") (roundrect_rratio 0.2)
      (net 9 "GND") (pintype "passive"))
  )

  (footprint "data-center-rdimm-ddr4-tester-footprints:Testpoint_smd_1mm" (layer "F.Cu")
    (at 252.586328 63.610808)
    (property "Author" "Antmicro")
    (property "License" "Apache-2.0")
    (property "MPN" "")
    (property "Manufacturer" "")
    (property "Sheetfile" "DDR4.kicad_sch")
    (property "Sheetname" "DDR4")
    (property "ki_description" "Test Point 1mm")
    (attr exclude_from_pos_files)
    (fp_text reference "TP10" (at 0.463672 0.339192) (layer "F.SilkS")
        (effects (font (size 0.7 0.7) (thickness 0.15)) (justify left bottom))
    )
    (fp_text value "TP_1mm_SMD" (at 0 1.4) (layer "F.Fab") hide
        (effects (font (size 0.7 0.7) (thickness 0.15)) (justify left bottom))
    )
    (fp_text user "License: Apache-2.0" (at -0.5 5.2) (layer "F.Fab") hide
        (effects (font (size 0.7 0.7) (thickness 0.15)) (justify left bottom))
    )
    (fp_text user "${REFERENCE}" (at -0.5 2.8) (layer "F.Fab") hide
        (effects (font (size 0.7 0.7) (thickness 0.15)) (justify left bottom))
    )
    (fp_text user "Author: Antmicro" (at -0.5 4) (layer "F.Fab") hide
        (effects (font (size 0.7 0.7) (thickness 0.15)) (justify left bottom))
    )
    (pad "1" smd circle (at 0 0) (size 1 1) (layers "F.Cu" "F.Mask")
      (net 308 "NC") (pinfunction "1") (pintype "passive"))
  )

  (footprint "data-center-rdimm-ddr4-tester-footprints:SOT-723" (layer "F.Cu")
    (at 148.85 127.55 90)
    (property "Author" "Antmicro")
    (property "License" "Apache-2.0")
    (property "MPN" "TPD2E009DRTR")
    (property "Manufacturer" "Texas Instruments")
    (property "Sheetfile" "interfaces.kicad_sch")
    (property "Sheetname" "Interfaces")
    (property "ki_description" "2-Channel ESD Solution for High-Speed (6-Gbps) Differential Interface")
    (attr smd)
    (fp_text reference "D3" (at 1.385 -0.84 180) (layer "F.SilkS")
        (effects (font (size 0.7 0.7) (thickness 0.15)) (justify left bottom))
    )
    (fp_text value "TPD2E009_SOT-9X3" (at 0 1.7 90) (layer "F.Fab") hide
        (effects (font (size 0.7 0.7) (thickness 0.15)) (justify left bottom))
    )
    (fp_text user "${REFERENCE}" (at -0.83 4 90) (layer "F.Fab") hide
        (effects (font (size 0.7 0.7) (thickness 0.15)) (justify left bottom))
    )
    (fp_text user "License: Apache-2.0" (at -0.83 6.4 90) (layer "F.Fab") hide
        (effects (font (size 0.7 0.7) (thickness 0.15)) (justify left bottom))
    )
    (fp_text user "Author: Antmicro" (at -0.83 5.2 90) (layer "F.Fab") hide
        (effects (font (size 0.7 0.7) (thickness 0.15)) (justify left bottom))
    )
    (fp_line (start -0.43 -0.1375) (end -0.43 0.1375)
      (stroke (width 0.15) (type solid)) (layer "F.SilkS"))
    (fp_line (start 0.43 -0.63) (end -0.2175 -0.63)
      (stroke (width 0.15) (type solid)) (layer "F.SilkS"))
    (fp_line (start 0.43 -0.23) (end 0.43 -0.63)
      (stroke (width 0.15) (type solid)) (layer "F.SilkS"))
    (fp_line (start 0.43 0.23) (end 0.43 0.63)
      (stroke (width 0.15) (type solid)) (layer "F.SilkS"))
    (fp_line (start 0.43 0.63) (end -0.22 0.63)
      (stroke (width 0.15) (type solid)) (layer "F.SilkS"))
    (fp_rect (start -0.83 -0.83) (end 0.83 0.83)
      (stroke (width 0.05) (type solid)) (fill none) (layer "F.CrtYd"))
    (fp_line (start -0.09 -0.53) (end -0.43 -0.19)
      (stroke (width 0.15) (type solid)) (layer "F.Fab"))
    (fp_line (start 0.424 -0.528) (end 0.424 0.524)
      (stroke (width 0.15) (type solid)) (layer "F.Fab"))
    (fp_line (start 0.424 0.524) (end -0.424 0.524)
      (stroke (width 0.15) (type solid)) (layer "F.Fab"))
    (fp_rect (start 0.424 0.524) (end -0.43 -0.528)
      (stroke (width 0.15) (type solid)) (fill none) (layer "F.Fab"))
    (pad "1" smd rect (at -0.501 -0.401) (size 0.3 0.4) (layers "F.Cu" "F.Paste" "F.Mask")
      (net 11 "DBG_USB_N") (pinfunction "1") (pintype "passive"))
    (pad "2" smd rect (at -0.501 0.399) (size 0.3 0.4) (layers "F.Cu" "F.Paste" "F.Mask")
      (net 10 "DBG_USB_P") (pinfunction "2") (pintype "passive"))
    (pad "3" smd rect (at 0.499 -0.001) (size 0.3 0.4) (layers "F.Cu" "F.Paste" "F.Mask")
      (net 9 "GND") (pinfunction "3") (pintype "passive"))
  )

  (footprint "data-center-rdimm-ddr4-tester-footprints:C_0603_1608Metric" (layer "F.Cu")
    (at 125.686328 85.826674)
    (descr "Capacitor SMD 0603")
    (tags "capacitor 0603")
    (property "Author" "Antmicro")
    (property "Dielectric" "")
    (property "License" "Apache-2.0")
    (property "MPN" "06031C103JAT2A")
    (property "Manufacturer" "AVX")
    (property "Sheetfile" "supply.kicad_sch")
    (property "Sheetname" "Supply")
    (property "Val" "10n")
    (property "Voltage" "")
    (property "ki_description" " ")
    (attr smd)
    (fp_text reference "C113" (at -1.386328 -4.426674) (layer "F.SilkS")
        (effects (font (size 0.7 0.7) (thickness 0.15)) (justify left bottom))
    )
    (fp_text value "C_10n_0603" (at 0 1.6) (layer "F.Fab") hide
        (effects (font (size 0.7 0.7) (thickness 0.15)) (justify left bottom))
    )
    (fp_text user "Author: Antmicro" (at -1.682 4.894) (layer "F.Fab") hide
        (effects (font (size 0.7 0.7) (thickness 0.15)) (justify left bottom))
    )
    (fp_text user "License: Apache-2.0" (at -1.682 5.895) (layer "F.Fab") hide
        (effects (font (size 0.7 0.7) (thickness 0.15)) (justify left bottom))
    )
    (fp_text user "${REFERENCE}" (at -1.682 3.895) (layer "F.Fab") hide
        (effects (font (size 0.7 0.7) (thickness 0.15)) (justify left bottom))
    )
    (fp_line (start -0.3 -0.3) (end 0.3 -0.3)
      (stroke (width 0.15) (type solid)) (layer "F.SilkS"))
    (fp_line (start -0.3 0.3) (end 0.3 0.3)
      (stroke (width 0.15) (type solid)) (layer "F.SilkS"))
    (fp_rect (start -1.24 -0.7) (end 1.24 0.7)
      (stroke (width 0.05) (type solid)) (fill none) (layer "F.CrtYd"))
    (fp_rect (start -0.8 -0.4) (end 0.8 0.4)
      (stroke (width 0.15) (type solid)) (fill none) (layer "F.Fab"))
    (pad "1" smd roundrect (at -0.7 0) (size 0.6 0.8) (layers "F.Cu" "F.Paste" "F.Mask") (roundrect_rratio 0.2)
      (net 184 "VPP") (pintype "passive"))
    (pad "2" smd roundrect (at 0.7 0) (size 0.6 0.8) (layers "F.Cu" "F.Paste" "F.Mask") (roundrect_rratio 0.2)
      (net 9 "GND") (pintype "passive"))
  )

  (footprint "data-center-rdimm-ddr4-tester-footprints:KEMET_A" (layer "F.Cu")
    (at 168.07 93.97 90)
    (descr "Capacitor SMD KEMET_A")
    (tags "capacitor SMD KEMET_A")
    (property "Author" "Antmicro")
    (property "Dielectric" "")
    (property "License" "Apache-2.0")
    (property "MPN" "298D107X06R3A2T")
    (property "Manufacturer" "Vishay")
    (property "Sheetfile" "fpga-power.kicad_sch")
    (property "Sheetname" "FPGA power")
    (property "Val" "100u")
    (property "Voltage" "")
    (property "ki_description" " ")
    (attr smd)
    (fp_text reference "C20" (at 1.81 -0.38 90) (layer "F.SilkS")
        (effects (font (size 0.7 0.7) (thickness 0.15)) (justify left bottom))
    )
    (fp_text value "C_100u_KEMET_A" (at 0 2 90) (layer "F.Fab") hide
        (effects (font (size 0.7 0.7) (thickness 0.15)) (justify left bottom))
    )
    (fp_text user "License: Apache-2.0" (at -2.1 5.198 90) (layer "F.Fab") hide
        (effects (font (size 0.7 0.7) (thickness 0.15)) (justify left bottom))
    )
    (fp_text user "Author: Antmicro" (at -2.1 6.198 90) (layer "F.Fab") hide
        (effects (font (size 0.7 0.7) (thickness 0.15)) (justify left bottom))
    )
    (fp_text user "${REFERENCE}" (at -2.1 4.198 90) (layer "F.Fab") hide
        (effects (font (size 0.7 0.7) (thickness 0.15)) (justify left bottom))
    )
    (fp_line (start -1.925 -0.825) (end -1.625 -0.825)
      (stroke (width 0.12) (type solid)) (layer "F.SilkS"))
    (fp_line (start -1.775 -0.975) (end -1.775 -0.675)
      (stroke (width 0.12) (type solid)) (layer "F.SilkS"))
    (fp_line (start -1.5 -0.85) (end -1.2 -0.85)
      (stroke (width 0.12) (type solid)) (layer "F.SilkS"))
    (fp_line (start -1.5 -0.7) (end -1.5 -0.85)
      (stroke (width 0.12) (type solid)) (layer "F.SilkS"))
    (fp_line (start -1.5 0.7) (end -1.5 0.85)
      (stroke (width 0.12) (type solid)) (layer "F.SilkS"))
    (fp_line (start -1.5 0.85) (end -1.2 0.85)
      (stroke (width 0.12) (type solid)) (layer "F.SilkS"))
    (fp_line (start 1.5 -0.85) (end 1.2 -0.85)
      (stroke (width 0.12) (type solid)) (layer "F.SilkS"))
    (fp_line (start 1.5 -0.7) (end 1.5 -0.85)
      (stroke (width 0.12) (type solid)) (layer "F.SilkS"))
    (fp_line (start 1.5 0.7) (end 1.5 0.85)
      (stroke (width 0.12) (type solid)) (layer "F.SilkS"))
    (fp_line (start 1.5 0.85) (end 1.2 0.85)
      (stroke (width 0.12) (type solid)) (layer "F.SilkS"))
    (fp_rect (start -1.9 -1.05) (end 1.9 1.05)
      (stroke (width 0.05) (type solid)) (fill none) (layer "F.CrtYd"))
    (fp_rect (start -1.601 -0.802) (end 1.6 0.8)
      (stroke (width 0.1) (type solid)) (fill none) (layer "F.Fab"))
    (pad "1" smd rect (at -1.2 0 90) (size 1.2 1.2) (layers "F.Cu" "F.Paste" "F.Mask")
      (net 147 "1V0_SYS") (pintype "passive"))
    (pad "2" smd rect (at 1.2 0 90) (size 1.2 1.2) (layers "F.Cu" "F.Paste" "F.Mask")
      (net 9 "GND") (pintype "passive"))
  )

  (footprint "data-center-rdimm-ddr4-tester-footprints:KEMET_D" (layer "F.Cu")
    (at 166.7 104.4 -90)
    (descr "Capacitor SMD KEMET_D")
    (tags "capacitor SMD KEMET_D")
    (property "Author" "Antmicro")
    (property "Dielectric" "")
    (property "License" "Apache-2.0")
    (property "MPN" "T520D337M006ATE045")
    (property "Manufacturer" "KEMET")
    (property "Sheetfile" "fpga-power.kicad_sch")
    (property "Sheetname" "FPGA power")
    (property "Val" "330u")
    (property "Voltage" "")
    (property "ki_description" " ")
    (attr smd)
    (fp_text reference "C8" (at 3.785 -3.07 -90) (layer "F.SilkS")
        (effects (font (size 0.7 0.7) (thickness 0.15)) (justify left bottom))
    )
    (fp_text value "C_330u_KEMET_D" (at 0 3.6 -90) (layer "F.Fab") hide
        (effects (font (size 0.7 0.7) (thickness 0.15)) (justify left bottom))
    )
    (fp_text user "License: Apache-2.0" (at -4.5 6.6 -90) (layer "F.Fab") hide
        (effects (font (size 0.7 0.7) (thickness 0.15)) (justify left bottom))
    )
    (fp_text user "Author: Antmicro" (at -4.5 7.6 -90) (layer "F.Fab") hide
        (effects (font (size 0.7 0.7) (thickness 0.15)) (justify left bottom))
    )
    (fp_text user "${REFERENCE}" (at -4.5 5.6 -90) (layer "F.Fab") hide
        (effects (font (size 0.7 0.7) (thickness 0.15)) (justify left bottom))
    )
    (fp_line (start -4.2 -1.55) (end -3.8 -1.55)
      (stroke (width 0.12) (type solid)) (layer "F.SilkS"))
    (fp_line (start -4 -1.75) (end -4 -1.35)
      (stroke (width 0.12) (type solid)) (layer "F.SilkS"))
    (fp_line (start -3.65 -2.15) (end 3.65 -2.15)
      (stroke (width 0.15) (type solid)) (layer "F.SilkS"))
    (fp_line (start -3.65 -1.6) (end -3.65 -2.15)
      (stroke (width 0.15) (type solid)) (layer "F.SilkS"))
    (fp_line (start -3.65 1.6) (end -3.65 2.15)
      (stroke (width 0.15) (type solid)) (layer "F.SilkS"))
    (fp_line (start -3.65 2.15) (end 3.65 2.15)
      (stroke (width 0.15) (type solid)) (layer "F.SilkS"))
    (fp_line (start 3.65 -2.15) (end 3.65 -1.6)
      (stroke (width 0.15) (type solid)) (layer "F.SilkS"))
    (fp_line (start 3.65 2.15) (end 3.65 1.6)
      (stroke (width 0.15) (type solid)) (layer "F.SilkS"))
    (fp_line (start -4.3 1.5) (end -4.3 -1.5)
      (stroke (width 0.05) (type solid)) (layer "F.CrtYd"))
    (fp_line (start -3.8 -2.4) (end -3.8 -1.5)
      (stroke (width 0.05) (type solid)) (layer "F.CrtYd"))
    (fp_line (start -3.8 -2.4) (end 3.8 -2.4)
      (stroke (width 0.05) (type solid)) (layer "F.CrtYd"))
    (fp_line (start -3.8 -1.5) (end -4.3 -1.5)
      (stroke (width 0.05) (type solid)) (layer "F.CrtYd"))
    (fp_line (start -3.8 1.5) (end -4.3 1.5)
      (stroke (width 0.05) (type solid)) (layer "F.CrtYd"))
    (fp_line (start -3.8 2.4) (end -3.8 1.5)
      (stroke (width 0.05) (type solid)) (layer "F.CrtYd"))
    (fp_line (start 3.8 -2.4) (end 3.8 -1.5)
      (stroke (width 0.05) (type solid)) (layer "F.CrtYd"))
    (fp_line (start 3.8 -1.5) (end 4.3 -1.5)
      (stroke (width 0.05) (type solid)) (layer "F.CrtYd"))
    (fp_line (start 3.8 1.5) (end 3.8 2.4)
      (stroke (width 0.05) (type solid)) (layer "F.CrtYd"))
    (fp_line (start 3.8 2.4) (end -3.8 2.4)
      (stroke (width 0.05) (type solid)) (layer "F.CrtYd"))
    (fp_line (start 4.3 -1.5) (end 4.3 1.5)
      (stroke (width 0.05) (type solid)) (layer "F.CrtYd"))
    (fp_line (start 4.3 1.5) (end 3.8 1.5)
      (stroke (width 0.05) (type solid)) (layer "F.CrtYd"))
    (fp_rect (start -3.65 -2.15) (end 3.65 2.15)
      (stroke (width 0.15) (type solid)) (fill none) (layer "F.Fab"))
    (pad "1" smd rect (at -3.1 0 270) (size 2.31 2.52) (layers "F.Cu" "F.Paste" "F.Mask")
      (net 147 "1V0_SYS") (pintype "passive"))
    (pad "2" smd rect (at 3.1 0 270) (size 2.31 2.52) (layers "F.Cu" "F.Paste" "F.Mask")
      (net 9 "GND") (pintype "passive"))
  )

  (footprint "data-center-rdimm-ddr4-tester-footprints:C_0603_1608Metric" (layer "F.Cu")
    (at 115.786328 82.060008 180)
    (descr "Capacitor SMD 0603")
    (tags "capacitor 0603")
    (property "Author" "Antmicro")
    (property "Dielectric" "")
    (property "License" "Apache-2.0")
    (property "MPN" "06031C103JAT2A")
    (property "Manufacturer" "AVX")
    (property "Sheetfile" "supply.kicad_sch")
    (property "Sheetname" "Supply")
    (property "Val" "10n")
    (property "Voltage" "")
    (property "ki_description" " ")
    (attr smd)
    (fp_text reference "C107" (at 1.446328 10.230008 180) (layer "F.SilkS")
        (effects (font (size 0.7 0.7) (thickness 0.15)) (justify left bottom))
    )
    (fp_text value "C_10n_0603" (at 0 1.6 180) (layer "F.Fab") hide
        (effects (font (size 0.7 0.7) (thickness 0.15)) (justify left bottom))
    )
    (fp_text user "Author: Antmicro" (at -1.682 4.894 180) (layer "F.Fab") hide
        (effects (font (size 0.7 0.7) (thickness 0.15)) (justify left bottom))
    )
    (fp_text user "License: Apache-2.0" (at -1.682 5.895 180) (layer "F.Fab") hide
        (effects (font (size 0.7 0.7) (thickness 0.15)) (justify left bottom))
    )
    (fp_text user "${REFERENCE}" (at -1.682 3.895 180) (layer "F.Fab") hide
        (effects (font (size 0.7 0.7) (thickness 0.15)) (justify left bottom))
    )
    (fp_line (start -0.3 -0.3) (end 0.3 -0.3)
      (stroke (width 0.15) (type solid)) (layer "F.SilkS"))
    (fp_line (start -0.3 0.3) (end 0.3 0.3)
      (stroke (width 0.15) (type solid)) (layer "F.SilkS"))
    (fp_rect (start -1.24 -0.7) (end 1.24 0.7)
      (stroke (width 0.05) (type solid)) (fill none) (layer "F.CrtYd"))
    (fp_rect (start -0.8 -0.4) (end 0.8 0.4)
      (stroke (width 0.15) (type solid)) (fill none) (layer "F.Fab"))
    (pad "1" smd roundrect (at -0.7 0 180) (size 0.6 0.8) (layers "F.Cu" "F.Paste" "F.Mask") (roundrect_rratio 0.2)
      (net 77 "VDDQ") (pintype "passive"))
    (pad "2" smd roundrect (at 0.7 0 180) (size 0.6 0.8) (layers "F.Cu" "F.Paste" "F.Mask") (roundrect_rratio 0.2)
      (net 9 "GND") (pintype "passive"))
  )

  (footprint "data-center-rdimm-ddr4-tester-footprints:C_0603_1608Metric" (layer "F.Cu")
    (at 155.803 75.756)
    (descr "Capacitor SMD 0603")
    (tags "capacitor 0603")
    (property "Author" "Antmicro")
    (property "Dielectric" "")
    (property "License" "Apache-2.0")
    (property "MPN" "GRM188R60J476ME15D")
    (property "Manufacturer" "Murata")
    (property "Sheetfile" "hyperram.kicad_sch")
    (property "Sheetname" "HyperRAM")
    (property "Val" "47u")
    (property "Voltage" "")
    (property "ki_description" " ")
    (attr smd)
    (fp_text reference "C102" (at -1.313 -0.826) (layer "F.SilkS")
        (effects (font (size 0.7 0.7) (thickness 0.15)) (justify left bottom))
    )
    (fp_text value "C_47u_0603" (at 0 1.6) (layer "F.Fab") hide
        (effects (font (size 0.7 0.7) (thickness 0.15)) (justify left bottom))
    )
    (fp_text user "Author: Antmicro" (at -1.682 4.894) (layer "F.Fab") hide
        (effects (font (size 0.7 0.7) (thickness 0.15)) (justify left bottom))
    )
    (fp_text user "${REFERENCE}" (at -1.682 3.895) (layer "F.Fab") hide
        (effects (font (size 0.7 0.7) (thickness 0.15)) (justify left bottom))
    )
    (fp_text user "License: Apache-2.0" (at -1.682 5.895) (layer "F.Fab") hide
        (effects (font (size 0.7 0.7) (thickness 0.15)) (justify left bottom))
    )
    (fp_line (start -0.3 -0.3) (end 0.3 -0.3)
      (stroke (width 0.15) (type solid)) (layer "F.SilkS"))
    (fp_line (start -0.3 0.3) (end 0.3 0.3)
      (stroke (width 0.15) (type solid)) (layer "F.SilkS"))
    (fp_rect (start -1.24 -0.7) (end 1.24 0.7)
      (stroke (width 0.05) (type solid)) (fill none) (layer "F.CrtYd"))
    (fp_rect (start -0.8 -0.4) (end 0.8 0.4)
      (stroke (width 0.15) (type solid)) (fill none) (layer "F.Fab"))
    (pad "1" smd roundrect (at -0.7 0) (size 0.6 0.8) (layers "F.Cu" "F.Paste" "F.Mask") (roundrect_rratio 0.2)
      (net 143 "3V3_SYS") (pintype "passive"))
    (pad "2" smd roundrect (at 0.7 0) (size 0.6 0.8) (layers "F.Cu" "F.Paste" "F.Mask") (roundrect_rratio 0.2)
      (net 9 "GND") (pintype "passive"))
  )

  (footprint "data-center-rdimm-ddr4-tester-footprints:R_0402_1005Metric" (layer "F.Cu")
    (at 152.6026 75.502 -90)
    (descr "Resistor SMD 0402")
    (tags "resistor SMD 0402")
    (property "Author" "Antmicro")
    (property "License" "Apache-2.0")
    (property "MPN" "CR0402-FX-1002GLF")
    (property "Manufacturer" "Bourns")
    (property "Sheetfile" "hyperram.kicad_sch")
    (property "Sheetname" "HyperRAM")
    (property "Tolerance" "1%")
    (property "Val" "10k")
    (property "ki_description" "10k resistor in 0402 package with 1% tolerance")
    (attr smd)
    (fp_text reference "R61" (at -0.832 -0.3574 -90) (layer "F.SilkS")
        (effects (font (size 0.7 0.7) (thickness 0.15)) (justify left bottom))
    )
    (fp_text value "R_10k_0402" (at 0 1.4 -90) (layer "F.Fab") hide
        (effects (font (size 0.7 0.7) (thickness 0.15)) (justify left bottom))
    )
    (fp_text user "Author: Antmicro" (at -0.95 4.169 -90) (layer "F.Fab") hide
        (effects (font (size 0.7 0.7) (thickness 0.15)) (justify left bottom))
    )
    (fp_text user "${REFERENCE}" (at -0.95 3.168 -90) (layer "F.Fab") hide
        (effects (font (size 0.7 0.7) (thickness 0.15)) (justify left bottom))
    )
    (fp_text user "License: Apache-2.0" (at -0.95 5.169 -90) (layer "F.Fab") hide
        (effects (font (size 0.7 0.7) (thickness 0.15)) (justify left bottom))
    )
    (fp_rect (start -0.93 -0.47) (end 0.93 0.47)
      (stroke (width 0.05) (type solid)) (fill none) (layer "F.CrtYd"))
    (fp_rect (start -0.5 -0.25) (end 0.5 0.25)
      (stroke (width 0.15) (type solid)) (fill none) (layer "F.Fab"))
    (pad "1" smd roundrect (at -0.485 0 270) (size 0.59 0.64) (layers "F.Cu" "F.Paste" "F.Mask") (roundrect_rratio 0.25)
      (net 143 "3V3_SYS") (pintype "passive"))
    (pad "2" smd roundrect (at 0.485 0 270) (size 0.59 0.64) (layers "F.Cu" "F.Paste" "F.Mask") (roundrect_rratio 0.25)
      (net 155 "HR_CS") (pintype "passive"))
  )

  (footprint "data-center-rdimm-ddr4-tester-footprints:FBGA-24-1_6x8mm_Layout5x5_P1mm" (layer "F.Cu")
    (at 155.496328 80.577157 90)
    (property "Author" "Antmicro")
    (property "License" "Apache-2.0")
    (property "MPN" "S27KL0641DABHI023")
    (property "Manufacturer" "Cypress Semiconductor")
    (property "Sheetfile" "hyperram.kicad_sch")
    (property "Sheetname" "HyperRAM")
    (attr smd)
    (fp_text reference "U11" (at 3.317157 -4.376328 180) (layer "F.SilkS")
        (effects (font (size 0.7 0.7) (thickness 0.15)) (justify left bottom))
    )
    (fp_text value "S27KL0641DABHI023" (at 0.1 5.3 90) (layer "F.Fab") hide
        (effects (font (size 0.7 0.7) (thickness 0.15)) (justify left bottom))
    )
    (fp_text user "${REFERENCE}" (at -3.25 8.359 90) (layer "F.Fab") hide
        (effects (font (size 0.7 0.7) (thickness 0.15)) (justify left bottom))
    )
    (fp_text user "Author: Antmicro" (at -3.25 9.559 90) (layer "F.Fab") hide
        (effects (font (size 0.7 0.7) (thickness 0.15)) (justify left bottom))
    )
    (fp_text user "License: Apache-2.0" (at -3.25 10.759 90) (layer "F.Fab") hide
        (effects (font (size 0.7 0.7) (thickness 0.15)) (justify left bottom))
    )
    (fp_line (start -3.121 -3) (end -3.121 -2.121)
      (stroke (width 0.15) (type solid)) (layer "F.SilkS"))
    (fp_line (start -3.121 4.12) (end -3.121 2.12)
      (stroke (width 0.15) (type solid)) (layer "F.SilkS"))
    (fp_line (start -2 -4.121) (end -3.121 -3)
      (stroke (width 0.15) (type solid)) (layer "F.SilkS"))
    (fp_line (start -1.621 -4.121) (end -2 -4.121)
      (stroke (width 0.15) (type solid)) (layer "F.SilkS"))
    (fp_line (start -1.621 4.12) (end -3.121 4.12)
      (stroke (width 0.15) (type solid)) (layer "F.SilkS"))
    (fp_line (start 1.62 -4.121) (end 3.12 -4.121)
      (stroke (width 0.15) (type solid)) (layer "F.SilkS"))
    (fp_line (start 1.62 -4.121) (end 3.12 -4.121)
      (stroke (width 0.15) (type solid)) (layer "F.SilkS"))
    (fp_line (start 1.62 -4.121) (end 3.12 -4.121)
      (stroke (width 0.15) (type solid)) (layer "F.SilkS"))
    (fp_line (start 1.62 4.12) (end 3.12 4.12)
      (stroke (width 0.15) (type solid)) (layer "F.SilkS"))
    (fp_line (start 3.12 -4.121) (end 3.12 -2.121)
      (stroke (width 0.15) (type solid)) (layer "F.SilkS"))
    (fp_line (start 3.12 -4.121) (end 3.12 -2.121)
      (stroke (width 0.15) (type solid)) (layer "F.SilkS"))
    (fp_line (start 3.12 -4.121) (end 3.12 -2.121)
      (stroke (width 0.15) (type solid)) (layer "F.SilkS"))
    (fp_line (start 3.12 4.12) (end 3.12 2.12)
      (stroke (width 0.15) (type solid)) (layer "F.SilkS"))
    (fp_circle (center -3.6 -3.9) (end -3.5 -3.9)
      (stroke (width 0.15) (type solid)) (fill solid) (layer "F.SilkS"))
    (fp_line (start -3.25 -4.25) (end 3.24 -4.25)
      (stroke (width 0.05) (type solid)) (layer "F.CrtYd"))
    (fp_line (start -3.25 4.24) (end -3.25 -4.25)
      (stroke (width 0.05) (type solid)) (layer "F.CrtYd"))
    (fp_line (start 3.24 -4.25) (end 3.24 4.24)
      (stroke (width 0.05) (type solid)) (layer "F.CrtYd"))
    (fp_line (start 3.24 4.24) (end -3.25 4.24)
      (stroke (width 0.05) (type solid)) (layer "F.CrtYd"))
    (fp_line (start -3 -3) (end -3 3.999)
      (stroke (width 0.15) (type solid)) (layer "F.Fab"))
    (fp_line (start -3 3.999) (end 2.999 3.999)
      (stroke (width 0.15) (type solid)) (layer "F.Fab"))
    (fp_line (start -2 -4) (end -3 -3)
      (stroke (width 0.15) (type solid)) (layer "F.Fab"))
    (fp_line (start 2.999 -4) (end -2 -4)
      (stroke (width 0.15) (type solid)) (layer "F.Fab"))
    (fp_line (start 2.999 3.999) (end 2.999 -4)
      (stroke (width 0.15) (type solid)) (layer "F.Fab"))
    (pad "A2" smd circle (at -1 -2 90) (size 0.4 0.4) (layers "F.Cu" "F.Paste" "F.Mask")
      (net 696 "unconnected-(U11-NC-PadA2)") (pinfunction "NC") (pintype "no_connect"))
    (pad "A3" smd circle (at 0 -2 90) (size 0.4 0.4) (layers "F.Cu" "F.Paste" "F.Mask")
      (net 155 "HR_CS") (pinfunction "~{CS}") (pintype "input"))
    (pad "A4" smd circle (at 0.999 -2 90) (size 0.4 0.4) (layers "F.Cu" "F.Paste" "F.Mask")
      (net 154 "HR_RST") (pinfunction "~{RESET}") (pintype "input"))
    (pad "A5" smd circle (at 1.999 -2 90) (size 0.4 0.4) (layers "F.Cu" "F.Paste" "F.Mask")
      (net 697 "unconnected-(U11-NC-PadA5)") (pinfunction "NC") (pintype "no_connect"))
    (pad "B1" smd circle (at -2 -1 90) (size 0.4 0.4) (layers "F.Cu" "F.Paste" "F.Mask")
      (net 159 "HR_CKN") (pinfunction "CK-") (pintype "input"))
    (pad "B2" smd circle (at -1 -1 90) (size 0.4 0.4) (layers "F.Cu" "F.Paste" "F.Mask")
      (net 164 "HR_CKP") (pinfunction "CK+") (pintype "input"))
    (pad "B3" smd circle (at 0 -1 90) (size 0.4 0.4) (layers "F.Cu" "F.Paste" "F.Mask")
      (net 9 "GND") (pinfunction "VSS") (pintype "power_in"))
    (pad "B4" smd circle (at 0.999 -1 90) (size 0.4 0.4) (layers "F.Cu" "F.Paste" "F.Mask")
      (net 143 "3V3_SYS") (pinfunction "VCC") (pintype "power_in"))
    (pad "B5" smd circle (at 1.999 -1 90) (size 0.4 0.4) (layers "F.Cu" "F.Paste" "F.Mask")
      (net 698 "unconnected-(U11-NC-PadB5)") (pinfunction "NC") (pintype "no_connect"))
    (pad "C1" smd circle (at -2 0 90) (size 0.4 0.4) (layers "F.Cu" "F.Paste" "F.Mask")
      (net 9 "GND") (pinfunction "VSSQ") (pintype "power_in"))
    (pad "C2" smd circle (at -1 0 90) (size 0.4 0.4) (layers "F.Cu" "F.Paste" "F.Mask")
      (net 699 "unconnected-(U11-NC-PadC2)") (pinfunction "NC") (pintype "no_connect"))
    (pad "C3" smd circle (at 0 0 90) (size 0.4 0.4) (layers "F.Cu" "F.Paste" "F.Mask")
      (net 158 "HR_RW") (pinfunction "RWDS") (pintype "bidirectional"))
    (pad "C4" smd circle (at 0.999 0 90) (size 0.4 0.4) (layers "F.Cu" "F.Paste" "F.Mask")
      (net 166 "HR_DQ2") (pinfunction "DQ2") (pintype "bidirectional"))
    (pad "C5" smd circle (at 1.999 0 90) (size 0.4 0.4) (layers "F.Cu" "F.Paste" "F.Mask")
      (net 700 "unconnected-(U11-NC-PadC5)") (pinfunction "NC") (pintype "no_connect"))
    (pad "D1" smd circle (at -2 0.999 90) (size 0.4 0.4) (layers "F.Cu" "F.Paste" "F.Mask")
      (net 143 "3V3_SYS") (pinfunction "VCCQ") (pintype "power_in"))
    (pad "D2" smd circle (at -1 0.999 90) (size 0.4 0.4) (layers "F.Cu" "F.Paste" "F.Mask")
      (net 156 "HR_DQ1") (pinfunction "DQ1") (pintype "bidirectional"))
    (pad "D3" smd circle (at 0 0.999 90) (size 0.4 0.4) (layers "F.Cu" "F.Paste" "F.Mask")
      (net 157 "HR_DQ0") (pinfunction "DQ0") (pintype "bidirectional"))
    (pad "D4" smd circle (at 0.999 0.999 90) (size 0.4 0.4) (layers "F.Cu" "F.Paste" "F.Mask")
      (net 165 "HR_DQ3") (pinfunction "DQ3") (pintype "bidirectional"))
    (pad "D5" smd circle (at 1.999 0.999 90) (size 0.4 0.4) (layers "F.Cu" "F.Paste" "F.Mask")
      (net 161 "HR_DQ4") (pinfunction "DQ4") (pintype "bidirectional"))
    (pad "E1" smd circle (at -2 1.999 90) (size 0.4 0.4) (layers "F.Cu" "F.Paste" "F.Mask")
      (net 162 "HR_DQ7") (pinfunction "DQ7") (pintype "bidirectional"))
    (pad "E2" smd circle (at -1 1.999 90) (size 0.4 0.4) (layers "F.Cu" "F.Paste" "F.Mask")
      (net 163 "HR_DQ6") (pinfunction "DQ6") (pintype "bidirectional"))
    (pad "E3" smd circle (at 0 1.999 90) (size 0.4 0.4) (layers "F.Cu" "F.Paste" "F.Mask")
      (net 160 "HR_DQ5") (pinfunction "DQ5") (pintype "bidirectional"))
    (pad "E4" smd circle (at 0.999 1.999 90) (size 0.4 0.4) (layers "F.Cu" "F.Paste" "F.Mask")
      (net 143 "3V3_SYS") (pinfunction "VCCQ") (pintype "passive"))
    (pad "E5" smd circle (at 1.999 1.999 90) (size 0.4 0.4) (layers "F.Cu" "F.Paste" "F.Mask")
      (net 9 "GND") (pinfunction "VSSQ") (pintype "passive"))
  )

  (footprint "data-center-rdimm-ddr4-tester-footprints:R_0402_1005Metric" (layer "F.Cu")
    (at 153.7202 75.502 -90)
    (descr "Resistor SMD 0402")
    (tags "resistor SMD 0402")
    (property "Author" "Antmicro")
    (property "License" "Apache-2.0")
    (property "MPN" "CR0402-FX-1002GLF")
    (property "Manufacturer" "Bourns")
    (property "Sheetfile" "hyperram.kicad_sch")
    (property "Sheetname" "HyperRAM")
    (property "Tolerance" "1%")
    (property "Val" "10k")
    (property "ki_description" "10k resistor in 0402 package with 1% tolerance")
    (attr smd)
    (fp_text reference "R56" (at -0.832 -0.3574 -90) (layer "F.SilkS")
        (effects (font (size 0.7 0.7) (thickness 0.15)) (justify left bottom))
    )
    (fp_text value "R_10k_0402" (at 0 1.4 -90) (layer "F.Fab") hide
        (effects (font (size 0.7 0.7) (thickness 0.15)) (justify left bottom))
    )
    (fp_text user "${REFERENCE}" (at -0.95 3.168 -90) (layer "F.Fab") hide
        (effects (font (size 0.7 0.7) (thickness 0.15)) (justify left bottom))
    )
    (fp_text user "License: Apache-2.0" (at -0.95 5.169 -90) (layer "F.Fab") hide
        (effects (font (size 0.7 0.7) (thickness 0.15)) (justify left bottom))
    )
    (fp_text user "Author: Antmicro" (at -0.95 4.169 -90) (layer "F.Fab") hide
        (effects (font (size 0.7 0.7) (thickness 0.15)) (justify left bottom))
    )
    (fp_rect (start -0.93 -0.47) (end 0.93 0.47)
      (stroke (width 0.05) (type solid)) (fill none) (layer "F.CrtYd"))
    (fp_rect (start -0.5 -0.25) (end 0.5 0.25)
      (stroke (width 0.15) (type solid)) (fill none) (layer "F.Fab"))
    (pad "1" smd roundrect (at -0.485 0 270) (size 0.59 0.64) (layers "F.Cu" "F.Paste" "F.Mask") (roundrect_rratio 0.25)
      (net 143 "3V3_SYS") (pintype "passive"))
    (pad "2" smd roundrect (at 0.485 0 270) (size 0.59 0.64) (layers "F.Cu" "F.Paste" "F.Mask") (roundrect_rratio 0.25)
      (net 154 "HR_RST") (pintype "passive"))
  )

  (footprint "data-center-rdimm-ddr4-tester-footprints:BGA-676_27x27mm_Layout26x26_P1X1mm" (layer "F.Cu")
    (at 183.635 90.06 180)
    (descr "FPGA XC7K160TFBG676")
    (tags "FPGA XC7K160TFBG676")
    (property "Author" "Antmicro")
    (property "License" "Apache-2.0")
    (property "MPN" "XC7K160T-FFG676")
    (property "Manufacturer" "AMD-Xilinx")
    (property "Sheetfile" "config-spi.kicad_sch")
    (property "Sheetname" "Config SPI flash")
    (property "ki_description" "Kintex®-7 Field Programmable Gate Array (FPGA) IC 300 4976640 65600 676-BBGA, FCBGA")
    (property "ki_keywords" "SMT, MICROCONTROLLER, IC, FPGA")
    (attr smd)
    (fp_text reference "U15" (at -10.675 -14.7 180) (layer "F.SilkS")
        (effects (font (size 0.7 0.7) (thickness 0.15)) (justify left bottom))
    )
    (fp_text value "XC7K160T-FFG676" (at 0 15.5 180) (layer "F.Fab")
        (effects (font (size 0.7 0.7) (thickness 0.15)) (justify left bottom))
    )
    (fp_text user "Author: Antmicro" (at -14.5 18.334 180) (layer "F.Fab") hide
        (effects (font (size 0.7 0.7) (thickness 0.15)) (justify left bottom))
    )
    (fp_text user "License: Apache-2.0" (at -14.5 19.534 180) (layer "F.Fab") hide
        (effects (font (size 0.7 0.7) (thickness 0.15)) (justify left bottom))
    )
    (fp_text user "${REFERENCE}" (at -14.5 17.134 180) (layer "F.Fab") hide
        (effects (font (size 0.7 0.7) (thickness 0.15)) (justify left bottom))
    )
    (fp_line (start -13.5 -13.5) (end -13.5 -6.75)
      (stroke (width 0.15) (type solid)) (layer "F.SilkS"))
    (fp_line (start -13.5 -13.5) (end -6.75 -13.5)
      (stroke (width 0.15) (type solid)) (layer "F.SilkS"))
    (fp_line (start -13.5 13.499) (end -13.5 6.749)
      (stroke (width 0.15) (type solid)) (layer "F.SilkS"))
    (fp_line (start -13.5 13.499) (end -6.75 13.499)
      (stroke (width 0.15) (type solid)) (layer "F.SilkS"))
    (fp_line (start 13.499 -13.5) (end 6.749 -13.5)
      (stroke (width 0.15) (type solid)) (layer "F.SilkS"))
    (fp_line (start 13.499 -13.5) (end 13.499 -6.75)
      (stroke (width 0.15) (type solid)) (layer "F.SilkS"))
    (fp_line (start 13.499 13.499) (end 6.749 13.499)
      (stroke (width 0.15) (type solid)) (layer "F.SilkS"))
    (fp_line (start 13.499 13.499) (end 13.499 6.749)
      (stroke (width 0.15) (type solid)) (layer "F.SilkS"))
    (fp_circle (center -14 -14) (end -13.95 -13.94)
      (stroke (width 0.15) (type solid)) (fill solid) (layer "F.SilkS"))
    (fp_rect (start -14.5 -14.5) (end 14.5 14.5)
      (stroke (width 0.05) (type solid)) (fill none) (layer "F.CrtYd"))
    (fp_rect (start -13.5 -13.5) (end 13.499 13.499)
      (stroke (width 0.15) (type solid)) (fill none) (layer "F.Fab"))
    (pad "A1" smd circle (at -12.5 -12.5 180) (size 0.5 0.5) (layers "F.Cu" "F.Paste" "F.Mask")
      (net 9 "GND") (pinfunction "GND") (pintype "power_in"))
    (pad "A2" smd circle (at -11.5 -12.5 180) (size 0.5 0.5) (layers "F.Cu" "F.Paste" "F.Mask")
      (net 9 "GND") (pinfunction "GND") (pintype "passive"))
    (pad "A3" smd circle (at -10.5 -12.5 180) (size 0.5 0.5) (layers "F.Cu" "F.Paste" "F.Mask")
      (net 418 "GTX_TX0_N") (pinfunction "MGTXTXN3_116") (pintype "bidirectional") (die_length 14.476))
    (pad "A4" smd circle (at -9.5 -12.5 180) (size 0.5 0.5) (layers "F.Cu" "F.Paste" "F.Mask")
      (net 411 "GTX_TX0_P") (pinfunction "MGTXTXP3_116") (pintype "bidirectional") (die_length 14.628))
    (pad "A5" smd circle (at -8.5 -12.5 180) (size 0.5 0.5) (layers "F.Cu" "F.Paste" "F.Mask")
      (net 9 "GND") (pinfunction "GND") (pintype "passive"))
    (pad "A6" smd circle (at -7.5 -12.5 180) (size 0.5 0.5) (layers "F.Cu" "F.Paste" "F.Mask")
      (net 9 "GND") (pinfunction "GND") (pintype "passive"))
    (pad "A7" smd circle (at -6.5 -12.5 180) (size 0.5 0.5) (layers "F.Cu" "F.Paste" "F.Mask")
      (net 9 "GND") (pinfunction "GND") (pintype "passive"))
    (pad "A8" smd circle (at -5.5 -12.5 180) (size 0.5 0.5) (layers "F.Cu" "F.Paste" "F.Mask")
      (net 120 "~{PERST}") (pinfunction "IO_L9N_T1_DQS_16") (pintype "bidirectional") (die_length 19.908))
    (pad "A9" smd circle (at -4.5 -12.5 180) (size 0.5 0.5) (layers "F.Cu" "F.Paste" "F.Mask")
      (net 711 "unconnected-(U15E-IO_L9P_T1_DQS_16-PadA9)") (pinfunction "IO_L9P_T1_DQS_16") (pintype "bidirectional+no_connect") (die_length 19.519))
    (pad "A10" smd circle (at -3.5 -12.5 180) (size 0.5 0.5) (layers "F.Cu" "F.Paste" "F.Mask")
      (net 62 "TMDS_D2_N") (pinfunction "IO_L22N_T3_16") (pintype "bidirectional") (die_length 20.762))
    (pad "A11" smd circle (at -2.5 -12.5 180) (size 0.5 0.5) (layers "F.Cu" "F.Paste" "F.Mask")
      (net 143 "3V3_SYS") (pinfunction "VCCO_16") (pintype "power_in"))
    (pad "A12" smd circle (at -1.5 -12.5 180) (size 0.5 0.5) (layers "F.Cu" "F.Paste" "F.Mask")
      (net 60 "TMDS_D1_N") (pinfunction "IO_L24N_T3_16") (pintype "bidirectional") (die_length 22.422))
    (pad "A13" smd circle (at -0.5 -12.5 180) (size 0.5 0.5) (layers "F.Cu" "F.Paste" "F.Mask")
      (net 59 "TMDS_D1_P") (pinfunction "IO_L24P_T3_16") (pintype "bidirectional") (die_length 22.76))
    (pad "A14" smd circle (at 0.499 -12.5 180) (size 0.5 0.5) (layers "F.Cu" "F.Paste" "F.Mask")
      (net 58 "TMDS_D0_N") (pinfunction "IO_L21N_T3_DQS_16") (pintype "bidirectional") (die_length 18.115))
    (pad "A15" smd circle (at 1.499 -12.5 180) (size 0.5 0.5) (layers "F.Cu" "F.Paste" "F.Mask")
      (net 56 "TMDS_CLK_N") (pinfunction "IO_L23N_T3_16") (pintype "bidirectional") (die_length 18.152))
    (pad "A16" smd circle (at 2.499 -12.5 180) (size 0.5 0.5) (layers "F.Cu" "F.Paste" "F.Mask")
      (net 9 "GND") (pinfunction "GND") (pintype "passive"))
    (pad "A17" smd circle (at 3.499 -12.5 180) (size 0.5 0.5) (layers "F.Cu" "F.Paste" "F.Mask")
      (net 406 "FMC_IO_3_N") (pinfunction "IO_L3N_T0_DQS_AD1N_15") (pintype "bidirectional") (die_length 18.146))
    (pad "A18" smd circle (at 4.499 -12.5 180) (size 0.5 0.5) (layers "F.Cu" "F.Paste" "F.Mask")
      (net 407 "FMC_IO_2_P") (pinfunction "IO_L2P_T0_AD8P_15") (pintype "bidirectional") (die_length 20.209))
    (pad "A19" smd circle (at 5.499 -12.5 180) (size 0.5 0.5) (layers "F.Cu" "F.Paste" "F.Mask")
      (net 416 "FMC_IO_2_N") (pinfunction "IO_L2N_T0_AD8N_15") (pintype "bidirectional") (die_length 19.837))
    (pad "A20" smd circle (at 6.499 -12.5 180) (size 0.5 0.5) (layers "F.Cu" "F.Paste" "F.Mask")
      (net 784 "HOT_SWAP_YELLOW") (pinfunction "IO_L8N_T1_D12_14") (pintype "bidirectional") (die_length 22.195))
    (pad "A21" smd circle (at 7.499 -12.5 180) (size 0.5 0.5) (layers "F.Cu" "F.Paste" "F.Mask")
      (net 143 "3V3_SYS") (pinfunction "VCCO_14") (pintype "power_in"))
    (pad "A22" smd circle (at 8.499 -12.5 180) (size 0.5 0.5) (layers "F.Cu" "F.Paste" "F.Mask")
      (net 22 "QSPI_DQ3") (pinfunction "IO_L2N_T0_D03_14") (pintype "bidirectional") (die_length 21.482))
    (pad "A23" smd circle (at 9.499 -12.5 180) (size 0.5 0.5) (layers "F.Cu" "F.Paste" "F.Mask")
      (net 141 "UART1_TX") (pinfunction "IO_L4P_T0_D04_14") (pintype "bidirectional") (die_length 21.833))
    (pad "A24" smd circle (at 10.499 -12.5 180) (size 0.5 0.5) (layers "F.Cu" "F.Paste" "F.Mask")
      (net 139 "UART1_RX") (pinfunction "IO_L4N_T0_D05_14") (pintype "bidirectional") (die_length 22.897))
    (pad "A25" smd circle (at 11.499 -12.5 180) (size 0.5 0.5) (layers "F.Cu" "F.Paste" "F.Mask")
      (net 20 "QSPI_DQ1") (pinfunction "IO_L1N_T0_D01_DIN_14") (pintype "bidirectional") (die_length 23.845))
    (pad "A26" smd circle (at 12.499 -12.5 180) (size 0.5 0.5) (layers "F.Cu" "F.Paste" "F.Mask")
      (net 9 "GND") (pinfunction "GND") (pintype "passive"))
    (pad "AA1" smd circle (at -12.5 7.499 180) (size 0.5 0.5) (layers "F.Cu" "F.Paste" "F.Mask")
      (net 77 "VDDQ") (pinfunction "VCCO_34") (pintype "power_in"))
    (pad "AA2" smd circle (at -11.5 7.499 180) (size 0.5 0.5) (layers "F.Cu" "F.Paste" "F.Mask")
      (net 320 "DQS1_N") (pinfunction "IO_L12N_T1_MRCC_34") (pintype "bidirectional") (die_length 19.51))
    (pad "AA3" smd circle (at -10.5 7.499 180) (size 0.5 0.5) (layers "F.Cu" "F.Paste" "F.Mask")
      (net 318 "DQS1_P") (pinfunction "IO_L12P_T1_MRCC_34") (pintype "bidirectional") (die_length 19.161))
    (pad "AA4" smd circle (at -9.5 7.499 180) (size 0.5 0.5) (layers "F.Cu" "F.Paste" "F.Mask")
      (net 247 "DQ14") (pinfunction "IO_L13P_T2_MRCC_34") (pintype "bidirectional") (die_length 19.112))
    (pad "AA5" smd circle (at -8.5 7.499 180) (size 0.5 0.5) (layers "F.Cu" "F.Paste" "F.Mask")
      (net 244 "DQ6") (pinfunction "IO_L15P_T2_DQS_34") (pintype "bidirectional") (die_length 18.268))
    (pad "AA6" smd circle (at -7.5 7.499 180) (size 0.5 0.5) (layers "F.Cu" "F.Paste" "F.Mask")
      (net 9 "GND") (pinfunction "GND") (pintype "passive"))
    (pad "AA7" smd circle (at -6.5 7.499 180) (size 0.5 0.5) (layers "F.Cu" "F.Paste" "F.Mask")
      (net 290 "CKE1\\NC") (pinfunction "IO_L8N_T1_33") (pintype "bidirectional") (die_length 16.325))
    (pad "AA8" smd circle (at -5.5 7.499 180) (size 0.5 0.5) (layers "F.Cu" "F.Paste" "F.Mask")
      (net 261 "CKE0") (pinfunction "IO_L8P_T1_33") (pintype "bidirectional") (die_length 15.251))
    (pad "AA9" smd circle (at -4.5 7.499 180) (size 0.5 0.5) (layers "F.Cu" "F.Paste" "F.Mask")
      (net 263 "BG0") (pinfunction "IO_L11P_T1_SRCC_33") (pintype "bidirectional") (die_length 13.773))
    (pad "AA10" smd circle (at -3.5 7.499 180) (size 0.5 0.5) (layers "F.Cu" "F.Paste" "F.Mask")
      (net 712 "unconnected-(U15G-IO_L14P_T2_SRCC_33-PadAA10)") (pinfunction "IO_L14P_T2_SRCC_33") (pintype "bidirectional+no_connect") (die_length 14.881))
    (pad "AA11" smd circle (at -2.5 7.499 180) (size 0.5 0.5) (layers "F.Cu" "F.Paste" "F.Mask")
      (net 77 "VDDQ") (pinfunction "VCCO_33") (pintype "power_in"))
    (pad "AA12" smd circle (at -1.5 7.499 180) (size 0.5 0.5) (layers "F.Cu" "F.Paste" "F.Mask")
      (net 238 "~{RAS}\\A16") (pinfunction "IO_L16N_T2_33") (pintype "bidirectional") (die_length 14.923))
    (pad "AA13" smd circle (at -0.5 7.499 180) (size 0.5 0.5) (layers "F.Cu" "F.Paste" "F.Mask")
      (net 210 "~{WE}\\A14") (pinfunction "IO_L16P_T2_33") (pintype "bidirectional") (die_length 16.493))
    (pad "AA14" smd circle (at 0.499 7.499 180) (size 0.5 0.5) (layers "F.Cu" "F.Paste" "F.Mask")
      (net 223 "DQ52") (pinfunction "IO_L7P_T1_32") (pintype "bidirectional") (die_length 11.726))
    (pad "AA15" smd circle (at 1.499 7.499 180) (size 0.5 0.5) (layers "F.Cu" "F.Paste" "F.Mask")
      (net 225 "DQ48") (pinfunction "IO_L7N_T1_32") (pintype "bidirectional") (die_length 11.467))
    (pad "AA16" smd circle (at 2.499 7.499 180) (size 0.5 0.5) (layers "F.Cu" "F.Paste" "F.Mask")
      (net 9 "GND") (pinfunction "GND") (pintype "passive"))
    (pad "AA17" smd circle (at 3.499 7.499 180) (size 0.5 0.5) (layers "F.Cu" "F.Paste" "F.Mask")
      (net 339 "DQS15_P") (pinfunction "IO_L11P_T1_SRCC_32") (pintype "bidirectional") (die_length 14.572))
    (pad "AA18" smd circle (at 4.499 7.499 180) (size 0.5 0.5) (layers "F.Cu" "F.Paste" "F.Mask")
      (net 341 "DQS15_N") (pinfunction "IO_L11N_T1_SRCC_32") (pintype "bidirectional") (die_length 14.747))
    (pad "AA19" smd circle (at 5.499 7.499 180) (size 0.5 0.5) (layers "F.Cu" "F.Paste" "F.Mask")
      (net 219 "DQ50") (pinfunction "IO_L16P_T2_32") (pintype "bidirectional") (die_length 19.389))
    (pad "AA20" smd circle (at 6.499 7.499 180) (size 0.5 0.5) (layers "F.Cu" "F.Paste" "F.Mask")
      (net 193 "DQ51") (pinfunction "IO_L16N_T2_32") (pintype "bidirectional") (die_length 21.053))
    (pad "AA21" smd circle (at 7.499 7.499 180) (size 0.5 0.5) (layers "F.Cu" "F.Paste" "F.Mask")
      (net 143 "3V3_SYS") (pinfunction "VCCO_12") (pintype "power_in"))
    (pad "AA22" smd circle (at 8.499 7.499 180) (size 0.5 0.5) (layers "F.Cu" "F.Paste" "F.Mask")
      (net 28 "ETH_RSTN") (pinfunction "IO_L13N_T2_MRCC_12") (pintype "bidirectional") (die_length 11.687))
    (pad "AA23" smd circle (at 9.499 7.499 180) (size 0.5 0.5) (layers "F.Cu" "F.Paste" "F.Mask")
      (net 30 "ETH_REF_CLK") (pinfunction "IO_L11P_T1_SRCC_12") (pintype "bidirectional") (die_length 13.863))
    (pad "AA24" smd circle (at 10.499 7.499 180) (size 0.5 0.5) (layers "F.Cu" "F.Paste" "F.Mask")
      (net 34 "ETH_TX_CLK") (pinfunction "IO_L12N_T1_MRCC_12") (pintype "bidirectional") (die_length 13.119))
    (pad "AA25" smd circle (at 11.499 7.499 180) (size 0.5 0.5) (layers "F.Cu" "F.Paste" "F.Mask")
      (net 39 "ETH_MDC") (pinfunction "IO_L7P_T1_12") (pintype "bidirectional") (die_length 15.139))
    (pad "AA26" smd circle (at 12.499 7.499 180) (size 0.5 0.5) (layers "F.Cu" "F.Paste" "F.Mask")
      (net 9 "GND") (pinfunction "GND") (pintype "passive"))
    (pad "AB1" smd circle (at -12.5 8.499 180) (size 0.5 0.5) (layers "F.Cu" "F.Paste" "F.Mask")
      (net 322 "DQS2_P") (pinfunction "IO_L9P_T1_DQS_34") (pintype "bidirectional") (die_length 21.468))
    (pad "AB2" smd circle (at -11.5 8.499 180) (size 0.5 0.5) (layers "F.Cu" "F.Paste" "F.Mask")
      (net 251 "DQ22") (pinfunction "IO_L11P_T1_SRCC_34") (pintype "bidirectional") (die_length 21.477))
    (pad "AB3" smd circle (at -10.5 8.499 180) (size 0.5 0.5) (layers "F.Cu" "F.Paste" "F.Mask")
      (net 9 "GND") (pinfunction "GND") (pintype "passive"))
    (pad "AB4" smd circle (at -9.5 8.499 180) (size 0.5 0.5) (layers "F.Cu" "F.Paste" "F.Mask")
      (net 273 "DQ15") (pinfunction "IO_L13N_T2_MRCC_34") (pintype "bidirectional") (die_length 19.11))
    (pad "AB5" smd circle (at -8.5 8.499 180) (size 0.5 0.5) (layers "F.Cu" "F.Paste" "F.Mask")
      (net 297 "DQ7") (pinfunction "IO_L15N_T2_DQS_34") (pintype "bidirectional") (die_length 17.889))
    (pad "AB6" smd circle (at -7.5 8.499 180) (size 0.5 0.5) (layers "F.Cu" "F.Paste" "F.Mask")
      (net 243 "DQ2") (pinfunction "IO_L16P_T2_34") (pintype "bidirectional") (die_length 18.462))
    (pad "AB7" smd circle (at -6.5 8.499 180) (size 0.5 0.5) (layers "F.Cu" "F.Paste" "F.Mask")
      (net 283 "A11") (pinfunction "IO_L10P_T1_33") (pintype "bidirectional") (die_length 14.818))
    (pad "AB8" smd circle (at -5.5 8.499 180) (size 0.5 0.5) (layers "F.Cu" "F.Paste" "F.Mask")
      (net 77 "VDDQ") (pinfunction "VCCO_33") (pintype "passive"))
    (pad "AB9" smd circle (at -4.5 8.499 180) (size 0.5 0.5) (layers "F.Cu" "F.Paste" "F.Mask")
      (net 267 "A6") (pinfunction "IO_L11N_T1_SRCC_33") (pintype "bidirectional") (die_length 13.992))
    (pad "AB10" smd circle (at -3.5 8.499 180) (size 0.5 0.5) (layers "F.Cu" "F.Paste" "F.Mask")
      (net 211 "BA1") (pinfunction "IO_L14N_T2_SRCC_33") (pintype "bidirectional") (die_length 15.337))
    (pad "AB11" smd circle (at -2.5 8.499 180) (size 0.5 0.5) (layers "F.Cu" "F.Paste" "F.Mask")
      (net 239 "BA0") (pinfunction "IO_L13P_T2_MRCC_33") (pintype "bidirectional") (die_length 18.178))
    (pad "AB12" smd circle (at -1.5 8.499 180) (size 0.5 0.5) (layers "F.Cu" "F.Paste" "F.Mask")
      (net 353 "CK1_P") (pinfunction "IO_L15P_T2_DQS_33") (pintype "bidirectional") (die_length 19.224))
    (pad "AB13" smd circle (at -0.5 8.499 180) (size 0.5 0.5) (layers "F.Cu" "F.Paste" "F.Mask")
      (net 9 "GND") (pinfunction "GND") (pintype "passive"))
    (pad "AB14" smd circle (at 0.499 8.499 180) (size 0.5 0.5) (layers "F.Cu" "F.Paste" "F.Mask")
      (net 229 "DQ40") (pinfunction "IO_L10P_T1_32") (pintype "bidirectional") (die_length 14.652))
    (pad "AB15" smd circle (at 1.499 8.499 180) (size 0.5 0.5) (layers "F.Cu" "F.Paste" "F.Mask")
      (net 188 "DQ43") (pinfunction "IO_L10N_T1_32") (pintype "bidirectional") (die_length 16.86))
    (pad "AB16" smd circle (at 2.499 8.499 180) (size 0.5 0.5) (layers "F.Cu" "F.Paste" "F.Mask")
      (net 204 "DQ53") (pinfunction "IO_L12P_T1_MRCC_32") (pintype "bidirectional") (die_length 17.498))
    (pad "AB17" smd circle (at 3.499 8.499 180) (size 0.5 0.5) (layers "F.Cu" "F.Paste" "F.Mask")
      (net 190 "DQ49") (pinfunction "IO_L14P_T2_SRCC_32") (pintype "bidirectional") (die_length 16.709))
    (pad "AB18" smd circle (at 4.499 8.499 180) (size 0.5 0.5) (layers "F.Cu" "F.Paste" "F.Mask")
      (net 77 "VDDQ") (pinfunction "VCCO_32") (pintype "power_in"))
    (pad "AB19" smd circle (at 5.499 8.499 180) (size 0.5 0.5) (layers "F.Cu" "F.Paste" "F.Mask")
      (net 220 "DQ54") (pinfunction "IO_L18P_T2_32") (pintype "bidirectional") (die_length 21.632))
    (pad "AB20" smd circle (at 6.499 8.499 180) (size 0.5 0.5) (layers "F.Cu" "F.Paste" "F.Mask")
      (net 206 "DQ55") (pinfunction "IO_L18N_T2_32") (pintype "bidirectional") (die_length 20.965))
    (pad "AB21" smd circle (at 7.499 8.499 180) (size 0.5 0.5) (layers "F.Cu" "F.Paste" "F.Mask")
      (net 713 "unconnected-(U15A-IO_L18P_T2_12-PadAB21)") (pinfunction "IO_L18P_T2_12") (pintype "bidirectional+no_connect") (die_length 11.49))
    (pad "AB22" smd circle (at 8.499 8.499 180) (size 0.5 0.5) (layers "F.Cu" "F.Paste" "F.Mask")
      (net 714 "unconnected-(U15A-IO_L17P_T2_12-PadAB22)") (pinfunction "IO_L17P_T2_12") (pintype "bidirectional+no_connect") (die_length 12.162))
    (pad "AB23" smd circle (at 9.499 8.499 180) (size 0.5 0.5) (layers "F.Cu" "F.Paste" "F.Mask")
      (net 9 "GND") (pinfunction "GND") (pintype "passive"))
    (pad "AB24" smd circle (at 10.499 8.499 180) (size 0.5 0.5) (layers "F.Cu" "F.Paste" "F.Mask")
      (net 715 "unconnected-(U15A-IO_L11N_T1_SRCC_12-PadAB24)") (pinfunction "IO_L11N_T1_SRCC_12") (pintype "bidirectional+no_connect") (die_length 14.571))
    (pad "AB25" smd circle (at 11.499 8.499 180) (size 0.5 0.5) (layers "F.Cu" "F.Paste" "F.Mask")
      (net 716 "unconnected-(U15A-IO_L7N_T1_12-PadAB25)") (pinfunction "IO_L7N_T1_12") (pintype "bidirectional+no_connect") (die_length 16.017))
    (pad "AB26" smd circle (at 12.499 8.499 180) (size 0.5 0.5) (layers "F.Cu" "F.Paste" "F.Mask")
      (net 29 "ETH_MDIO") (pinfunction "IO_L9P_T1_DQS_12") (pintype "bidirectional") (die_length 16.487))
    (pad "AC1" smd circle (at -12.5 9.499 180) (size 0.5 0.5) (layers "F.Cu" "F.Paste" "F.Mask")
      (net 324 "DQS2_N") (pinfunction "IO_L9N_T1_DQS_34") (pintype "bidirectional") (die_length 21.84))
    (pad "AC2" smd circle (at -11.5 9.499 180) (size 0.5 0.5) (layers "F.Cu" "F.Paste" "F.Mask")
      (net 253 "DQ18") (pinfunction "IO_L11N_T1_SRCC_34") (pintype "bidirectional") (die_length 21.727))
    (pad "AC3" smd circle (at -10.5 9.499 180) (size 0.5 0.5) (layers "F.Cu" "F.Paste" "F.Mask")
      (net 248 "DQ10") (pinfunction "IO_L14N_T2_SRCC_34") (pintype "bidirectional") (die_length 20.603))
    (pad "AC4" smd circle (at -9.5 9.499 180) (size 0.5 0.5) (layers "F.Cu" "F.Paste" "F.Mask")
      (net 274 "DQ11") (pinfunction "IO_L14P_T2_SRCC_34") (pintype "bidirectional") (die_length 20.232))
    (pad "AC5" smd circle (at -8.5 9.499 180) (size 0.5 0.5) (layers "F.Cu" "F.Paste" "F.Mask")
      (net 77 "VDDQ") (pinfunction "VCCO_34") (pintype "passive"))
    (pad "AC6" smd circle (at -7.5 9.499 180) (size 0.5 0.5) (layers "F.Cu" "F.Paste" "F.Mask")
      (net 292 "DQ3") (pinfunction "IO_L16N_T2_34") (pintype "bidirectional") (die_length 19.298))
    (pad "AC7" smd circle (at -6.5 9.499 180) (size 0.5 0.5) (layers "F.Cu" "F.Paste" "F.Mask")
      (net 265 "A12\\~{BC}") (pinfunction "IO_L10N_T1_33") (pintype "bidirectional") (die_length 16.292))
    (pad "AC8" smd circle (at -5.5 9.499 180) (size 0.5 0.5) (layers "F.Cu" "F.Paste" "F.Mask")
      (net 717 "unconnected-(U15G-IO_L9P_T1_DQS_33-PadAC8)") (pinfunction "IO_L9P_T1_DQS_33") (pintype "bidirectional+no_connect") (die_length 16.788))
    (pad "AC9" smd circle (at -4.5 9.499 180) (size 0.5 0.5) (layers "F.Cu" "F.Paste" "F.Mask")
      (net 289 "A4") (pinfunction "IO_L12P_T1_MRCC_33") (pintype "bidirectional") (die_length 16.857))
    (pad "AC10" smd circle (at -3.5 9.499 180) (size 0.5 0.5) (layers "F.Cu" "F.Paste" "F.Mask")
      (net 9 "GND") (pinfunction "GND") (pintype "passive"))
    (pad "AC11" smd circle (at -2.5 9.499 180) (size 0.5 0.5) (layers "F.Cu" "F.Paste" "F.Mask")
      (net 270 "A1") (pinfunction "IO_L13N_T2_MRCC_33") (pintype "bidirectional") (die_length 17.813))
    (pad "AC12" smd circle (at -1.5 9.499 180) (size 0.5 0.5) (layers "F.Cu" "F.Paste" "F.Mask")
      (net 354 "CK1_N") (pinfunction "IO_L15N_T2_DQS_33") (pintype "bidirectional") (die_length 18.956))
    (pad "AC13" smd circle (at -0.5 9.499 180) (size 0.5 0.5) (layers "F.Cu" "F.Paste" "F.Mask")
      (net 200 "A17") (pinfunction "IO_L17P_T2_33") (pintype "bidirectional") (die_length 21.425))
    (pad "AC14" smd circle (at 0.499 9.499 180) (size 0.5 0.5) (layers "F.Cu" "F.Paste" "F.Mask")
      (net 226 "DQ44") (pinfunction "IO_L8P_T1_32") (pintype "bidirectional") (die_length 15.875))
    (pad "AC15" smd circle (at 1.499 9.499 180) (size 0.5 0.5) (layers "F.Cu" "F.Paste" "F.Mask")
      (net 77 "VDDQ") (pinfunction "VCCO_32") (pintype "passive"))
    (pad "AC16" smd circle (at 2.499 9.499 180) (size 0.5 0.5) (layers "F.Cu" "F.Paste" "F.Mask")
      (net 224 "DQ42") (pinfunction "IO_L12N_T1_MRCC_32") (pintype "bidirectional") (die_length 17.396))
    (pad "AC17" smd circle (at 3.499 9.499 180) (size 0.5 0.5) (layers "F.Cu" "F.Paste" "F.Mask")
      (net 205 "DQ47") (pinfunction "IO_L14N_T2_SRCC_32") (pintype "bidirectional") (die_length 17.38))
    (pad "AC18" smd circle (at 4.499 9.499 180) (size 0.5 0.5) (layers "F.Cu" "F.Paste" "F.Mask")
      (net 334 "DQS5_P") (pinfunction "IO_L13P_T2_MRCC_32") (pintype "bidirectional") (die_length 20.008))
    (pad "AC19" smd circle (at 5.499 9.499 180) (size 0.5 0.5) (layers "F.Cu" "F.Paste" "F.Mask")
      (net 222 "DQ46") (pinfunction "IO_L17P_T2_32") (pintype "bidirectional") (die_length 22.343))
    (pad "AC20" smd circle (at 6.499 9.499 180) (size 0.5 0.5) (layers "F.Cu" "F.Paste" "F.Mask")
      (net 9 "GND") (pinfunction "GND") (pintype "passive"))
    (pad "AC21" smd circle (at 7.499 9.499 180) (size 0.5 0.5) (layers "F.Cu" "F.Paste" "F.Mask")
      (net 718 "unconnected-(U15A-IO_L18N_T2_12-PadAC21)") (pinfunction "IO_L18N_T2_12") (pintype "bidirectional+no_connect") (die_length 11.327))
    (pad "AC22" smd circle (at 8.499 9.499 180) (size 0.5 0.5) (layers "F.Cu" "F.Paste" "F.Mask")
      (net 719 "unconnected-(U15A-IO_L17N_T2_12-PadAC22)") (pinfunction "IO_L17N_T2_12") (pintype "bidirectional+no_connect") (die_length 12.08))
    (pad "AC23" smd circle (at 9.499 9.499 180) (size 0.5 0.5) (layers "F.Cu" "F.Paste" "F.Mask")
      (net 720 "unconnected-(U15A-IO_L14P_T2_SRCC_12-PadAC23)") (pinfunction "IO_L14P_T2_SRCC_12") (pintype "bidirectional+no_connect") (die_length 13.919))
    (pad "AC24" smd circle (at 10.499 9.499 180) (size 0.5 0.5) (layers "F.Cu" "F.Paste" "F.Mask")
      (net 154 "HR_RST") (pinfunction "IO_L14N_T2_SRCC_12") (pintype "bidirectional") (die_length 13.859))
    (pad "AC25" smd circle (at 11.499 9.499 180) (size 0.5 0.5) (layers "F.Cu" "F.Paste" "F.Mask")
      (net 143 "3V3_SYS") (pinfunction "VCCO_12") (pintype "passive"))
    (pad "AC26" smd circle (at 12.499 9.499 180) (size 0.5 0.5) (layers "F.Cu" "F.Paste" "F.Mask")
      (net 155 "HR_CS") (pinfunction "IO_L9N_T1_DQS_12") (pintype "bidirectional") (die_length 17.028))
    (pad "AD1" smd circle (at -12.5 10.499 180) (size 0.5 0.5) (layers "F.Cu" "F.Paste" "F.Mask")
      (net 277 "DQ23") (pinfunction "IO_L20P_T3_34") (pintype "bidirectional") (die_length 23.961))
    (pad "AD2" smd circle (at -11.5 10.499 180) (size 0.5 0.5) (layers "F.Cu" "F.Paste" "F.Mask")
      (net 77 "VDDQ") (pinfunction "VCCO_34") (pintype "passive"))
    (pad "AD3" smd circle (at -10.5 10.499 180) (size 0.5 0.5) (layers "F.Cu" "F.Paste" "F.Mask")
      (net 329 "DQS12_N") (pinfunction "IO_L19N_T3_VREF_34") (pintype "bidirectional") (die_length 21.156))
    (pad "AD4" smd circle (at -9.5 10.499 180) (size 0.5 0.5) (layers "F.Cu" "F.Paste" "F.Mask")
      (net 327 "DQS12_P") (pinfunction "IO_L19P_T3_34") (pintype "bidirectional") (die_length 21.197))
    (pad "AD5" smd circle (at -8.5 10.499 180) (size 0.5 0.5) (layers "F.Cu" "F.Paste" "F.Mask")
      (net 256 "DQ26") (pinfunction "IO_L18N_T2_34") (pintype "bidirectional") (die_length 19.989))
    (pad "AD6" smd circle (at -7.5 10.499 180) (size 0.5 0.5) (layers "F.Cu" "F.Paste" "F.Mask")
      (net 287 "DQ27") (pinfunction "IO_L18P_T2_34") (pintype "bidirectional") (die_length 20.498))
    (pad "AD7" smd circle (at -6.5 10.499 180) (size 0.5 0.5) (layers "F.Cu" "F.Paste" "F.Mask")
      (net 9 "GND") (pinfunction "GND") (pintype "passive"))
    (pad "AD8" smd circle (at -5.5 10.499 180) (size 0.5 0.5) (layers "F.Cu" "F.Paste" "F.Mask")
      (net 721 "unconnected-(U15G-IO_L9N_T1_DQS_33-PadAD8)") (pinfunction "IO_L9N_T1_DQS_33") (pintype "bidirectional+no_connect") (die_length 16.577))
    (pad "AD9" smd circle (at -4.5 10.499 180) (size 0.5 0.5) (layers "F.Cu" "F.Paste" "F.Mask")
      (net 276 "A5") (pinfunction "IO_L12N_T1_MRCC_33") (pintype "bidirectional") (die_length 17.579))
    (pad "AD10" smd circle (at -3.5 10.499 180) (size 0.5 0.5) (layers "F.Cu" "F.Paste" "F.Mask")
      (net 269 "A3") (pinfunction "IO_L20P_T3_33") (pintype "bidirectional") (die_length 16.019))
    (pad "AD11" smd circle (at -2.5 10.499 180) (size 0.5 0.5) (layers "F.Cu" "F.Paste" "F.Mask")
      (net 291 "A2") (pinfunction "IO_L19P_T3_33") (pintype "bidirectional") (die_length 18.739))
    (pad "AD12" smd circle (at -1.5 10.499 180) (size 0.5 0.5) (layers "F.Cu" "F.Paste" "F.Mask")
      (net 77 "VDDQ") (pinfunction "VCCO_33") (pintype "passive"))
    (pad "AD13" smd circle (at -0.5 10.499 180) (size 0.5 0.5) (layers "F.Cu" "F.Paste" "F.Mask")
      (net 207 "A13") (pinfunction "IO_L17N_T2_33") (pintype "bidirectional") (die_length 19.307))
    (pad "AD14" smd circle (at 0.499 10.499 180) (size 0.5 0.5) (layers "F.Cu" "F.Paste" "F.Mask")
      (net 212 "DQ37") (pinfunction "IO_L8N_T1_32") (pintype "bidirectional") (die_length 17.8))
    (pad "AD15" smd circle (at 1.499 10.499 180) (size 0.5 0.5) (layers "F.Cu" "F.Paste" "F.Mask")
      (net 331 "DQS13_P") (pinfunction "IO_L4P_T0_32") (pintype "bidirectional") (die_length 19.249))
    (pad "AD16" smd circle (at 2.499 10.499 180) (size 0.5 0.5) (layers "F.Cu" "F.Paste" "F.Mask")
      (net 203 "DQ45") (pinfunction "IO_L6P_T0_32") (pintype "bidirectional") (die_length 19.246))
    (pad "AD17" smd circle (at 3.499 10.499 180) (size 0.5 0.5) (layers "F.Cu" "F.Paste" "F.Mask")
      (net 9 "GND") (pinfunction "GND") (pintype "passive"))
    (pad "AD18" smd circle (at 4.499 10.499 180) (size 0.5 0.5) (layers "F.Cu" "F.Paste" "F.Mask")
      (net 336 "DQS5_N") (pinfunction "IO_L13N_T2_MRCC_32") (pintype "bidirectional") (die_length 20.423))
    (pad "AD19" smd circle (at 5.499 10.499 180) (size 0.5 0.5) (layers "F.Cu" "F.Paste" "F.Mask")
      (net 189 "DQ41") (pinfunction "IO_L17N_T2_32") (pintype "bidirectional") (die_length 20.752))
    (pad "AD20" smd circle (at 6.499 10.499 180) (size 0.5 0.5) (layers "F.Cu" "F.Paste" "F.Mask")
      (net 335 "DQS14_P") (pinfunction "IO_L15P_T2_DQS_32") (pintype "bidirectional") (die_length 22.214))
    (pad "AD21" smd circle (at 7.499 10.499 180) (size 0.5 0.5) (layers "F.Cu" "F.Paste" "F.Mask")
      (net 722 "unconnected-(U15A-IO_L19P_T3_12-PadAD21)") (pinfunction "IO_L19P_T3_12") (pintype "bidirectional+no_connect") (die_length 13.92))
    (pad "AD22" smd circle (at 8.499 10.499 180) (size 0.5 0.5) (layers "F.Cu" "F.Paste" "F.Mask")
      (net 143 "3V3_SYS") (pinfunction "VCCO_12") (pintype "passive"))
    (pad "AD23" smd circle (at 9.499 10.499 180) (size 0.5 0.5) (layers "F.Cu" "F.Paste" "F.Mask")
      (net 158 "HR_RW") (pinfunction "IO_L16P_T2_12") (pintype "bidirectional") (die_length 14.54))
    (pad "AD24" smd circle (at 10.499 10.499 180) (size 0.5 0.5) (layers "F.Cu" "F.Paste" "F.Mask")
      (net 162 "HR_DQ7") (pinfunction "IO_L16N_T2_12") (pintype "bidirectional") (die_length 14.673))
    (pad "AD25" smd circle (at 11.499 10.499 180) (size 0.5 0.5) (layers "F.Cu" "F.Paste" "F.Mask")
      (net 156 "HR_DQ1") (pinfunction "IO_L23P_T3_12") (pintype "bidirectional") (die_length 16.272))
    (pad "AD26" smd circle (at 12.499 10.499 180) (size 0.5 0.5) (layers "F.Cu" "F.Paste" "F.Mask")
      (net 164 "HR_CKP") (pinfunction "IO_L21P_T3_DQS_12") (pintype "bidirectional") (die_length 17.707))
    (pad "AE1" smd circle (at -12.5 11.499 180) (size 0.5 0.5) (layers "F.Cu" "F.Paste" "F.Mask")
      (net 286 "DQ19") (pinfunction "IO_L20N_T3_34") (pintype "bidirectional") (die_length 23.86))
    (pad "AE2" smd circle (at -11.5 11.499 180) (size 0.5 0.5) (layers "F.Cu" "F.Paste" "F.Mask")
      (net 252 "DQ28") (pinfunction "IO_L22N_T3_34") (pintype "bidirectional") (die_length 25.162))
    (pad "AE3" smd circle (at -10.5 11.499 180) (size 0.5 0.5) (layers "F.Cu" "F.Paste" "F.Mask")
      (net 254 "DQ24") (pinfunction "IO_L22P_T3_34") (pintype "bidirectional") (die_length 24.57))
    (pad "AE4" smd circle (at -9.5 11.499 180) (size 0.5 0.5) (layers "F.Cu" "F.Paste" "F.Mask")
      (net 9 "GND") (pinfunction "GND") (pintype "passive"))
    (pad "AE5" smd circle (at -8.5 11.499 180) (size 0.5 0.5) (layers "F.Cu" "F.Paste" "F.Mask")
      (net 255 "DQ30") (pinfunction "IO_L23N_T3_34") (pintype "bidirectional") (die_length 20.276))
    (pad "AE6" smd circle (at -7.5 11.499 180) (size 0.5 0.5) (layers "F.Cu" "F.Paste" "F.Mask")
      (net 279 "DQ31") (pinfunction "IO_L23P_T3_34") (pintype "bidirectional") (die_length 20.819))
    (pad "AE7" smd circle (at -6.5 11.499 180) (size 0.5 0.5) (layers "F.Cu" "F.Paste" "F.Mask")
      (net 266 "A9") (pinfunction "IO_L7P_T1_33") (pintype "bidirectional") (die_length 17.815))
    (pad "AE8" smd circle (at -5.5 11.499 180) (size 0.5 0.5) (layers "F.Cu" "F.Paste" "F.Mask")
      (net 268 "A8") (pinfunction "IO_L22P_T3_33") (pintype "bidirectional") (die_length 19.534))
    (pad "AE9" smd circle (at -4.5 11.499 180) (size 0.5 0.5) (layers "F.Cu" "F.Paste" "F.Mask")
      (net 77 "VDDQ") (pinfunction "VCCO_33") (pintype "passive"))
    (pad "AE10" smd circle (at -3.5 11.499 180) (size 0.5 0.5) (layers "F.Cu" "F.Paste" "F.Mask")
      (net 296 "~{ALERT}") (pinfunction "IO_L20N_T3_33") (pintype "bidirectional") (die_length 16.714))
    (pad "AE11" smd circle (at -2.5 11.499 180) (size 0.5 0.5) (layers "F.Cu" "F.Paste" "F.Mask")
      (net 312 "VREF_33") (pinfunction "IO_L19N_T3_VREF_33") (pintype "bidirectional") (die_length 17.525))
    (pad "AE12" smd circle (at -1.5 11.499 180) (size 0.5 0.5) (layers "F.Cu" "F.Paste" "F.Mask")
      (net 355 "CK0_P") (pinfunction "IO_L21P_T3_DQS_33") (pintype "bidirectional") (die_length 19.187))
    (pad "AE13" smd circle (at -0.5 11.499 180) (size 0.5 0.5) (layers "F.Cu" "F.Paste" "F.Mask")
      (net 199 "PARITY") (pinfunction "IO_L23P_T3_33") (pintype "bidirectional") (die_length 20.167))
    (pad "AE14" smd circle (at 0.499 11.499 180) (size 0.5 0.5) (layers "F.Cu" "F.Paste" "F.Mask")
      (net 9 "GND") (pinfunction "GND") (pintype "passive"))
    (pad "AE15" smd circle (at 1.499 11.499 180) (size 0.5 0.5) (layers "F.Cu" "F.Paste" "F.Mask")
      (net 333 "DQS13_N") (pinfunction "IO_L4N_T0_32") (pintype "bidirectional") (die_length 20.349))
    (pad "AE16" smd circle (at 2.499 11.499 180) (size 0.5 0.5) (layers "F.Cu" "F.Paste" "F.Mask")
      (net 194 "DQ33") (pinfunction "IO_L6N_T0_VREF_32") (pintype "bidirectional") (die_length 18.914))
    (pad "AE17" smd circle (at 3.499 11.499 180) (size 0.5 0.5) (layers "F.Cu" "F.Paste" "F.Mask")
      (net 330 "DQS4_P") (pinfunction "IO_L1P_T0_32") (pintype "bidirectional") (die_length 25.66))
    (pad "AE18" smd circle (at 4.499 11.499 180) (size 0.5 0.5) (layers "F.Cu" "F.Paste" "F.Mask")
      (net 202 "DQ39") (pinfunction "IO_L3P_T0_DQS_32") (pintype "bidirectional") (die_length 23.868))
    (pad "AE19" smd circle (at 5.499 11.499 180) (size 0.5 0.5) (layers "F.Cu" "F.Paste" "F.Mask")
      (net 77 "VDDQ") (pinfunction "VCCO_32") (pintype "passive"))
    (pad "AE20" smd circle (at 6.499 11.499 180) (size 0.5 0.5) (layers "F.Cu" "F.Paste" "F.Mask")
      (net 337 "DQS14_N") (pinfunction "IO_L15N_T2_DQS_32") (pintype "bidirectional") (die_length 21.92))
    (pad "AE21" smd circle (at 7.499 11.499 180) (size 0.5 0.5) (layers "F.Cu" "F.Paste" "F.Mask")
      (net 723 "unconnected-(U15A-IO_L19N_T3_VREF_12-PadAE21)") (pinfunction "IO_L19N_T3_VREF_12") (pintype "bidirectional+no_connect") (die_length 13.224))
    (pad "AE22" smd circle (at 8.499 11.499 180) (size 0.5 0.5) (layers "F.Cu" "F.Paste" "F.Mask")
      (net 165 "HR_DQ3") (pinfunction "IO_L24P_T3_12") (pintype "bidirectional") (die_length 13.617))
    (pad "AE23" smd circle (at 9.499 11.499 180) (size 0.5 0.5) (layers "F.Cu" "F.Paste" "F.Mask")
      (net 157 "HR_DQ0") (pinfunction "IO_L22P_T3_12") (pintype "bidirectional") (die_length 17.11))
    (pad "AE24" smd circle (at 10.499 11.499 180) (size 0.5 0.5) (layers "F.Cu" "F.Paste" "F.Mask")
      (net 9 "GND") (pinfunction "GND") (pintype "passive"))
    (pad "AE25" smd circle (at 11.499 11.499 180) (size 0.5 0.5) (layers "F.Cu" "F.Paste" "F.Mask")
      (net 163 "HR_DQ6") (pinfunction "IO_L23N_T3_12") (pintype "bidirectional") (die_length 16.458))
    (pad "AE26" smd circle (at 12.499 11.499 180) (size 0.5 0.5) (layers "F.Cu" "F.Paste" "F.Mask")
      (net 159 "HR_CKN") (pinfunction "IO_L21N_T3_DQS_12") (pintype "bidirectional") (die_length 17.907))
    (pad "AF1" smd circle (at -12.5 12.499 180) (size 0.5 0.5) (layers "F.Cu" "F.Paste" "F.Mask")
      (net 9 "GND") (pinfunction "GND") (pintype "passive"))
    (pad "AF2" smd circle (at -11.5 12.499 180) (size 0.5 0.5) (layers "F.Cu" "F.Paste" "F.Mask")
      (net 285 "DQ29") (pinfunction "IO_L24N_T3_34") (pintype "bidirectional") (die_length 24.825))
    (pad "AF3" smd circle (at -10.5 12.499 180) (size 0.5 0.5) (layers "F.Cu" "F.Paste" "F.Mask")
      (net 271 "DQ25") (pinfunction "IO_L24P_T3_34") (pintype "bidirectional") (die_length 23.875))
    (pad "AF4" smd circle (at -9.5 12.499 180) (size 0.5 0.5) (layers "F.Cu" "F.Paste" "F.Mask")
      (net 328 "DQS3_N") (pinfunction "IO_L21N_T3_DQS_34") (pintype "bidirectional") (die_length 21.687))
    (pad "AF5" smd circle (at -8.5 12.499 180) (size 0.5 0.5) (layers "F.Cu" "F.Paste" "F.Mask")
      (net 326 "DQS3_P") (pinfunction "IO_L21P_T3_DQS_34") (pintype "bidirectional") (die_length 22.107))
    (pad "AF6" smd circle (at -7.5 12.499 180) (size 0.5 0.5) (layers "F.Cu" "F.Paste" "F.Mask")
      (net 77 "VDDQ") (pinfunction "VCCO_34") (pintype "passive"))
    (pad "AF7" smd circle (at -6.5 12.499 180) (size 0.5 0.5) (layers "F.Cu" "F.Paste" "F.Mask")
      (net 284 "A7") (pinfunction "IO_L7N_T1_33") (pintype "bidirectional") (die_length 18.816))
    (pad "AF8" smd circle (at -5.5 12.499 180) (size 0.5 0.5) (layers "F.Cu" "F.Paste" "F.Mask")
      (net 262 "~{RESET}") (pinfunction "IO_L22N_T3_33") (pintype "bidirectional") (die_length 19.356))
    (pad "AF9" smd circle (at -4.5 12.499 180) (size 0.5 0.5) (layers "F.Cu" "F.Paste" "F.Mask")
      (net 280 "BG1") (pinfunction "IO_L24N_T3_33") (pintype "bidirectional") (die_length 18.041))
    (pad "AF10" smd circle (at -3.5 12.499 180) (size 0.5 0.5) (layers "F.Cu" "F.Paste" "F.Mask")
      (net 240 "A0") (pinfunction "IO_L24P_T3_33") (pintype "bidirectional") (die_length 18.552))
    (pad "AF11" smd circle (at -2.5 12.499 180) (size 0.5 0.5) (layers "F.Cu" "F.Paste" "F.Mask")
      (net 9 "GND") (pinfunction "GND") (pintype "passive"))
    (pad "AF12" smd circle (at -1.5 12.499 180) (size 0.5 0.5) (layers "F.Cu" "F.Paste" "F.Mask")
      (net 356 "CK0_N") (pinfunction "IO_L21N_T3_DQS_33") (pintype "bidirectional") (die_length 18.818))
    (pad "AF13" smd circle (at -0.5 12.499 180) (size 0.5 0.5) (layers "F.Cu" "F.Paste" "F.Mask")
      (net 236 "~{CAS}\\A15") (pinfunction "IO_L23N_T3_33") (pintype "bidirectional") (die_length 20.747))
    (pad "AF14" smd circle (at 0.499 12.499 180) (size 0.5 0.5) (layers "F.Cu" "F.Paste" "F.Mask")
      (net 233 "DQ36") (pinfunction "IO_L2P_T0_32") (pintype "bidirectional") (die_length 20.408))
    (pad "AF15" smd circle (at 1.499 12.499 180) (size 0.5 0.5) (layers "F.Cu" "F.Paste" "F.Mask")
      (net 232 "DQ32") (pinfunction "IO_L2N_T0_32") (pintype "bidirectional") (die_length 21.691))
    (pad "AF16" smd circle (at 2.499 12.499 180) (size 0.5 0.5) (layers "F.Cu" "F.Paste" "F.Mask")
      (net 77 "VDDQ") (pinfunction "VCCO_32") (pintype "passive"))
    (pad "AF17" smd circle (at 3.499 12.499 180) (size 0.5 0.5) (layers "F.Cu" "F.Paste" "F.Mask")
      (net 332 "DQS4_N") (pinfunction "IO_L1N_T0_32") (pintype "bidirectional") (die_length 25.392))
    (pad "AF18" smd circle (at 4.499 12.499 180) (size 0.5 0.5) (layers "F.Cu" "F.Paste" "F.Mask")
      (net 228 "DQ38") (pinfunction "IO_L3N_T0_DQS_32") (pintype "bidirectional") (die_length 23.477))
    (pad "AF19" smd circle (at 5.499 12.499 180) (size 0.5 0.5) (layers "F.Cu" "F.Paste" "F.Mask")
      (net 227 "DQ34") (pinfunction "IO_L5P_T0_32") (pintype "bidirectional") (die_length 22.609))
    (pad "AF20" smd circle (at 6.499 12.499 180) (size 0.5 0.5) (layers "F.Cu" "F.Paste" "F.Mask")
      (net 213 "DQ35") (pinfunction "IO_L5N_T0_32") (pintype "bidirectional") (die_length 22.255))
    (pad "AF21" smd circle (at 7.499 12.499 180) (size 0.5 0.5) (layers "F.Cu" "F.Paste" "F.Mask")
      (net 9 "GND") (pinfunction "GND") (pintype "passive"))
    (pad "AF22" smd circle (at 8.499 12.499 180) (size 0.5 0.5) (layers "F.Cu" "F.Paste" "F.Mask")
      (net 789 "DDR_PRESENCE") (pinfunction "IO_L24N_T3_12") (pintype "bidirectional") (die_length 14.462))
    (pad "AF23" smd circle (at 9.499 12.499 180) (size 0.5 0.5) (layers "F.Cu" "F.Paste" "F.Mask")
      (net 161 "HR_DQ4") (pinfunction "IO_L22N_T3_12") (pintype "bidirectional") (die_length 16.26))
    (pad "AF24" smd circle (at 10.499 12.499 180) (size 0.5 0.5) (layers "F.Cu" "F.Paste" "F.Mask")
      (net 166 "HR_DQ2") (pinfunction "IO_L20P_T3_12") (pintype "bidirectional") (die_length 17.799))
    (pad "AF25" smd circle (at 11.499 12.499 180) (size 0.5 0.5) (layers "F.Cu" "F.Paste" "F.Mask")
      (net 160 "HR_DQ5") (pinfunction "IO_L20N_T3_12") (pintype "bidirectional") (die_length 18.603))
    (pad "AF26" smd circle (at 12.499 12.499 180) (size 0.5 0.5) (layers "F.Cu" "F.Paste" "F.Mask")
      (net 143 "3V3_SYS") (pinfunction "VCCO_12") (pintype "passive"))
    (pad "B1" smd circle (at -12.5 -11.5 180) (size 0.5 0.5) (layers "F.Cu" "F.Paste" "F.Mask")
      (net 429 "GTX_TX1_N") (pinfunction "MGTXTXN2_116") (pintype "bidirectional") (die_length 15.86))
    (pad "B2" smd circle (at -11.5 -11.5 180) (size 0.5 0.5) (layers "F.Cu" "F.Paste" "F.Mask")
      (net 420 "GTX_TX1_P") (pinfunction "MGTXTXP2_116") (pintype "bidirectional") (die_length 16.008))
    (pad "B3" smd circle (at -10.5 -11.5 180) (size 0.5 0.5) (layers "F.Cu" "F.Paste" "F.Mask")
      (net 306 "1V2_SYS") (pinfunction "MGTAVTT") (pintype "power_in"))
    (pad "B4" smd circle (at -9.5 -11.5 180) (size 0.5 0.5) (layers "F.Cu" "F.Paste" "F.Mask")
      (net 9 "GND") (pinfunction "GND") (pintype "passive"))
    (pad "B5" smd circle (at -8.5 -11.5 180) (size 0.5 0.5) (layers "F.Cu" "F.Paste" "F.Mask")
      (net 656 "GTX_RX0_N") (pinfunction "MGTXRXN3_116") (pintype "bidirectional") (die_length 13.646))
    (pad "B6" smd circle (at -7.5 -11.5 180) (size 0.5 0.5) (layers "F.Cu" "F.Paste" "F.Mask")
      (net 655 "GTX_RX0_P") (pinfunction "MGTXRXP3_116") (pintype "bidirectional") (die_length 13.747))
    (pad "B7" smd circle (at -6.5 -11.5 180) (size 0.5 0.5) (layers "F.Cu" "F.Paste" "F.Mask")
      (net 9 "GND") (pinfunction "GND") (pintype "passive"))
    (pad "B8" smd circle (at -5.5 -11.5 180) (size 0.5 0.5) (layers "F.Cu" "F.Paste" "F.Mask")
      (net 143 "3V3_SYS") (pinfunction "VCCO_16") (pintype "passive"))
    (pad "B9" smd circle (at -4.5 -11.5 180) (size 0.5 0.5) (layers "F.Cu" "F.Paste" "F.Mask")
      (net 724 "unconnected-(U15E-IO_L10N_T1_16-PadB9)") (pinfunction "IO_L10N_T1_16") (pintype "bidirectional+no_connect") (die_length 21.661))
    (pad "B10" smd circle (at -3.5 -11.5 180) (size 0.5 0.5) (layers "F.Cu" "F.Paste" "F.Mask")
      (net 61 "TMDS_D2_P") (pinfunction "IO_L22P_T3_16") (pintype "bidirectional") (die_length 19.148))
    (pad "B11" smd circle (at -2.5 -11.5 180) (size 0.5 0.5) (layers "F.Cu" "F.Paste" "F.Mask")
      (net 725 "unconnected-(U15E-IO_L20N_T3_16-PadB11)") (pinfunction "IO_L20N_T3_16") (pintype "bidirectional+no_connect") (die_length 19.129))
    (pad "B12" smd circle (at -1.5 -11.5 180) (size 0.5 0.5) (layers "F.Cu" "F.Paste" "F.Mask")
      (net 726 "unconnected-(U15E-IO_L20P_T3_16-PadB12)") (pinfunction "IO_L20P_T3_16") (pintype "bidirectional+no_connect") (die_length 19.084))
    (pad "B13" smd circle (at -0.5 -11.5 180) (size 0.5 0.5) (layers "F.Cu" "F.Paste" "F.Mask")
      (net 9 "GND") (pinfunction "GND") (pintype "passive"))
    (pad "B14" smd circle (at 0.499 -11.5 180) (size 0.5 0.5) (layers "F.Cu" "F.Paste" "F.Mask")
      (net 57 "TMDS_D0_P") (pinfunction "IO_L21P_T3_DQS_16") (pintype "bidirectional") (die_length 17.698))
    (pad "B15" smd circle (at 1.499 -11.5 180) (size 0.5 0.5) (layers "F.Cu" "F.Paste" "F.Mask")
      (net 55 "TMDS_CLK_P") (pinfunction "IO_L23P_T3_16") (pintype "bidirectional") (die_length 17.518))
    (pad "B16" smd circle (at 2.499 -11.5 180) (size 0.5 0.5) (layers "F.Cu" "F.Paste" "F.Mask")
      (net 417 "FMC_IO_1_N") (pinfunction "IO_L1N_T0_AD0N_15") (pintype "bidirectional") (die_length 16.625))
    (pad "B17" smd circle (at 3.499 -11.5 180) (size 0.5 0.5) (layers "F.Cu" "F.Paste" "F.Mask")
      (net 425 "FMC_IO_3_P") (pinfunction "IO_L3P_T0_DQS_AD1P_15") (pintype "bidirectional") (die_length 17.668))
    (pad "B18" smd circle (at 4.499 -11.5 180) (size 0.5 0.5) (layers "F.Cu" "F.Paste" "F.Mask")
      (net 143 "3V3_SYS") (pinfunction "VCCO_15") (pintype "power_in"))
    (pad "B19" smd circle (at 5.499 -11.5 180) (size 0.5 0.5) (layers "F.Cu" "F.Paste" "F.Mask")
      (net 426 "FMC_IO_4_N") (pinfunction "IO_L4N_T0_AD9N_15") (pintype "bidirectional") (die_length 18.77))
    (pad "B20" smd circle (at 6.499 -11.5 180) (size 0.5 0.5) (layers "F.Cu" "F.Paste" "F.Mask")
      (net 70 "USR_LED2") (pinfunction "IO_L8P_T1_D11_14") (pintype "bidirectional") (die_length 20.881))
    (pad "B21" smd circle (at 7.499 -11.5 180) (size 0.5 0.5) (layers "F.Cu" "F.Paste" "F.Mask")
      (net 68 "USR_LED3") (pinfunction "IO_L10N_T1_D15_14") (pintype "bidirectional") (die_length 22.228))
    (pad "B22" smd circle (at 8.499 -11.5 180) (size 0.5 0.5) (layers "F.Cu" "F.Paste" "F.Mask")
      (net 21 "QSPI_DQ2") (pinfunction "IO_L2P_T0_D02_14") (pintype "bidirectional") (die_length 20.4))
    (pad "B23" smd circle (at 9.499 -11.5 180) (size 0.5 0.5) (layers "F.Cu" "F.Paste" "F.Mask")
      (net 9 "GND") (pinfunction "GND") (pintype "passive"))
    (pad "B24" smd circle (at 10.499 -11.5 180) (size 0.5 0.5) (layers "F.Cu" "F.Paste" "F.Mask")
      (net 19 "QSPI_DQ0") (pinfunction "IO_L1P_T0_D00_MOSI_14") (pintype "bidirectional") (die_length 22.518))
    (pad "B25" smd circle (at 11.499 -11.5 180) (size 0.5 0.5) (layers "F.Cu" "F.Paste" "F.Mask")
      (net 79 "PUDC_B") (pinfunction "IO_L3P_T0_DQS_PUDC_B_14") (pintype "bidirectional") (die_length 23.894))
    (pad "B26" smd circle (at 12.499 -11.5 180) (size 0.5 0.5) (layers "F.Cu" "F.Paste" "F.Mask")
      (net 99 "EMCCLK") (pinfunction "IO_L3N_T0_DQS_EMCCLK_14") (pintype "bidirectional") (die_length 24.039))
    (pad "C1" smd circle (at -12.5 -10.5 180) (size 0.5 0.5) (layers "F.Cu" "F.Paste" "F.Mask")
      (net 9 "GND") (pinfunction "GND") (pintype "passive"))
    (pad "C2" smd circle (at -11.5 -10.5 180) (size 0.5 0.5) (layers "F.Cu" "F.Paste" "F.Mask")
      (net 306 "1V2_SYS") (pinfunction "MGTAVTT") (pintype "passive"))
    (pad "C3" smd circle (at -10.5 -10.5 180) (size 0.5 0.5) (layers "F.Cu" "F.Paste" "F.Mask")
      (net 633 "GTX_RX1_N") (pinfunction "MGTXRXN2_116") (pintype "bidirectional") (die_length 14.495))
    (pad "C4" smd circle (at -9.5 -10.5 180) (size 0.5 0.5) (layers "F.Cu" "F.Paste" "F.Mask")
      (net 632 "GTX_RX1_P") (pinfunction "MGTXRXP2_116") (pintype "bidirectional") (die_length 14.581))
    (pad "C5" smd circle (at -8.5 -10.5 180) (size 0.5 0.5) (layers "F.Cu" "F.Paste" "F.Mask")
      (net 9 "GND") (pinfunction "GND") (pintype "passive"))
    (pad "C6" smd circle (at -7.5 -10.5 180) (size 0.5 0.5) (layers "F.Cu" "F.Paste" "F.Mask")
      (net 147 "1V0_SYS") (pinfunction "MGTAVCC") (pintype "power_in"))
    (pad "C7" smd circle (at -6.5 -10.5 180) (size 0.5 0.5) (layers "F.Cu" "F.Paste" "F.Mask")
      (net 9 "GND") (pinfunction "GND") (pintype "passive"))
    (pad "C8" smd circle (at -5.5 -10.5 180) (size 0.5 0.5) (layers "F.Cu" "F.Paste" "F.Mask")
      (net 96 "CCLK") (pinfunction "CCLK_0") (pintype "bidirectional") (die_length 21.831))
    (pad "C9" smd circle (at -4.5 -10.5 180) (size 0.5 0.5) (layers "F.Cu" "F.Paste" "F.Mask")
      (net 87 "SD_DAT2") (pinfunction "IO_L10P_T1_16") (pintype "bidirectional") (die_length 20.913))
    (pad "C10" smd circle (at -3.5 -10.5 180) (size 0.5 0.5) (layers "F.Cu" "F.Paste" "F.Mask")
      (net 9 "GND") (pinfunction "GND") (pintype "passive"))
    (pad "C11" smd circle (at -2.5 -10.5 180) (size 0.5 0.5) (layers "F.Cu" "F.Paste" "F.Mask")
      (net 727 "unconnected-(U15E-IO_L13N_T2_MRCC_16-PadC11)") (pinfunction "IO_L13N_T2_MRCC_16") (pintype "bidirectional+no_connect") (die_length 19.377))
    (pad "C12" smd circle (at -1.5 -10.5 180) (size 0.5 0.5) (layers "F.Cu" "F.Paste" "F.Mask")
      (net 311 "GCLK100") (pinfunction "IO_L13P_T2_MRCC_16") (pintype "bidirectional") (die_length 19.317))
    (pad "C13" smd circle (at -0.5 -10.5 180) (size 0.5 0.5) (layers "F.Cu" "F.Paste" "F.Mask")
      (net 728 "unconnected-(U15E-IO_L19N_T3_VREF_16-PadC13)") (pinfunction "IO_L19N_T3_VREF_16") (pintype "bidirectional+no_connect") (die_length 16.263))
    (pad "C14" smd circle (at 0.499 -10.5 180) (size 0.5 0.5) (layers "F.Cu" "F.Paste" "F.Mask")
      (net 729 "unconnected-(U15E-IO_L19P_T3_16-PadC14)") (pinfunction "IO_L19P_T3_16") (pintype "bidirectional+no_connect") (die_length 15.843))
    (pad "C15" smd circle (at 1.499 -10.5 180) (size 0.5 0.5) (layers "F.Cu" "F.Paste" "F.Mask")
      (net 143 "3V3_SYS") (pinfunction "VCCO_16") (pintype "passive"))
    (pad "C16" smd circle (at 2.499 -10.5 180) (size 0.5 0.5) (layers "F.Cu" "F.Paste" "F.Mask")
      (net 427 "FMC_IO_1_P") (pinfunction "IO_L1P_T0_AD0P_15") (pintype "bidirectional") (die_length 14.788))
    (pad "C17" smd circle (at 3.499 -10.5 180) (size 0.5 0.5) (layers "F.Cu" "F.Paste" "F.Mask")
      (net 428 "FMC_IO_5_P") (pinfunction "IO_L5P_T0_AD2P_15") (pintype "bidirectional") (die_length 15.703))
    (pad "C18" smd circle (at 4.499 -10.5 180) (size 0.5 0.5) (layers "F.Cu" "F.Paste" "F.Mask")
      (net 435 "FMC_IO_5_N") (pinfunction "IO_L5N_T0_AD2N_15") (pintype "bidirectional") (die_length 17.41))
    (pad "C19" smd circle (at 5.499 -10.5 180) (size 0.5 0.5) (layers "F.Cu" "F.Paste" "F.Mask")
      (net 436 "FMC_IO_4_P") (pinfunction "IO_L4P_T0_AD9P_15") (pintype "bidirectional") (die_length 16.927))
    (pad "C20" smd circle (at 6.499 -10.5 180) (size 0.5 0.5) (layers "F.Cu" "F.Paste" "F.Mask")
      (net 9 "GND") (pinfunction "GND") (pintype "passive"))
    (pad "C21" smd circle (at 7.499 -10.5 180) (size 0.5 0.5) (layers "F.Cu" "F.Paste" "F.Mask")
      (net 149 "HOT_SWAP_BUTTON") (pinfunction "IO_L10P_T1_D14_14") (pintype "bidirectional") (die_length 20.52))
    (pad "C22" smd circle (at 8.499 -10.5 180) (size 0.5 0.5) (layers "F.Cu" "F.Paste" "F.Mask")
      (net 72 "USR_LED4") (pinfunction "IO_L7N_T1_D10_14") (pintype "bidirectional") (die_length 20.673))
    (pad "C23" smd circle (at 9.499 -10.5 180) (size 0.5 0.5) (layers "F.Cu" "F.Paste" "F.Mask")
      (net 95 "FCS_B") (pinfunction "IO_L6P_T0_FCS_B_14") (pintype "bidirectional") (die_length 20.723))
    (pad "C24" smd circle (at 10.499 -10.5 180) (size 0.5 0.5) (layers "F.Cu" "F.Paste" "F.Mask")
      (net 126 "AUX_JTAG_TCK") (pinfunction "IO_L6N_T0_D08_VREF_14") (pintype "bidirectional") (die_length 22.056))
    (pad "C25" smd circle (at 11.499 -10.5 180) (size 0.5 0.5) (layers "F.Cu" "F.Paste" "F.Mask")
      (net 143 "3V3_SYS") (pinfunction "VCCO_14") (pintype "passive"))
    (pad "C26" smd circle (at 12.499 -10.5 180) (size 0.5 0.5) (layers "F.Cu" "F.Paste" "F.Mask")
      (net 146 "AUX_JTAG_TDO") (pinfunction "IO_L5N_T0_D07_14") (pintype "bidirectional") (die_length 24.432))
    (pad "D1" smd circle (at -12.5 -9.5 180) (size 0.5 0.5) (layers "F.Cu" "F.Paste" "F.Mask")
      (net 439 "GTX_TX2_N") (pinfunction "MGTXTXN1_116") (pintype "bidirectional") (die_length 15.23))
    (pad "D2" smd circle (at -11.5 -9.5 180) (size 0.5 0.5) (layers "F.Cu" "F.Paste" "F.Mask")
      (net 431 "GTX_TX2_P") (pinfunction "MGTXTXP1_116") (pintype "bidirectional") (die_length 15.219))
    (pad "D3" smd circle (at -10.5 -9.5 180) (size 0.5 0.5) (layers "F.Cu" "F.Paste" "F.Mask")
      (net 306 "1V2_SYS") (pinfunction "MGTAVTT") (pintype "passive"))
    (pad "D4" smd circle (at -9.5 -9.5 180) (size 0.5 0.5) (layers "F.Cu" "F.Paste" "F.Mask")
      (net 9 "GND") (pinfunction "GND") (pintype "passive"))
    (pad "D5" smd circle (at -8.5 -9.5 180) (size 0.5 0.5) (layers "F.Cu" "F.Paste" "F.Mask")
      (net 886 "/FPGA banks 115-116/GTR_REFCLK2_N") (pinfunction "MGTREFCLK0N_116") (pintype "bidirectional") (die_length 13.229))
    (pad "D6" smd circle (at -7.5 -9.5 180) (size 0.5 0.5) (layers "F.Cu" "F.Paste" "F.Mask")
      (net 885 "/FPGA banks 115-116/GTR_REFCLK2_P") (pinfunction "MGTREFCLK0P_116") (pintype "bidirectional") (die_length 13.265))
    (pad "D7" smd circle (at -6.5 -9.5 180) (size 0.5 0.5) (layers "F.Cu" "F.Paste" "F.Mask")
      (net 9 "GND") (pinfunction "GND") (pintype "passive"))
    (pad "D8" smd circle (at -5.5 -9.5 180) (size 0.5 0.5) (layers "F.Cu" "F.Paste" "F.Mask")
      (net 85 "SD_CMD") (pinfunction "IO_L8N_T1_16") (pintype "bidirectional") (die_length 19.972))
    (pad "D9" smd circle (at -4.5 -9.5 180) (size 0.5 0.5) (layers "F.Cu" "F.Paste" "F.Mask")
      (net 86 "SD_DAT3") (pinfunction "IO_L8P_T1_16") (pintype "bidirectional") (die_length 18.666))
    (pad "D10" smd circle (at -3.5 -9.5 180) (size 0.5 0.5) (layers "F.Cu" "F.Paste" "F.Mask")
      (net 84 "SD_CLK") (pinfunction "IO_L12N_T1_MRCC_16") (pintype "bidirectional") (die_length 17.142))
    (pad "D11" smd circle (at -2.5 -9.5 180) (size 0.5 0.5) (layers "F.Cu" "F.Paste" "F.Mask")
      (net 730 "unconnected-(U15E-IO_L14N_T2_SRCC_16-PadD11)") (pinfunction "IO_L14N_T2_SRCC_16") (pintype "bidirectional+no_connect") (die_length 15.596))
    (pad "D12" smd circle (at -1.5 -9.5 180) (size 0.5 0.5) (layers "F.Cu" "F.Paste" "F.Mask")
      (net 143 "3V3_SYS") (pinfunction "VCCO_16") (pintype "passive"))
    (pad "D13" smd circle (at -0.5 -9.5 180) (size 0.5 0.5) (layers "F.Cu" "F.Paste" "F.Mask")
      (net 731 "unconnected-(U15E-IO_L17N_T2_16-PadD13)") (pinfunction "IO_L17N_T2_16") (pintype "bidirectional+no_connect") (die_length 16.197))
    (pad "D14" smd circle (at 0.499 -9.5 180) (size 0.5 0.5) (layers "F.Cu" "F.Paste" "F.Mask")
      (net 732 "unconnected-(U15E-IO_L17P_T2_16-PadD14)") (pinfunction "IO_L17P_T2_16") (pintype "bidirectional+no_connect") (die_length 15.301))
    (pad "D15" smd circle (at 1.499 -9.5 180) (size 0.5 0.5) (layers "F.Cu" "F.Paste" "F.Mask")
      (net 437 "FMC_IO_6_P") (pinfunction "IO_L6P_T0_15") (pintype "bidirectional") (die_length 17.491))
    (pad "D16" smd circle (at 2.499 -9.5 180) (size 0.5 0.5) (layers "F.Cu" "F.Paste" "F.Mask")
      (net 444 "FMC_IO_6_N") (pinfunction "IO_L6N_T0_VREF_15") (pintype "bidirectional") (die_length 17.595))
    (pad "D17" smd circle (at 3.499 -9.5 180) (size 0.5 0.5) (layers "F.Cu" "F.Paste" "F.Mask")
      (net 9 "GND") (pinfunction "GND") (pintype "passive"))
    (pad "D18" smd circle (at 4.499 -9.5 180) (size 0.5 0.5) (layers "F.Cu" "F.Paste" "F.Mask")
      (net 445 "FMC_IO_13_N") (pinfunction "IO_L13N_T2_MRCC_15") (pintype "bidirectional") (die_length 16.746))
    (pad "D19" smd circle (at 5.499 -9.5 180) (size 0.5 0.5) (layers "F.Cu" "F.Paste" "F.Mask")
      (net 446 "FMC_IO_15_P") (pinfunction "IO_L15P_T2_DQS_15") (pintype "bidirectional") (die_length 16.273))
    (pad "D20" smd circle (at 6.499 -9.5 180) (size 0.5 0.5) (layers "F.Cu" "F.Paste" "F.Mask")
      (net 447 "FMC_IO_15_N") (pinfunction "IO_L15N_T2_DQS_ADV_B_15") (pintype "bidirectional") (die_length 16.189))
    (pad "D21" smd circle (at 7.499 -9.5 180) (size 0.5 0.5) (layers "F.Cu" "F.Paste" "F.Mask")
      (net 67 "USR_LED1") (pinfunction "IO_L7P_T1_D09_14") (pintype "bidirectional") (die_length 20.735))
    (pad "D22" smd circle (at 8.499 -9.5 180) (size 0.5 0.5) (layers "F.Cu" "F.Paste" "F.Mask")
      (net 143 "3V3_SYS") (pinfunction "VCCO_14") (pintype "passive"))
    (pad "D23" smd circle (at 9.499 -9.5 180) (size 0.5 0.5) (layers "F.Cu" "F.Paste" "F.Mask")
      (net 786 "HOT_SWAP_GREEN") (pinfunction "IO_L11P_T1_SRCC_14") (pintype "bidirectional") (die_length 20.085))
    (pad "D24" smd circle (at 10.499 -9.5 180) (size 0.5 0.5) (layers "F.Cu" "F.Paste" "F.Mask")
      (net 128 "AUX_JTAG_TDI") (pinfunction "IO_L11N_T1_SRCC_14") (pintype "bidirectional") (die_length 20.314))
    (pad "D25" smd circle (at 11.499 -9.5 180) (size 0.5 0.5) (layers "F.Cu" "F.Paste" "F.Mask")
      (net 131 "AUX_JTAG_TMS") (pinfunction "IO_L15N_T2_DQS_DOUT_CSO_B_14") (pintype "bidirectional") (die_length 20.821))
    (pad "D26" smd circle (at 12.499 -9.5 180) (size 0.5 0.5) (layers "F.Cu" "F.Paste" "F.Mask")
      (net 357 "SDA_3V3") (pinfunction "IO_L5P_T0_D06_14") (pintype "bidirectional") (die_length 24.394))
    (pad "E1" smd circle (at -12.5 -8.5 180) (size 0.5 0.5) (layers "F.Cu" "F.Paste" "F.Mask")
      (net 9 "GND") (pinfunction "GND") (pintype "passive"))
    (pad "E2" smd circle (at -11.5 -8.5 180) (size 0.5 0.5) (layers "F.Cu" "F.Paste" "F.Mask")
      (net 9 "GND") (pinfunction "GND") (pintype "passive"))
    (pad "E3" smd circle (at -10.5 -8.5 180) (size 0.5 0.5) (layers "F.Cu" "F.Paste" "F.Mask")
      (net 635 "GTX_RX2_N") (pinfunction "MGTXRXN1_116") (pintype "bidirectional") (die_length 13.353))
    (pad "E4" smd circle (at -9.5 -8.5 180) (size 0.5 0.5) (layers "F.Cu" "F.Paste" "F.Mask")
      (net 634 "GTX_RX2_P") (pinfunction "MGTXRXP1_116") (pintype "bidirectional") (die_length 13.435))
    (pad "E5" smd circle (at -8.5 -8.5 180) (size 0.5 0.5) (layers "F.Cu" "F.Paste" "F.Mask")
      (net 9 "GND") (pinfunction "GND") (pintype "passive"))
    (pad "E6" smd circle (at -7.5 -8.5 180) (size 0.5 0.5) (layers "F.Cu" "F.Paste" "F.Mask")
      (net 147 "1V0_SYS") (pinfunction "MGTAVCC") (pintype "passive"))
    (pad "E7" smd circle (at -6.5 -8.5 180) (size 0.5 0.5) (layers "F.Cu" "F.Paste" "F.Mask")
      (net 9 "GND") (pinfunction "GND") (pintype "passive"))
    (pad "E8" smd circle (at -5.5 -8.5 180) (size 0.5 0.5) (layers "F.Cu" "F.Paste" "F.Mask")
      (net 144 "1V8_SYS") (pinfunction "VCCBATT_0") (pintype "power_in"))
    (pad "E9" smd circle (at -4.5 -8.5 180) (size 0.5 0.5) (layers "F.Cu" "F.Paste" "F.Mask")
      (net 143 "3V3_SYS") (pinfunction "VCCO_16") (pintype "passive"))
    (pad "E10" smd circle (at -3.5 -8.5 180) (size 0.5 0.5) (layers "F.Cu" "F.Paste" "F.Mask")
      (net 83 "SD_DAT0") (pinfunction "IO_L12P_T1_MRCC_16") (pintype "bidirectional") (die_length 17.165))
    (pad "E11" smd circle (at -2.5 -8.5 180) (size 0.5 0.5) (layers "F.Cu" "F.Paste" "F.Mask")
      (net 733 "unconnected-(U15E-IO_L14P_T2_SRCC_16-PadE11)") (pinfunction "IO_L14P_T2_SRCC_16") (pintype "bidirectional+no_connect") (die_length 15.195))
    (pad "E12" smd circle (at -1.5 -8.5 180) (size 0.5 0.5) (layers "F.Cu" "F.Paste" "F.Mask")
      (net 734 "unconnected-(U15E-IO_L18N_T2_16-PadE12)") (pinfunction "IO_L18N_T2_16") (pintype "bidirectional+no_connect") (die_length 14.446))
    (pad "E13" smd circle (at -0.5 -8.5 180) (size 0.5 0.5) (layers "F.Cu" "F.Paste" "F.Mask")
      (net 735 "unconnected-(U15E-IO_L18P_T2_16-PadE13)") (pinfunction "IO_L18P_T2_16") (pintype "bidirectional+no_connect") (die_length 14.156))
    (pad "E14" smd circle (at 0.499 -8.5 180) (size 0.5 0.5) (layers "F.Cu" "F.Paste" "F.Mask")
      (net 9 "GND") (pinfunction "GND") (pintype "passive"))
    (pad "E15" smd circle (at 1.499 -8.5 180) (size 0.5 0.5) (layers "F.Cu" "F.Paste" "F.Mask")
      (net 448 "FMC_IO_10_P") (pinfunction "IO_L10P_T1_AD4P_15") (pintype "bidirectional") (die_length 18.592))
    (pad "E16" smd circle (at 2.499 -8.5 180) (size 0.5 0.5) (layers "F.Cu" "F.Paste" "F.Mask")
      (net 456 "FMC_IO_10_N") (pinfunction "IO_L10N_T1_AD4N_15") (pintype "bidirectional") (die_length 18.741))
    (pad "E17" smd circle (at 3.499 -8.5 180) (size 0.5 0.5) (layers "F.Cu" "F.Paste" "F.Mask")
      (net 457 "FMC_IO_12_N") (pinfunction "IO_L12N_T1_MRCC_AD5N_15") (pintype "bidirectional") (die_length 14.038))
    (pad "E18" smd circle (at 4.499 -8.5 180) (size 0.5 0.5) (layers "F.Cu" "F.Paste" "F.Mask")
      (net 458 "FMC_IO_13_P") (pinfunction "IO_L13P_T2_MRCC_15") (pintype "bidirectional") (die_length 17.01))
    (pad "E19" smd circle (at 5.499 -8.5 180) (size 0.5 0.5) (layers "F.Cu" "F.Paste" "F.Mask")
      (net 143 "3V3_SYS") (pinfunction "VCCO_15") (pintype "passive"))
    (pad "E20" smd circle (at 6.499 -8.5 180) (size 0.5 0.5) (layers "F.Cu" "F.Paste" "F.Mask")
      (net 459 "FMC_IO_17_N") (pinfunction "IO_L17N_T2_A25_15") (pintype "bidirectional") (die_length 13.703))
    (pad "E21" smd circle (at 7.499 -8.5 180) (size 0.5 0.5) (layers "F.Cu" "F.Paste" "F.Mask")
      (net 788 "HOT_SWAP_RED") (pinfunction "IO_L9P_T1_DQS_14") (pintype "bidirectional") (die_length 20.497))
    (pad "E22" smd circle (at 8.499 -8.5 180) (size 0.5 0.5) (layers "F.Cu" "F.Paste" "F.Mask")
      (net 74 "USR_LED5") (pinfunction "IO_L9N_T1_DQS_D13_14") (pintype "bidirectional") (die_length 20.469))
    (pad "E23" smd circle (at 9.499 -8.5 180) (size 0.5 0.5) (layers "F.Cu" "F.Paste" "F.Mask")
      (net 751 "PRSNT_M2C") (pinfunction "IO_L12N_T1_MRCC_14") (pintype "bidirectional") (die_length 19.664))
    (pad "E24" smd circle (at 10.499 -8.5 180) (size 0.5 0.5) (layers "F.Cu" "F.Paste" "F.Mask")
      (net 9 "GND") (pinfunction "GND") (pintype "passive"))
    (pad "E25" smd circle (at 11.499 -8.5 180) (size 0.5 0.5) (layers "F.Cu" "F.Paste" "F.Mask")
      (net 358 "SCL_3V3") (pinfunction "IO_L15P_T2_DQS_RDWR_B_14") (pintype "bidirectional") (die_length 20.423))
    (pad "E26" smd circle (at 12.499 -8.5 180) (size 0.5 0.5) (layers "F.Cu" "F.Paste" "F.Mask")
      (net 137 "UART0_TX") (pinfunction "IO_L17N_T2_A13_D29_14") (pintype "bidirectional") (die_length 20.928))
    (pad "F1" smd circle (at -12.5 -7.5 180) (size 0.5 0.5) (layers "F.Cu" "F.Paste" "F.Mask")
      (net 463 "GTX_TX3_N") (pinfunction "MGTXTXN0_116") (pintype "bidirectional") (die_length 14.583))
    (pad "F2" smd circle (at -11.5 -7.5 180) (size 0.5 0.5) (layers "F.Cu" "F.Paste" "F.Mask")
      (net 450 "GTX_TX3_P") (pinfunction "MGTXTXP0_116") (pintype "bidirectional") (die_length 14.603))
    (pad "F3" smd circle (at -10.5 -7.5 180) (size 0.5 0.5) (layers "F.Cu" "F.Paste" "F.Mask")
      (net 9 "GND") (pinfunction "GND") (pintype "passive"))
    (pad "F4" smd circle (at -9.5 -7.5 180) (size 0.5 0.5) (layers "F.Cu" "F.Paste" "F.Mask")
      (net 9 "GND") (pinfunction "GND") (pintype "passive"))
    (pad "F5" smd circle (at -8.5 -7.5 180) (size 0.5 0.5) (layers "F.Cu" "F.Paste" "F.Mask")
      (net 888 "/FPGA banks 115-116/GTR_REFCLK3_N") (pinfunction "MGTREFCLK1N_116") (pintype "bidirectional") (die_length 12.724))
    (pad "F6" smd circle (at -7.5 -7.5 180) (size 0.5 0.5) (layers "F.Cu" "F.Paste" "F.Mask")
      (net 887 "/FPGA banks 115-116/GTR_REFCLK3_P") (pinfunction "MGTREFCLK1P_116") (pintype "bidirectional") (die_length 13.203))
    (pad "F7" smd circle (at -6.5 -7.5 180) (size 0.5 0.5) (layers "F.Cu" "F.Paste" "F.Mask")
      (net 9 "GND") (pinfunction "GND") (pintype "passive"))
    (pad "F8" smd circle (at -5.5 -7.5 180) (size 0.5 0.5) (layers "F.Cu" "F.Paste" "F.Mask")
      (net 82 "SD_DAT1") (pinfunction "IO_L7N_T1_16") (pintype "bidirectional") (die_length 17.801))
    (pad "F9" smd circle (at -4.5 -7.5 180) (size 0.5 0.5) (layers "F.Cu" "F.Paste" "F.Mask")
      (net 88 "SD_CD") (pinfunction "IO_L7P_T1_16") (pintype "bidirectional") (die_length 16.924))
    (pad "F10" smd circle (at -3.5 -7.5 180) (size 0.5 0.5) (layers "F.Cu" "F.Paste" "F.Mask")
      (net 742 "unconnected-(U15E-IO_L11N_T1_SRCC_16-PadF10)") (pinfunction "IO_L11N_T1_SRCC_16") (pintype "bidirectional+no_connect") (die_length 15.436))
    (pad "F11" smd circle (at -2.5 -7.5 180) (size 0.5 0.5) (layers "F.Cu" "F.Paste" "F.Mask")
      (net 9 "GND") (pinfunction "GND") (pintype "passive"))
    (pad "F12" smd circle (at -1.5 -7.5 180) (size 0.5 0.5) (layers "F.Cu" "F.Paste" "F.Mask")
      (net 743 "unconnected-(U15E-IO_L16N_T2_16-PadF12)") (pinfunction "IO_L16N_T2_16") (pintype "bidirectional+no_connect") (die_length 13.211))
    (pad "F13" smd circle (at -0.5 -7.5 180) (size 0.5 0.5) (layers "F.Cu" "F.Paste" "F.Mask")
      (net 744 "unconnected-(U15E-IO_L15N_T2_DQS_16-PadF13)") (pinfunction "IO_L15N_T2_DQS_16") (pintype "bidirectional+no_connect") (die_length 15.248))
    (pad "F14" smd circle (at 0.499 -7.5 180) (size 0.5 0.5) (layers "F.Cu" "F.Paste" "F.Mask")
      (net 745 "unconnected-(U15E-IO_L15P_T2_DQS_16-PadF14)") (pinfunction "IO_L15P_T2_DQS_16") (pintype "bidirectional+no_connect") (die_length 15.557))
    (pad "F15" smd circle (at 1.499 -7.5 180) (size 0.5 0.5) (layers "F.Cu" "F.Paste" "F.Mask")
      (net 460 "FMC_IO_8_N") (pinfunction "IO_L8N_T1_AD3N_15") (pintype "bidirectional") (die_length 18.872))
    (pad "F16" smd circle (at 2.499 -7.5 180) (size 0.5 0.5) (layers "F.Cu" "F.Paste" "F.Mask")
      (net 143 "3V3_SYS") (pinfunction "VCCO_15") (pintype "passive"))
    (pad "F17" smd circle (at 3.499 -7.5 180) (size 0.5 0.5) (layers "F.Cu" "F.Paste" "F.Mask")
      (net 472 "FMC_IO_12_P") (pinfunction "IO_L12P_T1_MRCC_AD5P_15") (pintype "bidirectional") (die_length 13.832))
    (pad "F18" smd circle (at 4.499 -7.5 180) (size 0.5 0.5) (layers "F.Cu" "F.Paste" "F.Mask")
      (net 473 "FMC_IO_11_N") (pinfunction "IO_L11N_T1_SRCC_AD12N_15") (pintype "bidirectional") (die_length 12.908))
    (pad "F19" smd circle (at 5.499 -7.5 180) (size 0.5 0.5) (layers "F.Cu" "F.Paste" "F.Mask")
      (net 474 "FMC_IO_17_P") (pinfunction "IO_L17P_T2_A26_15") (pintype "bidirectional") (die_length 14.191))
    (pad "F20" smd circle (at 6.499 -7.5 180) (size 0.5 0.5) (layers "F.Cu" "F.Paste" "F.Mask")
      (net 475 "FMC_IO_16_N") (pinfunction "IO_L16N_T2_A27_15") (pintype "bidirectional") (die_length 12.487))
    (pad "F21" smd circle (at 7.499 -7.5 180) (size 0.5 0.5) (layers "F.Cu" "F.Paste" "F.Mask")
      (net 9 "GND") (pinfunction "GND") (pintype "passive"))
    (pad "F22" smd circle (at 8.499 -7.5 180) (size 0.5 0.5) (layers "F.Cu" "F.Paste" "F.Mask")
      (net 746 "unconnected-(U15C-IO_L12P_T1_MRCC_14-PadF22)") (pinfunction "IO_L12P_T1_MRCC_14") (pintype "bidirectional+no_connect") (die_length 19.515))
    (pad "F23" smd circle (at 9.499 -7.5 180) (size 0.5 0.5) (layers "F.Cu" "F.Paste" "F.Mask")
      (net 747 "unconnected-(U15C-IO_L13N_T2_MRCC_14-PadF23)") (pinfunction "IO_L13N_T2_MRCC_14") (pintype "bidirectional+no_connect") (die_length 17.933))
    (pad "F24" smd circle (at 10.499 -7.5 180) (size 0.5 0.5) (layers "F.Cu" "F.Paste" "F.Mask")
      (net 449 "CLK_DIR") (pinfunction "IO_L14N_T2_SRCC_14") (pintype "bidirectional") (die_length 19.105))
    (pad "F25" smd circle (at 11.499 -7.5 180) (size 0.5 0.5) (layers "F.Cu" "F.Paste" "F.Mask")
      (net 135 "UART0_RX") (pinfunction "IO_L17P_T2_A14_D30_14") (pintype "bidirectional") (die_length 19.892))
    (pad "F26" smd circle (at 12.499 -7.5 180) (size 0.5 0.5) (layers "F.Cu" "F.Paste" "F.Mask")
      (net 143 "3V3_SYS") (pinfunction "VCCO_14") (pintype "passive"))
    (pad "G1" smd circle (at -12.5 -6.5 180) (size 0.5 0.5) (layers "F.Cu" "F.Paste" "F.Mask")
      (net 9 "GND") (pinfunction "GND") (pintype "passive"))
    (pad "G2" smd circle (at -11.5 -6.5 180) (size 0.5 0.5) (layers "F.Cu" "F.Paste" "F.Mask")
      (net 306 "1V2_SYS") (pinfunction "MGTAVTT") (pintype "passive"))
    (pad "G3" smd circle (at -10.5 -6.5 180) (size 0.5 0.5) (layers "F.Cu" "F.Paste" "F.Mask")
      (net 637 "GTX_RX3_N") (pinfunction "MGTXRXN0_116") (pintype "bidirectional") (die_length 12.486))
    (pad "G4" smd circle (at -9.5 -6.5 180) (size 0.5 0.5) (layers "F.Cu" "F.Paste" "F.Mask")
      (net 636 "GTX_RX3_P") (pinfunction "MGTXRXP0_116") (pintype "bidirectional") (die_length 12.584))
    (pad "G5" smd circle (at -8.5 -6.5 180) (size 0.5 0.5) (layers "F.Cu" "F.Paste" "F.Mask")
      (net 9 "GND") (pinfunction "GND") (pintype "passive"))
    (pad "G6" smd circle (at -7.5 -6.5 180) (size 0.5 0.5) (layers "F.Cu" "F.Paste" "F.Mask")
      (net 147 "1V0_SYS") (pinfunction "MGTAVCC") (pintype "passive"))
    (pad "G7" smd circle (at -6.5 -6.5 180) (size 0.5 0.5) (layers "F.Cu" "F.Paste" "F.Mask")
      (net 93 "INIT_B") (pinfunction "INIT_B_0") (pintype "bidirectional") (die_length 30.602))
    (pad "G8" smd circle (at -5.5 -6.5 180) (size 0.5 0.5) (layers "F.Cu" "F.Paste" "F.Mask")
      (net 9 "GND") (pinfunction "GND") (pintype "passive"))
    (pad "G9" smd circle (at -4.5 -6.5 180) (size 0.5 0.5) (layers "F.Cu" "F.Paste" "F.Mask")
      (net 748 "unconnected-(U15E-IO_L2N_T0_16-PadG9)") (pinfunction "IO_L2N_T0_16") (pintype "bidirectional+no_connect") (die_length 14.946))
    (pad "G10" smd circle (at -3.5 -6.5 180) (size 0.5 0.5) (layers "F.Cu" "F.Paste" "F.Mask")
      (net 749 "unconnected-(U15E-IO_L2P_T0_16-PadG10)") (pinfunction "IO_L2P_T0_16") (pintype "bidirectional+no_connect") (die_length 13.481))
    (pad "G11" smd circle (at -2.5 -6.5 180) (size 0.5 0.5) (layers "F.Cu" "F.Paste" "F.Mask")
      (net 750 "unconnected-(U15E-IO_L11P_T1_SRCC_16-PadG11)") (pinfunction "IO_L11P_T1_SRCC_16") (pintype "bidirectional+no_connect") (die_length 14.905))
    (pad "G12" smd circle (at -1.5 -6.5 180) (size 0.5 0.5) (layers "F.Cu" "F.Paste" "F.Mask")
      (net 752 "unconnected-(U15E-IO_L16P_T2_16-PadG12)") (pinfunction "IO_L16P_T2_16") (pintype "bidirectional+no_connect") (die_length 13.211))
    (pad "G13" smd circle (at -0.5 -6.5 180) (size 0.5 0.5) (layers "F.Cu" "F.Paste" "F.Mask")
      (net 143 "3V3_SYS") (pinfunction "VCCO_16") (pintype "passive"))
    (pad "G14" smd circle (at 0.499 -6.5 180) (size 0.5 0.5) (layers "F.Cu" "F.Paste" "F.Mask")
      (net 753 "unconnected-(U15E-IO_L5N_T0_16-PadG14)") (pinfunction "IO_L5N_T0_16") (pintype "bidirectional+no_connect") (die_length 10.327))
    (pad "G15" smd circle (at 1.499 -6.5 180) (size 0.5 0.5) (layers "F.Cu" "F.Paste" "F.Mask")
      (net 476 "FMC_IO_8_P") (pinfunction "IO_L8P_T1_AD3P_15") (pintype "bidirectional") (die_length 19.124))
    (pad "G16" smd circle (at 2.499 -6.5 180) (size 0.5 0.5) (layers "F.Cu" "F.Paste" "F.Mask")
      (net 490 "FMC_IO_7_N") (pinfunction "IO_L7N_T1_AD10N_15") (pintype "bidirectional") (die_length 13.719))
    (pad "G17" smd circle (at 3.499 -6.5 180) (size 0.5 0.5) (layers "F.Cu" "F.Paste" "F.Mask")
      (net 491 "FMC_IO_11_P") (pinfunction "IO_L11P_T1_SRCC_AD12P_15") (pintype "bidirectional") (die_length 12.537))
    (pad "G18" smd circle (at 4.499 -6.5 180) (size 0.5 0.5) (layers "F.Cu" "F.Paste" "F.Mask")
      (net 9 "GND") (pinfunction "GND") (pintype "passive"))
    (pad "G19" smd circle (at 5.499 -6.5 180) (size 0.5 0.5) (layers "F.Cu" "F.Paste" "F.Mask")
      (net 492 "FMC_IO_16_P") (pinfunction "IO_L16P_T2_A28_15") (pintype "bidirectional") (die_length 12.445))
    (pad "G20" smd circle (at 6.499 -6.5 180) (size 0.5 0.5) (layers "F.Cu" "F.Paste" "F.Mask")
      (net 493 "FMC_IO_18_N") (pinfunction "IO_L18N_T2_A23_15") (pintype "bidirectional") (die_length 11.544))
    (pad "G21" smd circle (at 7.499 -6.5 180) (size 0.5 0.5) (layers "F.Cu" "F.Paste" "F.Mask")
      (net 758 "unconnected-(U15C-IO_L19N_T3_A09_D25_VREF_14-PadG21)") (pinfunction "IO_L19N_T3_A09_D25_VREF_14") (pintype "bidirectional+no_connect") (die_length 18.813))
    (pad "G22" smd circle (at 8.499 -6.5 180) (size 0.5 0.5) (layers "F.Cu" "F.Paste" "F.Mask")
      (net 759 "unconnected-(U15C-IO_L13P_T2_MRCC_14-PadG22)") (pinfunction "IO_L13P_T2_MRCC_14") (pintype "bidirectional+no_connect") (die_length 18.389))
    (pad "G23" smd circle (at 9.499 -6.5 180) (size 0.5 0.5) (layers "F.Cu" "F.Paste" "F.Mask")
      (net 143 "3V3_SYS") (pinfunction "VCCO_14") (pintype "passive"))
    (pad "G24" smd circle (at 10.499 -6.5 180) (size 0.5 0.5) (layers "F.Cu" "F.Paste" "F.Mask")
      (net 908 "FMC_SDA_3V3") (pinfunction "IO_L14P_T2_SRCC_14") (pintype "bidirectional") (die_length 19.02))
    (pad "G25" smd circle (at 11.499 -6.5 180) (size 0.5 0.5) (layers "F.Cu" "F.Paste" "F.Mask")
      (net 133 "AUX_JTAG_RST") (pinfunction "IO_L16P_T2_CSI_B_14") (pintype "bidirectional") (die_length 19.777))
    (pad "G26" smd circle (at 12.499 -6.5 180) (size 0.5 0.5) (layers "F.Cu" "F.Paste" "F.Mask")
      (net 804 "FPGA_POWER_CYCLE") (pinfunction "IO_L16N_T2_A15_D31_14") (pintype "bidirectional") (die_length 19.839))
    (pad "H1" smd circle (at -12.5 -5.5 180) (size 0.5 0.5) (layers "F.Cu" "F.Paste" "F.Mask")
      (net 479 "GTX_TX4_N") (pinfunction "MGTXTXN3_115") (pintype "bidirectional") (die_length 13.778))
    (pad "H2" smd circle (at -11.5 -5.5 180) (size 0.5 0.5) (layers "F.Cu" "F.Paste" "F.Mask")
      (net 465 "GTX_TX4_P") (pinfunction "MGTXTXP3_115") (pintype "bidirectional") (die_length 13.817))
    (pad "H3" smd circle (at -10.5 -5.5 180) (size 0.5 0.5) (layers "F.Cu" "F.Paste" "F.Mask")
      (net 306 "1V2_SYS") (pinfunction "MGTAVTT") (pintype "passive"))
    (pad "H4" smd circle (at -9.5 -5.5 180) (size 0.5 0.5) (layers "F.Cu" "F.Paste" "F.Mask")
      (net 9 "GND") (pinfunction "GND") (pintype "passive"))
    (pad "H5" smd circle (at -8.5 -5.5 180) (size 0.5 0.5) (layers "F.Cu" "F.Paste" "F.Mask")
      (net 409 "/FPGA banks 115-116/GTR_REFCLK0_N") (pinfunction "MGTREFCLK0N_115") (pintype "bidirectional") (die_length 11.598))
    (pad "H6" smd circle (at -7.5 -5.5 180) (size 0.5 0.5) (layers "F.Cu" "F.Paste" "F.Mask")
      (net 404 "/FPGA banks 115-116/GTR_REFCLK0_P") (pinfunction "MGTREFCLK0P_115") (pintype "bidirectional") (die_length 11.559))
    (pad "H7" smd circle (at -6.5 -5.5 180) (size 0.5 0.5) (layers "F.Cu" "F.Paste" "F.Mask")
      (net 9 "GND") (pinfunction "GND") (pintype "passive"))
    (pad "H8" smd circle (at -5.5 -5.5 180) (size 0.5 0.5) (layers "F.Cu" "F.Paste" "F.Mask")
      (net 760 "unconnected-(U15E-IO_L1N_T0_16-PadH8)") (pinfunction "IO_L1N_T0_16") (pintype "bidirectional+no_connect") (die_length 16.747))
    (pad "H9" smd circle (at -4.5 -5.5 180) (size 0.5 0.5) (layers "F.Cu" "F.Paste" "F.Mask")
      (net 761 "unconnected-(U15E-IO_L1P_T0_16-PadH9)") (pinfunction "IO_L1P_T0_16") (pintype "bidirectional+no_connect") (die_length 15.601))
    (pad "H10" smd circle (at -3.5 -5.5 180) (size 0.5 0.5) (layers "F.Cu" "F.Paste" "F.Mask")
      (net 143 "3V3_SYS") (pinfunction "VCCO_16") (pintype "passive"))
    (pad "H11" smd circle (at -2.5 -5.5 180) (size 0.5 0.5) (layers "F.Cu" "F.Paste" "F.Mask")
      (net 762 "unconnected-(U15E-IO_L6N_T0_VREF_16-PadH11)") (pinfunction "IO_L6N_T0_VREF_16") (pintype "bidirectional+no_connect") (die_length 14.821))
    (pad "H12" smd circle (at -1.5 -5.5 180) (size 0.5 0.5) (layers "F.Cu" "F.Paste" "F.Mask")
      (net 763 "unconnected-(U15E-IO_L6P_T0_16-PadH12)") (pinfunction "IO_L6P_T0_16") (pintype "bidirectional+no_connect") (die_length 13.516))
    (pad "H13" smd circle (at -0.5 -5.5 180) (size 0.5 0.5) (layers "F.Cu" "F.Paste" "F.Mask")
      (net 764 "unconnected-(U15E-IO_L3N_T0_DQS_16-PadH13)") (pinfunction "IO_L3N_T0_DQS_16") (pintype "bidirectional+no_connect") (die_length 12.402))
    (pad "H14" smd circle (at 0.499 -5.5 180) (size 0.5 0.5) (layers "F.Cu" "F.Paste" "F.Mask")
      (net 765 "unconnected-(U15E-IO_L5P_T0_16-PadH14)") (pinfunction "IO_L5P_T0_16") (pintype "bidirectional+no_connect") (die_length 10.698))
    (pad "H15" smd circle (at 1.499 -5.5 180) (size 0.5 0.5) (layers "F.Cu" "F.Paste" "F.Mask")
      (net 9 "GND") (pinfunction "GND") (pintype "passive"))
    (pad "H16" smd circle (at 2.499 -5.5 180) (size 0.5 0.5) (layers "F.Cu" "F.Paste" "F.Mask")
      (net 505 "FMC_IO_7_P") (pinfunction "IO_L7P_T1_AD10P_15") (pintype "bidirectional") (die_length 14.081))
    (pad "H17" smd circle (at 3.499 -5.5 180) (size 0.5 0.5) (layers "F.Cu" "F.Paste" "F.Mask")
      (net 506 "FMC_IO_14_P") (pinfunction "IO_L14P_T2_SRCC_15") (pintype "bidirectional") (die_length 11.166))
    (pad "H18" smd circle (at 4.499 -5.5 180) (size 0.5 0.5) (layers "F.Cu" "F.Paste" "F.Mask")
      (net 507 "FMC_IO_14_N") (pinfunction "IO_L14N_T2_SRCC_15") (pintype "bidirectional") (die_length 11.108))
    (pad "H19" smd circle (at 5.499 -5.5 180) (size 0.5 0.5) (layers "F.Cu" "F.Paste" "F.Mask")
      (net 514 "FMC_IO_18_P") (pinfunction "IO_L18P_T2_A24_15") (pintype "bidirectional") (die_length 11.791))
    (pad "H20" smd circle (at 6.499 -5.5 180) (size 0.5 0.5) (layers "F.Cu" "F.Paste" "F.Mask")
      (net 143 "3V3_SYS") (pinfunction "VCCO_15") (pintype "passive"))
    (pad "H21" smd circle (at 7.499 -5.5 180) (size 0.5 0.5) (layers "F.Cu" "F.Paste" "F.Mask")
      (net 766 "unconnected-(U15C-IO_L19P_T3_A10_D26_14-PadH21)") (pinfunction "IO_L19P_T3_A10_D26_14") (pintype "bidirectional+no_connect") (die_length 18.685))
    (pad "H22" smd circle (at 8.499 -5.5 180) (size 0.5 0.5) (layers "F.Cu" "F.Paste" "F.Mask")
      (net 907 "FMC_SCL_3V3") (pinfunction "IO_L21N_T3_DQS_A06_D22_14") (pintype "bidirectional") (die_length 20.841))
    (pad "H23" smd circle (at 9.499 -5.5 180) (size 0.5 0.5) (layers "F.Cu" "F.Paste" "F.Mask")
      (net 767 "unconnected-(U15C-IO_L20P_T3_A08_D24_14-PadH23)") (pinfunction "IO_L20P_T3_A08_D24_14") (pintype "bidirectional+no_connect") (die_length 18.73))
    (pad "H24" smd circle (at 10.499 -5.5 180) (size 0.5 0.5) (layers "F.Cu" "F.Paste" "F.Mask")
      (net 768 "unconnected-(U15C-IO_L20N_T3_A07_D23_14-PadH24)") (pinfunction "IO_L20N_T3_A07_D23_14") (pintype "bidirectional+no_connect") (die_length 17.912))
    (pad "H25" smd circle (at 11.499 -5.5 180) (size 0.5 0.5) (layers "F.Cu" "F.Paste" "F.Mask")
      (net 9 "GND") (pinfunction "GND") (pintype "passive"))
    (pad "H26" smd circle (at 12.499 -5.5 180) (size 0.5 0.5) (layers "F.Cu" "F.Paste" "F.Mask")
      (net 800 "FPGA_VTT_CNTL") (pinfunction "IO_L18N_T2_A11_D27_14") (pintype "bidirectional") (die_length 19.909))
    (pad "J1" smd circle (at -12.5 -4.5 180) (size 0.5 0.5) (layers "F.Cu" "F.Paste" "F.Mask")
      (net 9 "GND") (pinfunction "GND") (pintype "passive"))
    (pad "J2" smd circle (at -11.5 -4.5 180) (size 0.5 0.5) (layers "F.Cu" "F.Paste" "F.Mask")
      (net 9 "GND") (pinfunction "GND") (pintype "passive"))
    (pad "J3" smd circle (at -10.5 -4.5 180) (size 0.5 0.5) (layers "F.Cu" "F.Paste" "F.Mask")
      (net 639 "GTX_RX4_N") (pinfunction "MGTXRXN3_115") (pintype "bidirectional") (die_length 11.806))
    (pad "J4" smd circle (at -9.5 -4.5 180) (size 0.5 0.5) (layers "F.Cu" "F.Paste" "F.Mask")
      (net 638 "GTX_RX4_P") (pinfunction "MGTXRXP3_115") (pintype "bidirectional") (die_length 11.935))
    (pad "J5" smd circle (at -8.5 -4.5 180) (size 0.5 0.5) (layers "F.Cu" "F.Paste" "F.Mask")
      (net 9 "GND") (pinfunction "GND") (pintype "passive"))
    (pad "J6" smd circle (at -7.5 -4.5 180) (size 0.5 0.5) (layers "F.Cu" "F.Paste" "F.Mask")
      (net 147 "1V0_SYS") (pinfunction "MGTAVCC") (pintype "passive"))
    (pad "J7" smd circle (at -6.5 -4.5 180) (size 0.5 0.5) (layers "F.Cu" "F.Paste" "F.Mask")
      (net 25 "DONE") (pinfunction "DONE_0") (pintype "bidirectional") (die_length 33.726))
    (pad "J8" smd circle (at -5.5 -4.5 180) (size 0.5 0.5) (layers "F.Cu" "F.Paste" "F.Mask")
      (net 769 "unconnected-(U15E-IO_0_16-PadJ8)") (pinfunction "IO_0_16") (pintype "bidirectional+no_connect") (die_length 17.143))
    (pad "J9" smd circle (at -4.5 -4.5 180) (size 0.5 0.5) (layers "F.Cu" "F.Paste" "F.Mask")
      (net 147 "1V0_SYS") (pinfunction "VCCINT") (pintype "power_in"))
    (pad "J10" smd circle (at -3.5 -4.5 180) (size 0.5 0.5) (layers "F.Cu" "F.Paste" "F.Mask")
      (net 770 "unconnected-(U15E-IO_L4N_T0_16-PadJ10)") (pinfunction "IO_L4N_T0_16") (pintype "bidirectional+no_connect") (die_length 16.988))
    (pad "J11" smd circle (at -2.5 -4.5 180) (size 0.5 0.5) (layers "F.Cu" "F.Paste" "F.Mask")
      (net 771 "unconnected-(U15E-IO_L4P_T0_16-PadJ11)") (pinfunction "IO_L4P_T0_16") (pintype "bidirectional+no_connect") (die_length 16.441))
    (pad "J12" smd circle (at -1.5 -4.5 180) (size 0.5 0.5) (layers "F.Cu" "F.Paste" "F.Mask")
      (net 9 "GND") (pinfunction "GND") (pintype "passive"))
    (pad "J13" smd circle (at -0.5 -4.5 180) (size 0.5 0.5) (layers "F.Cu" "F.Paste" "F.Mask")
      (net 772 "unconnected-(U15E-IO_L3P_T0_DQS_16-PadJ13)") (pinfunction "IO_L3P_T0_DQS_16") (pintype "bidirectional+no_connect") (die_length 12.775))
    (pad "J14" smd circle (at 0.499 -4.5 180) (size 0.5 0.5) (layers "F.Cu" "F.Paste" "F.Mask")
      (net 773 "unconnected-(U15E-IO_25_16-PadJ14)") (pinfunction "IO_25_16") (pintype "bidirectional+no_connect") (die_length 13.82))
    (pad "J15" smd circle (at 1.499 -4.5 180) (size 0.5 0.5) (layers "F.Cu" "F.Paste" "F.Mask")
      (net 515 "FMC_IO_9_P") (pinfunction "IO_L9P_T1_DQS_AD11P_15") (pintype "bidirectional") (die_length 15.384))
    (pad "J16" smd circle (at 2.499 -4.5 180) (size 0.5 0.5) (layers "F.Cu" "F.Paste" "F.Mask")
      (net 516 "FMC_IO_9_N") (pinfunction "IO_L9N_T1_DQS_AD11N_15") (pintype "bidirectional") (die_length 14.742))
    (pad "J17" smd circle (at 3.499 -4.5 180) (size 0.5 0.5) (layers "F.Cu" "F.Paste" "F.Mask")
      (net 143 "3V3_SYS") (pinfunction "VCCO_15") (pintype "passive"))
    (pad "J18" smd circle (at 4.499 -4.5 180) (size 0.5 0.5) (layers "F.Cu" "F.Paste" "F.Mask")
      (net 517 "FMC_IO_20_P") (pinfunction "IO_L20P_T3_A20_15") (pintype "bidirectional") (die_length 11.906))
    (pad "J19" smd circle (at 5.499 -4.5 180) (size 0.5 0.5) (layers "F.Cu" "F.Paste" "F.Mask")
      (net 518 "FMC_IO_20_N") (pinfunction "IO_L20N_T3_A19_15") (pintype "bidirectional") (die_length 11.025))
    (pad "J20" smd circle (at 6.499 -4.5 180) (size 0.5 0.5) (layers "F.Cu" "F.Paste" "F.Mask")
      (net 528 "FMC_IO_19_N") (pinfunction "IO_L19N_T3_A21_VREF_15") (pintype "bidirectional") (die_length 9.831))
    (pad "J21" smd circle (at 7.499 -4.5 180) (size 0.5 0.5) (layers "F.Cu" "F.Paste" "F.Mask")
      (net 774 "unconnected-(U15C-IO_L21P_T3_DQS_14-PadJ21)") (pinfunction "IO_L21P_T3_DQS_14") (pintype "bidirectional+no_connect") (die_length 21.288))
    (pad "J22" smd circle (at 8.499 -4.5 180) (size 0.5 0.5) (layers "F.Cu" "F.Paste" "F.Mask")
      (net 9 "GND") (pinfunction "GND") (pintype "passive"))
    (pad "J23" smd circle (at 9.499 -4.5 180) (size 0.5 0.5) (layers "F.Cu" "F.Paste" "F.Mask")
      (net 775 "unconnected-(U15C-IO_L24N_T3_A00_D16_14-PadJ23)") (pinfunction "IO_L24N_T3_A00_D16_14") (pintype "bidirectional+no_connect") (die_length 18.062))
    (pad "J24" smd circle (at 10.499 -4.5 180) (size 0.5 0.5) (layers "F.Cu" "F.Paste" "F.Mask")
      (net 776 "unconnected-(U15C-IO_L22P_T3_A05_D21_14-PadJ24)") (pinfunction "IO_L22P_T3_A05_D21_14") (pintype "bidirectional+no_connect") (die_length 17.661))
    (pad "J25" smd circle (at 11.499 -4.5 180) (size 0.5 0.5) (layers "F.Cu" "F.Paste" "F.Mask")
      (net 777 "unconnected-(U15C-IO_L22N_T3_A04_D20_14-PadJ25)") (pinfunction "IO_L22N_T3_A04_D20_14") (pintype "bidirectional+no_connect") (die_length 17.645))
    (pad "J26" smd circle (at 12.499 -4.5 180) (size 0.5 0.5) (layers "F.Cu" "F.Paste" "F.Mask")
      (net 799 "FPGA_SLP_S4") (pinfunction "IO_L18P_T2_A12_D28_14") (pintype "bidirectional") (die_length 21.026))
    (pad "K1" smd circle (at -12.5 -3.5 180) (size 0.5 0.5) (layers "F.Cu" "F.Paste" "F.Mask")
      (net 483 "GTX_TX5_N") (pinfunction "MGTXTXN2_115") (pintype "bidirectional") (die_length 13.554))
    (pad "K2" smd circle (at -11.5 -3.5 180) (size 0.5 0.5) (layers "F.Cu" "F.Paste" "F.Mask")
      (net 481 "GTX_TX5_P") (pinfunction "MGTXTXP2_115") (pintype "bidirectional") (die_length 13.554))
    (pad "K3" smd circle (at -10.5 -3.5 180) (size 0.5 0.5) (layers "F.Cu" "F.Paste" "F.Mask")
      (net 9 "GND") (pinfunction "GND") (pintype "passive"))
    (pad "K4" smd circle (at -9.5 -3.5 180) (size 0.5 0.5) (layers "F.Cu" "F.Paste" "F.Mask")
      (net 9 "GND") (pinfunction "GND") (pintype "passive"))
    (pad "K5" smd circle (at -8.5 -3.5 180) (size 0.5 0.5) (layers "F.Cu" "F.Paste" "F.Mask")
      (net 884 "/FPGA banks 115-116/GTR_REFCLK1_N") (pinfunction "MGTREFCLK1N_115") (pintype "bidirectional") (die_length 11.876))
    (pad "K6" smd circle (at -7.5 -3.5 180) (size 0.5 0.5) (layers "F.Cu" "F.Paste" "F.Mask")
      (net 883 "/FPGA banks 115-116/GTR_REFCLK1_P") (pinfunction "MGTREFCLK1P_115") (pintype "bidirectional") (die_length 11.561))
    (pad "K7" smd circle (at -6.5 -3.5 180) (size 0.5 0.5) (layers "F.Cu" "F.Paste" "F.Mask")
      (net 9 "GND") (pinfunction "GND") (pintype "passive"))
    (pad "K8" smd circle (at -5.5 -3.5 180) (size 0.5 0.5) (layers "F.Cu" "F.Paste" "F.Mask")
      (net 147 "1V0_SYS") (pinfunction "VCCINT") (pintype "passive"))
    (pad "K9" smd circle (at -4.5 -3.5 180) (size 0.5 0.5) (layers "F.Cu" "F.Paste" "F.Mask")
      (net 9 "GND") (pinfunction "GND") (pintype "passive"))
    (pad "K10" smd circle (at -3.5 -3.5 180) (size 0.5 0.5) (layers "F.Cu" "F.Paste" "F.Mask")
      (net 147 "1V0_SYS") (pinfunction "VCCINT") (pintype "passive"))
    (pad "K11" smd circle (at -2.5 -3.5 180) (size 0.5 0.5) (layers "F.Cu" "F.Paste" "F.Mask")
      (net 9 "GND") (pinfunction "GND") (pintype "passive"))
    (pad "K12" smd circle (at -1.5 -3.5 180) (size 0.5 0.5) (layers "F.Cu" "F.Paste" "F.Mask")
      (net 147 "1V0_SYS") (pinfunction "VCCINT") (pintype "passive"))
    (pad "K13" smd circle (at -0.5 -3.5 180) (size 0.5 0.5) (layers "F.Cu" "F.Paste" "F.Mask")
      (net 9 "GND") (pinfunction "GND") (pintype "passive"))
    (pad "K14" smd circle (at 0.499 -3.5 180) (size 0.5 0.5) (layers "F.Cu" "F.Paste" "F.Mask")
      (net 147 "1V0_SYS") (pinfunction "VCCINT") (pintype "passive"))
    (pad "K15" smd circle (at 1.499 -3.5 180) (size 0.5 0.5) (layers "F.Cu" "F.Paste" "F.Mask")
      (net 529 "FMC_IO_0") (pinfunction "IO_0_15") (pintype "bidirectional") (die_length 6.731))
    (pad "K16" smd circle (at 2.499 -3.5 180) (size 0.5 0.5) (layers "F.Cu" "F.Paste" "F.Mask")
      (net 538 "FMC_IO_22_P") (pinfunction "IO_L22P_T3_A17_15") (pintype "bidirectional") (die_length 6.898))
    (pad "K17" smd circle (at 3.499 -3.5 180) (size 0.5 0.5) (layers "F.Cu" "F.Paste" "F.Mask")
      (net 539 "FMC_IO_22_N") (pinfunction "IO_L22N_T3_A16_15") (pintype "bidirectional") (die_length 7.2))
    (pad "K18" smd circle (at 4.499 -3.5 180) (size 0.5 0.5) (layers "F.Cu" "F.Paste" "F.Mask")
      (net 809 "FMC_IO_24_N") (pinfunction "IO_L24N_T3_RS0_15") (pintype "bidirectional") (die_length 7.112))
    (pad "K19" smd circle (at 5.499 -3.5 180) (size 0.5 0.5) (layers "F.Cu" "F.Paste" "F.Mask")
      (net 9 "GND") (pinfunction "GND") (pintype "passive"))
    (pad "K20" smd circle (at 6.499 -3.5 180) (size 0.5 0.5) (layers "F.Cu" "F.Paste" "F.Mask")
      (net 810 "FMC_IO_19_P") (pinfunction "IO_L19P_T3_A22_15") (pintype "bidirectional") (die_length 8.708))
    (pad "K21" smd circle (at 7.499 -3.5 180) (size 0.5 0.5) (layers "F.Cu" "F.Paste" "F.Mask")
      (net 778 "unconnected-(U15C-IO_0_14-PadK21)") (pinfunction "IO_0_14") (pintype "bidirectional+no_connect") (die_length 10.072))
    (pad "K22" smd circle (at 8.499 -3.5 180) (size 0.5 0.5) (layers "F.Cu" "F.Paste" "F.Mask")
      (net 779 "unconnected-(U15C-IO_L23N_T3_A02_D18_14-PadK22)") (pinfunction "IO_L23N_T3_A02_D18_14") (pintype "bidirectional+no_connect") (die_length 16.883))
    (pad "K23" smd circle (at 9.499 -3.5 180) (size 0.5 0.5) (layers "F.Cu" "F.Paste" "F.Mask")
      (net 780 "unconnected-(U15C-IO_L24P_T3_A01_D17_14-PadK23)") (pinfunction "IO_L24P_T3_A01_D17_14") (pintype "bidirectional+no_connect") (die_length 17.632))
    (pad "K24" smd circle (at 10.499 -3.5 180) (size 0.5 0.5) (layers "F.Cu" "F.Paste" "F.Mask")
      (net 77 "VDDQ") (pinfunction "VCCO_13") (pintype "power_in"))
    (pad "K25" smd circle (at 11.499 -3.5 180) (size 0.5 0.5) (layers "F.Cu" "F.Paste" "F.Mask")
      (net 781 "unconnected-(U15B-IO_L1P_T0_13-PadK25)") (pinfunction "IO_L1P_T0_13") (pintype "bidirectional+no_connect") (die_length 16.886))
    (pad "K26" smd circle (at 12.499 -3.5 180) (size 0.5 0.5) (layers "F.Cu" "F.Paste" "F.Mask")
      (net 782 "unconnected-(U15B-IO_L1N_T0_13-PadK26)") (pinfunction "IO_L1N_T0_13") (pintype "bidirectional+no_connect") (die_length 17.592))
    (pad "L1" smd circle (at -12.5 -2.5 180) (size 0.5 0.5) (layers "F.Cu" "F.Paste" "F.Mask")
      (net 9 "GND") (pinfunction "GND") (pintype "passive"))
    (pad "L2" smd circle (at -11.5 -2.5 180) (size 0.5 0.5) (layers "F.Cu" "F.Paste" "F.Mask")
      (net 306 "1V2_SYS") (pinfunction "MGTAVTT") (pintype "passive"))
    (pad "L3" smd circle (at -10.5 -2.5 180) (size 0.5 0.5) (layers "F.Cu" "F.Paste" "F.Mask")
      (net 641 "GTX_RX5_N") (pinfunction "MGTXRXN2_115") (pintype "bidirectional") (die_length 11.935))
    (pad "L4" smd circle (at -9.5 -2.5 180) (size 0.5 0.5) (layers "F.Cu" "F.Paste" "F.Mask")
      (net 640 "GTX_RX5_P") (pinfunction "MGTXRXP2_115") (pintype "bidirectional") (die_length 12.06))
    (pad "L5" smd circle (at -8.5 -2.5 180) (size 0.5 0.5) (layers "F.Cu" "F.Paste" "F.Mask")
      (net 9 "GND") (pinfunction "GND") (pintype "passive"))
    (pad "L6" smd circle (at -7.5 -2.5 180) (size 0.5 0.5) (layers "F.Cu" "F.Paste" "F.Mask")
      (net 147 "1V0_SYS") (pinfunction "MGTAVCC") (pintype "passive"))
    (pad "L7" smd circle (at -6.5 -2.5 180) (size 0.5 0.5) (layers "F.Cu" "F.Paste" "F.Mask")
      (net 143 "3V3_SYS") (pinfunction "VCCO_0") (pintype "power_in"))
    (pad "L8" smd circle (at -5.5 -2.5 180) (size 0.5 0.5) (layers "F.Cu" "F.Paste" "F.Mask")
      (net 12 "TCK_JTAG") (pinfunction "TCK_0") (pintype "bidirectional") (die_length 14.628))
    (pad "L9" smd circle (at -4.5 -2.5 180) (size 0.5 0.5) (layers "F.Cu" "F.Paste" "F.Mask")
      (net 147 "1V0_SYS") (pinfunction "VCCINT") (pintype "passive"))
    (pad "L10" smd circle (at -3.5 -2.5 180) (size 0.5 0.5) (layers "F.Cu" "F.Paste" "F.Mask")
      (net 9 "GND") (pinfunction "GND") (pintype "passive"))
    (pad "L11" smd circle (at -2.5 -2.5 180) (size 0.5 0.5) (layers "F.Cu" "F.Paste" "F.Mask")
      (net 144 "1V8_SYS") (pinfunction "VCCAUX") (pintype "power_in"))
    (pad "L12" smd circle (at -1.5 -2.5 180) (size 0.5 0.5) (layers "F.Cu" "F.Paste" "F.Mask")
      (net 9 "GND") (pinfunction "GND") (pintype "passive"))
    (pad "L13" smd circle (at -0.5 -2.5 180) (size 0.5 0.5) (layers "F.Cu" "F.Paste" "F.Mask")
      (net 147 "1V0_SYS") (pinfunction "VCCINT") (pintype "passive"))
    (pad "L14" smd circle (at 0.499 -2.5 180) (size 0.5 0.5) (layers "F.Cu" "F.Paste" "F.Mask")
      (net 9 "GND") (pinfunction "GND") (pintype "passive"))
    (pad "L15" smd circle (at 1.499 -2.5 180) (size 0.5 0.5) (layers "F.Cu" "F.Paste" "F.Mask")
      (net 147 "1V0_SYS") (pinfunction "VCCINT") (pintype "passive"))
    (pad "L16" smd circle (at 2.499 -2.5 180) (size 0.5 0.5) (layers "F.Cu" "F.Paste" "F.Mask")
      (net 9 "GND") (pinfunction "GND") (pintype "passive"))
    (pad "L17" smd circle (at 3.499 -2.5 180) (size 0.5 0.5) (layers "F.Cu" "F.Paste" "F.Mask")
      (net 811 "FMC_IO_24_P") (pinfunction "IO_L24P_T3_RS1_15") (pintype "bidirectional") (die_length 6.318))
    (pad "L18" smd circle (at 4.499 -2.5 180) (size 0.5 0.5) (layers "F.Cu" "F.Paste" "F.Mask")
      (net 812 "FMC_IO_23_N") (pinfunction "IO_L23N_T3_FWE_B_15") (pintype "bidirectional") (die_length 7.658))
    (pad "L19" smd circle (at 5.499 -2.5 180) (size 0.5 0.5) (layers "F.Cu" "F.Paste" "F.Mask")
      (net 813 "FMC_IO_21_P") (pinfunction "IO_L21P_T3_DQS_15") (pintype "bidirectional") (die_length 7.664))
    (pad "L20" smd circle (at 6.499 -2.5 180) (size 0.5 0.5) (layers "F.Cu" "F.Paste" "F.Mask")
      (net 814 "FMC_IO_21_N") (pinfunction "IO_L21N_T3_DQS_A18_15") (pintype "bidirectional") (die_length 7.681))
    (pad "L21" smd circle (at 7.499 -2.5 180) (size 0.5 0.5) (layers "F.Cu" "F.Paste" "F.Mask")
      (net 143 "3V3_SYS") (pinfunction "VCCO_14") (pintype "passive"))
    (pad "L22" smd circle (at 8.499 -2.5 180) (size 0.5 0.5) (layers "F.Cu" "F.Paste" "F.Mask")
      (net 783 "unconnected-(U15C-IO_L23P_T3_A03_D19_14-PadL22)") (pinfunction "IO_L23P_T3_A03_D19_14") (pintype "bidirectional+no_connect") (die_length 16.198))
    (pad "L23" smd circle (at 9.499 -2.5 180) (size 0.5 0.5) (layers "F.Cu" "F.Paste" "F.Mask")
      (net 785 "unconnected-(U15C-IO_25_14-PadL23)") (pinfunction "IO_25_14") (pintype "bidirectional+no_connect") (die_length 15.436))
    (pad "L24" smd circle (at 10.499 -2.5 180) (size 0.5 0.5) (layers "F.Cu" "F.Paste" "F.Mask")
      (net 787 "unconnected-(U15B-IO_L8N_T1_13-PadL24)") (pinfunction "IO_L8N_T1_13") (pintype "bidirectional+no_connect") (die_length 16.877))
    (pad "L25" smd circle (at 11.499 -2.5 180) (size 0.5 0.5) (layers "F.Cu" "F.Paste" "F.Mask")
      (net 791 "unconnected-(U15B-IO_L3N_T0_DQS_13-PadL25)") (pinfunction "IO_L3N_T0_DQS_13") (pintype "bidirectional+no_connect") (die_length 16.692))
    (pad "L26" smd circle (at 12.499 -2.5 180) (size 0.5 0.5) (layers "F.Cu" "F.Paste" "F.Mask")
      (net 9 "GND") (pinfunction "GND") (pintype "passive"))
    (pad "M1" smd circle (at -12.5 -1.5 180) (size 0.5 0.5) (layers "F.Cu" "F.Paste" "F.Mask")
      (net 512 "GTX_TX6_N") (pinfunction "MGTXTXN1_115") (pintype "bidirectional") (die_length 13.445))
    (pad "M2" smd circle (at -11.5 -1.5 180) (size 0.5 0.5) (layers "F.Cu" "F.Paste" "F.Mask")
      (net 498 "GTX_TX6_P") (pinfunction "MGTXTXP1_115") (pintype "bidirectional") (die_length 13.639))
    (pad "M3" smd circle (at -10.5 -1.5 180) (size 0.5 0.5) (layers "F.Cu" "F.Paste" "F.Mask")
      (net 306 "1V2_SYS") (pinfunction "MGTAVTT") (pintype "passive"))
    (pad "M4" smd circle (at -9.5 -1.5 180) (size 0.5 0.5) (layers "F.Cu" "F.Paste" "F.Mask")
      (net 9 "GND") (pinfunction "GND") (pintype "passive"))
    (pad "M5" smd circle (at -8.5 -1.5 180) (size 0.5 0.5) (layers "F.Cu" "F.Paste" "F.Mask")
      (net 306 "1V2_SYS") (pinfunction "MGTAVTTRCAL_115") (pintype "power_in"))
    (pad "M6" smd circle (at -7.5 -1.5 180) (size 0.5 0.5) (layers "F.Cu" "F.Paste" "F.Mask")
      (net 663 "Net-(U15J-MGTRREF_115)") (pinfunction "MGTRREF_115") (pintype "power_in") (die_length 11.045))
    (pad "M7" smd circle (at -6.5 -1.5 180) (size 0.5 0.5) (layers "F.Cu" "F.Paste" "F.Mask")
      (net 9 "GND") (pinfunction "GND") (pintype "passive"))
    (pad "M8" smd circle (at -5.5 -1.5 180) (size 0.5 0.5) (layers "F.Cu" "F.Paste" "F.Mask")
      (net 147 "1V0_SYS") (pinfunction "VCCINT") (pintype "passive"))
    (pad "M9" smd circle (at -4.5 -1.5 180) (size 0.5 0.5) (layers "F.Cu" "F.Paste" "F.Mask")
      (net 9 "GND") (pinfunction "GND") (pintype "passive"))
    (pad "M10" smd circle (at -3.5 -1.5 180) (size 0.5 0.5) (layers "F.Cu" "F.Paste" "F.Mask")
      (net 144 "1V8_SYS") (pinfunction "VCCAUX") (pintype "passive"))
    (pad "M11" smd circle (at -2.5 -1.5 180) (size 0.5 0.5) (layers "F.Cu" "F.Paste" "F.Mask")
      (net 9 "GND") (pinfunction "GNDADC_0") (pintype "power_in"))
    (pad "M12" smd circle (at -1.5 -1.5 180) (size 0.5 0.5) (layers "F.Cu" "F.Paste" "F.Mask")
      (net 144 "1V8_SYS") (pinfunction "VCCADC_0") (pintype "power_in"))
    (pad "M13" smd circle (at -0.5 -1.5 180) (size 0.5 0.5) (layers "F.Cu" "F.Paste" "F.Mask")
      (net 9 "GND") (pinfunction "GND") (pintype "passive"))
    (pad "M14" smd circle (at 0.499 -1.5 180) (size 0.5 0.5) (layers "F.Cu" "F.Paste" "F.Mask")
      (net 147 "1V0_SYS") (pinfunction "VCCINT") (pintype "passive"))
    (pad "M15" smd circle (at 1.499 -1.5 180) (size 0.5 0.5) (layers "F.Cu" "F.Paste" "F.Mask")
      (net 9 "GND") (pinfunction "GND") (pintype "passive"))
    (pad "M16" smd circle (at 2.499 -1.5 180) (size 0.5 0.5) (layers "F.Cu" "F.Paste" "F.Mask")
      (net 815 "FMC_IO_25") (pinfunction "IO_25_15") (pintype "bidirectional") (die_length 5.552))
    (pad "M17" smd circle (at 3.499 -1.5 180) (size 0.5 0.5) (layers "F.Cu" "F.Paste" "F.Mask")
      (net 816 "FMC_IO_23_P") (pinfunction "IO_L23P_T3_FOE_B_15") (pintype "bidirectional") (die_length 8.087))
    (pad "M18" smd circle (at 4.499 -1.5 180) (size 0.5 0.5) (layers "F.Cu" "F.Paste" "F.Mask")
      (net 143 "3V3_SYS") (pinfunction "VCCO_15") (pintype "passive"))
    (pad "M19" smd circle (at 5.499 -1.5 180) (size 0.5 0.5) (layers "F.Cu" "F.Paste" "F.Mask")
      (net 792 "unconnected-(U15B-IO_L22N_T3_13-PadM19)") (pinfunction "IO_L22N_T3_13") (pintype "bidirectional+no_connect") (die_length 14.527))
    (pad "M20" smd circle (at 6.499 -1.5 180) (size 0.5 0.5) (layers "F.Cu" "F.Paste" "F.Mask")
      (net 795 "unconnected-(U15B-IO_L7N_T1_13-PadM20)") (pinfunction "IO_L7N_T1_13") (pintype "bidirectional+no_connect") (die_length 12.084))
    (pad "M21" smd circle (at 7.499 -1.5 180) (size 0.5 0.5) (layers "F.Cu" "F.Paste" "F.Mask")
      (net 797 "unconnected-(U15B-IO_L10P_T1_13-PadM21)") (pinfunction "IO_L10P_T1_13") (pintype "bidirectional+no_connect") (die_length 14.496))
    (pad "M22" smd circle (at 8.499 -1.5 180) (size 0.5 0.5) (layers "F.Cu" "F.Paste" "F.Mask")
      (net 801 "unconnected-(U15B-IO_L10N_T1_13-PadM22)") (pinfunction "IO_L10N_T1_13") (pintype "bidirectional+no_connect") (die_length 14.558))
    (pad "M23" smd circle (at 9.499 -1.5 180) (size 0.5 0.5) (layers "F.Cu" "F.Paste" "F.Mask")
      (net 9 "GND") (pinfunction "GND") (pintype "passive"))
    (pad "M24" smd circle (at 10.499 -1.5 180) (size 0.5 0.5) (layers "F.Cu" "F.Paste" "F.Mask")
      (net 802 "unconnected-(U15B-IO_L8P_T1_13-PadM24)") (pinfunction "IO_L8P_T1_13") (pintype "bidirectional+no_connect") (die_length 15.433))
    (pad "M25" smd circle (at 11.499 -1.5 180) (size 0.5 0.5) (layers "F.Cu" "F.Paste" "F.Mask")
      (net 803 "unconnected-(U15B-IO_L3P_T0_DQS_13-PadM25)") (pinfunction "IO_L3P_T0_DQS_13") (pintype "bidirectional+no_connect") (die_length 16.172))
    (pad "M26" smd circle (at 12.499 -1.5 180) (size 0.5 0.5) (layers "F.Cu" "F.Paste" "F.Mask")
      (net 817 "unconnected-(U15B-IO_L5N_T0_13-PadM26)") (pinfunction "IO_L5N_T0_13") (pintype "bidirectional+no_connect") (die_length 16.457))
    (pad "N1" smd circle (at -12.5 -0.5 180) (size 0.5 0.5) (layers "F.Cu" "F.Paste" "F.Mask")
      (net 9 "GND") (pinfunction "GND") (pintype "passive"))
    (pad "N2" smd circle (at -11.5 -0.5 180) (size 0.5 0.5) (layers "F.Cu" "F.Paste" "F.Mask")
      (net 9 "GND") (pinfunction "GND") (pintype "passive"))
    (pad "N3" smd circle (at -10.5 -0.5 180) (size 0.5 0.5) (layers "F.Cu" "F.Paste" "F.Mask")
      (net 648 "GTX_RX6_N") (pinfunction "MGTXRXN1_115") (pintype "bidirectional") (die_length 12.774))
    (pad "N4" smd circle (at -9.5 -0.5 180) (size 0.5 0.5) (layers "F.Cu" "F.Paste" "F.Mask")
      (net 647 "GTX_RX6_P") (pinfunction "MGTXRXP1_115") (pintype "bidirectional") (die_length 12.878))
    (pad "N5" smd circle (at -8.5 -0.5 180) (size 0.5 0.5) (layers "F.Cu" "F.Paste" "F.Mask")
      (net 9 "GND") (pinfunction "GND") (pintype "passive"))
    (pad "N6" smd circle (at -7.5 -0.5 180) (size 0.5 0.5) (layers "F.Cu" "F.Paste" "F.Mask")
      (net 144 "1V8_SYS") (pinfunction "MGTVCCAUX") (pintype "power_in"))
    (pad "N7" smd circle (at -6.5 -0.5 180) (size 0.5 0.5) (layers "F.Cu" "F.Paste" "F.Mask")
      (net 9 "GND") (pinfunction "GND") (pintype "passive"))
    (pad "N8" smd circle (at -5.5 -0.5 180) (size 0.5 0.5) (layers "F.Cu" "F.Paste" "F.Mask")
      (net 13 "TMS_JTAG") (pinfunction "TMS_0") (pintype "bidirectional") (die_length 12.891))
    (pad "N9" smd circle (at -4.5 -0.5 180) (size 0.5 0.5) (layers "F.Cu" "F.Paste" "F.Mask")
      (net 147 "1V0_SYS") (pinfunction "VCCINT") (pintype "passive"))
    (pad "N10" smd circle (at -3.5 -0.5 180) (size 0.5 0.5) (layers "F.Cu" "F.Paste" "F.Mask")
      (net 9 "GND") (pinfunction "GND") (pintype "passive"))
    (pad "N11" smd circle (at -2.5 -0.5 180) (size 0.5 0.5) (layers "F.Cu" "F.Paste" "F.Mask")
      (net 9 "GND") (pinfunction "VREFN_0") (pintype "bidirectional") (die_length 14.753))
    (pad "N12" smd circle (at -1.5 -0.5 180) (size 0.5 0.5) (layers "F.Cu" "F.Paste" "F.Mask")
      (net 9 "GND") (pinfunction "VP_0") (pintype "bidirectional") (die_length 12.915))
    (pad "N13" smd circle (at -0.5 -0.5 180) (size 0.5 0.5) (layers "F.Cu" "F.Paste" "F.Mask")
      (net 147 "1V0_SYS") (pinfunction "VCCBRAM") (pintype "power_in"))
    (pad "N14" smd circle (at 0.499 -0.5 180) (size 0.5 0.5) (layers "F.Cu" "F.Paste" "F.Mask")
      (net 9 "GND") (pinfunction "GND") (pintype "passive"))
    (pad "N15" smd circle (at 1.499 -0.5 180) (size 0.5 0.5) (layers "F.Cu" "F.Paste" "F.Mask")
      (net 147 "1V0_SYS") (pinfunction "VCCINT") (pintype "passive"))
    (pad "N16" smd circle (at 2.499 -0.5 180) (size 0.5 0.5) (layers "F.Cu" "F.Paste" "F.Mask")
      (net 818 "unconnected-(U15B-IO_0_13-PadN16)") (pinfunction "IO_0_13") (pintype "bidirectional+no_connect") (die_length 6.733))
    (pad "N17" smd circle (at 3.499 -0.5 180) (size 0.5 0.5) (layers "F.Cu" "F.Paste" "F.Mask")
      (net 819 "unconnected-(U15B-IO_L20N_T3_13-PadN17)") (pinfunction "IO_L20N_T3_13") (pintype "bidirectional+no_connect") (die_length 9.445))
    (pad "N18" smd circle (at 4.499 -0.5 180) (size 0.5 0.5) (layers "F.Cu" "F.Paste" "F.Mask")
      (net 820 "unconnected-(U15B-IO_L22P_T3_13-PadN18)") (pinfunction "IO_L22P_T3_13") (pintype "bidirectional+no_connect") (die_length 11.191))
    (pad "N19" smd circle (at 5.499 -0.5 180) (size 0.5 0.5) (layers "F.Cu" "F.Paste" "F.Mask")
      (net 821 "unconnected-(U15B-IO_L7P_T1_13-PadN19)") (pinfunction "IO_L7P_T1_13") (pintype "bidirectional+no_connect") (die_length 10.696))
    (pad "N20" smd circle (at 6.499 -0.5 180) (size 0.5 0.5) (layers "F.Cu" "F.Paste" "F.Mask")
      (net 9 "GND") (pinfunction "GND") (pintype "passive"))
    (pad "N21" smd circle (at 7.499 -0.5 180) (size 0.5 0.5) (layers "F.Cu" "F.Paste" "F.Mask")
      (net 822 "unconnected-(U15B-IO_L12P_T1_MRCC_13-PadN21)") (pinfunction "IO_L12P_T1_MRCC_13") (pintype "bidirectional+no_connect") (die_length 11.848))
    (pad "N22" smd circle (at 8.499 -0.5 180) (size 0.5 0.5) (layers "F.Cu" "F.Paste" "F.Mask")
      (net 823 "unconnected-(U15B-IO_L12N_T1_MRCC_13-PadN22)") (pinfunction "IO_L12N_T1_MRCC_13") (pintype "bidirectional+no_connect") (die_length 12.32))
    (pad "N23" smd circle (at 9.499 -0.5 180) (size 0.5 0.5) (layers "F.Cu" "F.Paste" "F.Mask")
      (net 847 "unconnected-(U15B-IO_L11N_T1_SRCC_13-PadN23)") (pinfunction "IO_L11N_T1_SRCC_13") (pintype "bidirectional+no_connect") (die_length 14.434))
    (pad "N24" smd circle (at 10.499 -0.5 180) (size 0.5 0.5) (layers "F.Cu" "F.Paste" "F.Mask")
      (net 848 "unconnected-(U15B-IO_L4N_T0_13-PadN24)") (pinfunction "IO_L4N_T0_13") (pintype "bidirectional+no_connect") (die_length 15.311))
    (pad "N25" smd circle (at 11.499 -0.5 180) (size 0.5 0.5) (layers "F.Cu" "F.Paste" "F.Mask")
      (net 77 "VDDQ") (pinfunction "VCCO_13") (pintype "passive"))
    (pad "N26" smd circle (at 12.499 -0.5 180) (size 0.5 0.5) (layers "F.Cu" "F.Paste" "F.Mask")
      (net 849 "unconnected-(U15B-IO_L5P_T0_13-PadN26)") (pinfunction "IO_L5P_T0_13") (pintype "bidirectional+no_connect") (die_length 16.049))
    (pad "P1" smd circle (at -12.5 0.499 180) (size 0.5 0.5) (layers "F.Cu" "F.Paste" "F.Mask")
      (net 526 "GTX_TX7_N") (pinfunction "MGTXTXN0_115") (pintype "bidirectional") (die_length 14.843))
    (pad "P2" smd circle (at -11.5 0.499 180) (size 0.5 0.5) (layers "F.Cu" "F.Paste" "F.Mask")
      (net 524 "GTX_TX7_P") (pinfunction "MGTXTXP0_115") (pintype "bidirectional") (die_length 15.009))
    (pad "P3" smd circle (at -10.5 0.499 180) (size 0.5 0.5) (layers "F.Cu" "F.Paste" "F.Mask")
      (net 9 "GND") (pinfunction "GND") (pintype "passive"))
    (pad "P4" smd circle (at -9.5 0.499 180) (size 0.5 0.5) (layers "F.Cu" "F.Paste" "F.Mask")
      (net 9 "GND") (pinfunction "GND") (pintype "passive"))
    (pad "P5" smd circle (at -8.5 0.499 180) (size 0.5 0.5) (layers "F.Cu" "F.Paste" "F.Mask")
      (net 18 "MODE2") (pinfunction "M2_0") (pintype "bidirectional") (die_length 16.743))
    (pad "P6" smd circle (at -7.5 0.499 180) (size 0.5 0.5) (layers "F.Cu" "F.Paste" "F.Mask")
      (net 91 "PROGRAM_B") (pinfunction "PROGRAM_B_0") (pintype "bidirectional") (die_length 16.276))
    (pad "P7" smd circle (at -6.5 0.499 180) (size 0.5 0.5) (layers "F.Cu" "F.Paste" "F.Mask")
      (net 100 "CFGBVS") (pinfunction "CFGBVS_0") (pintype "bidirectional") (die_length 14.171))
    (pad "P8" smd circle (at -5.5 0.499 180) (size 0.5 0.5) (layers "F.Cu" "F.Paste" "F.Mask")
      (net 144 "1V8_SYS") (pinfunction "VCCAUX_IO_G0") (pintype "power_in"))
    (pad "P9" smd circle (at -4.5 0.499 180) (size 0.5 0.5) (layers "F.Cu" "F.Paste" "F.Mask")
      (net 9 "GND") (pinfunction "GND") (pintype "passive"))
    (pad "P10" smd circle (at -3.5 0.499 180) (size 0.5 0.5) (layers "F.Cu" "F.Paste" "F.Mask")
      (net 144 "1V8_SYS") (pinfunction "VCCAUX") (pintype "passive"))
    (pad "P11" smd circle (at -2.5 0.499 180) (size 0.5 0.5) (layers "F.Cu" "F.Paste" "F.Mask")
      (net 9 "GND") (pinfunction "VN_0") (pintype "bidirectional") (die_length 13.84))
    (pad "P12" smd circle (at -1.5 0.499 180) (size 0.5 0.5) (layers "F.Cu" "F.Paste" "F.Mask")
      (net 9 "GND") (pinfunction "VREFP_0") (pintype "bidirectional") (die_length 12.633))
    (pad "P13" smd circle (at -0.5 0.499 180) (size 0.5 0.5) (layers "F.Cu" "F.Paste" "F.Mask")
      (net 9 "GND") (pinfunction "GND") (pintype "passive"))
    (pad "P14" smd circle (at 0.499 0.499 180) (size 0.5 0.5) (layers "F.Cu" "F.Paste" "F.Mask")
      (net 147 "1V0_SYS") (pinfunction "VCCINT") (pintype "passive"))
    (pad "P15" smd circle (at 1.499 0.499 180) (size 0.5 0.5) (layers "F.Cu" "F.Paste" "F.Mask")
      (net 9 "GND") (pinfunction "GND") (pintype "passive"))
    (pad "P16" smd circle (at 2.499 0.499 180) (size 0.5 0.5) (layers "F.Cu" "F.Paste" "F.Mask")
      (net 850 "unconnected-(U15B-IO_L20P_T3_13-PadP16)") (pinfunction "IO_L20P_T3_13") (pintype "bidirectional+no_connect") (die_length 8.016))
    (pad "P17" smd circle (at 3.499 0.499 180) (size 0.5 0.5) (layers "F.Cu" "F.Paste" "F.Mask")
      (net 9 "GND") (pinfunction "GND") (pintype "passive"))
    (pad "P18" smd circle (at 4.499 0.499 180) (size 0.5 0.5) (layers "F.Cu" "F.Paste" "F.Mask")
      (net 851 "unconnected-(U15B-IO_L24N_T3_13-PadP18)") (pinfunction "IO_L24N_T3_13") (pintype "bidirectional+no_connect") (die_length 10.217))
    (pad "P19" smd circle (at 5.499 0.499 180) (size 0.5 0.5) (layers "F.Cu" "F.Paste" "F.Mask")
      (net 346 "DQS8_P") (pinfunction "IO_L9P_T1_DQS_13") (pintype "bidirectional") (die_length 12.118))
    (pad "P20" smd circle (at 6.499 0.499 180) (size 0.5 0.5) (layers "F.Cu" "F.Paste" "F.Mask")
      (net 348 "DQS8_N") (pinfunction "IO_L9N_T1_DQS_13") (pintype "bidirectional") (die_length 12.121))
    (pad "P21" smd circle (at 7.499 0.499 180) (size 0.5 0.5) (layers "F.Cu" "F.Paste" "F.Mask")
      (net 852 "unconnected-(U15B-IO_L13N_T2_MRCC_13-PadP21)") (pinfunction "IO_L13N_T2_MRCC_13") (pintype "bidirectional+no_connect") (die_length 10.375))
    (pad "P22" smd circle (at 8.499 0.499 180) (size 0.5 0.5) (layers "F.Cu" "F.Paste" "F.Mask")
      (net 77 "VDDQ") (pinfunction "VCCO_13") (pintype "passive"))
    (pad "P23" smd circle (at 9.499 0.499 180) (size 0.5 0.5) (layers "F.Cu" "F.Paste" "F.Mask")
      (net 858 "unconnected-(U15B-IO_L11P_T1_SRCC_13-PadP23)") (pinfunction "IO_L11P_T1_SRCC_13") (pintype "bidirectional+no_connect") (die_length 14.144))
    (pad "P24" smd circle (at 10.499 0.499 180) (size 0.5 0.5) (layers "F.Cu" "F.Paste" "F.Mask")
      (net 861 "unconnected-(U15B-IO_L4P_T0_13-PadP24)") (pinfunction "IO_L4P_T0_13") (pintype "bidirectional+no_connect") (die_length 13.362))
    (pad "P25" smd circle (at 11.499 0.499 180) (size 0.5 0.5) (layers "F.Cu" "F.Paste" "F.Mask")
      (net 865 "unconnected-(U15B-IO_L6N_T0_VREF_13-PadP25)") (pinfunction "IO_L6N_T0_VREF_13") (pintype "bidirectional+no_connect") (die_length 14.662))
    (pad "P26" smd circle (at 12.499 0.499 180) (size 0.5 0.5) (layers "F.Cu" "F.Paste" "F.Mask")
      (net 866 "unconnected-(U15B-IO_L2N_T0_13-PadP26)") (pinfunction "IO_L2N_T0_13") (pintype "bidirectional+no_connect") (die_length 17.56))
    (pad "R1" smd circle (at -12.5 1.499 180) (size 0.5 0.5) (layers "F.Cu" "F.Paste" "F.Mask")
      (net 9 "GND") (pinfunction "GND") (pintype "passive"))
    (pad "R2" smd circle (at -11.5 1.499 180) (size 0.5 0.5) (layers "F.Cu" "F.Paste" "F.Mask")
      (net 9 "GND") (pinfunction "GND") (pintype "passive"))
    (pad "R3" smd circle (at -10.5 1.499 180) (size 0.5 0.5) (layers "F.Cu" "F.Paste" "F.Mask")
      (net 646 "GTX_RX7_N") (pinfunction "MGTXRXN0_115") (pintype "bidirectional") (die_length 13.691))
    (pad "R4" smd circle (at -9.5 1.499 180) (size 0.5 0.5) (layers "F.Cu" "F.Paste" "F.Mask")
      (net 645 "GTX_RX7_P") (pinfunction "MGTXRXP0_115") (pintype "bidirectional") (die_length 13.771))
    (pad "R5" smd circle (at -8.5 1.499 180) (size 0.5 0.5) (layers "F.Cu" "F.Paste" "F.Mask")
      (net 9 "GND") (pinfunction "GND") (pintype "passive"))
    (pad "R6" smd circle (at -7.5 1.499 180) (size 0.5 0.5) (layers "F.Cu" "F.Paste" "F.Mask")
      (net 14 "TDI_JTAG") (pinfunction "TDI_0") (pintype "bidirectional") (die_length 16.338))
    (pad "R7" smd circle (at -6.5 1.499 180) (size 0.5 0.5) (layers "F.Cu" "F.Paste" "F.Mask")
      (net 15 "TDO_JTAG") (pinfunction "TDO_0") (pintype "bidirectional") (die_length 15.018))
    (pad "R8" smd circle (at -5.5 1.499 180) (size 0.5 0.5) (layers "F.Cu" "F.Paste" "F.Mask")
      (net 9 "GND") (pinfunction "GND") (pintype "passive"))
    (pad "R9" smd circle (at -4.5 1.499 180) (size 0.5 0.5) (layers "F.Cu" "F.Paste" "F.Mask")
      (net 144 "1V8_SYS") (pinfunction "VCCAUX_IO_G0") (pintype "passive"))
    (pad "R10" smd circle (at -3.5 1.499 180) (size 0.5 0.5) (layers "F.Cu" "F.Paste" "F.Mask")
      (net 9 "GND") (pinfunction "GND") (pintype "passive"))
    (pad "R11" smd circle (at -2.5 1.499 180) (size 0.5 0.5) (layers "F.Cu" "F.Paste" "F.Mask")
      (net 9 "GND") (pinfunction "DXN_0") (pintype "bidirectional") (die_length 14.9))
    (pad "R12" smd circle (at -1.5 1.499 180) (size 0.5 0.5) (layers "F.Cu" "F.Paste" "F.Mask")
      (net 9 "GND") (pinfunction "DXP_0") (pintype "bidirectional") (die_length 12.842))
    (pad "R13" smd circle (at -0.5 1.499 180) (size 0.5 0.5) (layers "F.Cu" "F.Paste" "F.Mask")
      (net 147 "1V0_SYS") (pinfunction "VCCBRAM") (pintype "passive"))
    (pad "R14" smd circle (at 0.499 1.499 180) (size 0.5 0.5) (layers "F.Cu" "F.Paste" "F.Mask")
      (net 9 "GND") (pinfunction "GND") (pintype "passive"))
    (pad "R15" smd circle (at 1.499 1.499 180) (size 0.5 0.5) (layers "F.Cu" "F.Paste" "F.Mask")
      (net 147 "1V0_SYS") (pinfunction "VCCINT") (pintype "passive"))
    (pad "R16" smd circle (at 2.499 1.499 180) (size 0.5 0.5) (layers "F.Cu" "F.Paste" "F.Mask")
      (net 347 "DQS17_P") (pinfunction "IO_L21P_T3_DQS_13") (pintype "bidirectional") (die_length 10.096))
    (pad "R17" smd circle (at 3.499 1.499 180) (size 0.5 0.5) (layers "F.Cu" "F.Paste" "F.Mask")
      (net 349 "DQS17_N") (pinfunction "IO_L21N_T3_DQS_13") (pintype "bidirectional") (die_length 10.012))
    (pad "R18" smd circle (at 4.499 1.499 180) (size 0.5 0.5) (layers "F.Cu" "F.Paste" "F.Mask")
      (net 867 "unconnected-(U15B-IO_L24P_T3_13-PadR18)") (pinfunction "IO_L24P_T3_13") (pintype "bidirectional+no_connect") (die_length 8.982))
    (pad "R19" smd circle (at 5.499 1.499 180) (size 0.5 0.5) (layers "F.Cu" "F.Paste" "F.Mask")
      (net 77 "VDDQ") (pinfunction "VCCO_13") (pintype "passive"))
    (pad "R20" smd circle (at 6.499 1.499 180) (size 0.5 0.5) (layers "F.Cu" "F.Paste" "F.Mask")
      (net 868 "unconnected-(U15B-IO_L16N_T2_13-PadR20)") (pinfunction "IO_L16N_T2_13") (pintype "bidirectional+no_connect") (die_length 9.979))
    (pad "R21" smd circle (at 7.499 1.499 180) (size 0.5 0.5) (layers "F.Cu" "F.Paste" "F.Mask")
      (net 259 "CB6") (pinfunction "IO_L13P_T2_MRCC_13") (pintype "bidirectional") (die_length 10.23))
    (pad "R22" smd circle (at 8.499 1.499 180) (size 0.5 0.5) (layers "F.Cu" "F.Paste" "F.Mask")
      (net 260 "CB2") (pinfunction "IO_L14P_T2_SRCC_13") (pintype "bidirectional") (die_length 11.973))
    (pad "R23" smd circle (at 9.499 1.499 180) (size 0.5 0.5) (layers "F.Cu" "F.Paste" "F.Mask")
      (net 869 "unconnected-(U15B-IO_L14N_T2_SRCC_13-PadR23)") (pinfunction "IO_L14N_T2_SRCC_13") (pintype "bidirectional+no_connect") (die_length 12.182))
    (pad "R24" smd circle (at 10.499 1.499 180) (size 0.5 0.5) (layers "F.Cu" "F.Paste" "F.Mask")
      (net 9 "GND") (pinfunction "GND") (pintype "passive"))
    (pad "R25" smd circle (at 11.499 1.499 180) (size 0.5 0.5) (layers "F.Cu" "F.Paste" "F.Mask")
      (net 870 "unconnected-(U15B-IO_L6P_T0_13-PadR25)") (pinfunction "IO_L6P_T0_13") (pintype "bidirectional+no_connect") (die_length 14.416))
    (pad "R26" smd circle (at 12.499 1.499 180) (size 0.5 0.5) (layers "F.Cu" "F.Paste" "F.Mask")
      (net 871 "unconnected-(U15B-IO_L2P_T0_13-PadR26)") (pinfunction "IO_L2P_T0_13") (pintype "bidirectional+no_connect") (die_length 16.3))
    (pad "T1" smd circle (at -12.5 2.499 180) (size 0.5 0.5) (layers "F.Cu" "F.Paste" "F.Mask")
      (net 9 "GND") (pinfunction "GND") (pintype "passive"))
    (pad "T2" smd circle (at -11.5 2.499 180) (size 0.5 0.5) (layers "F.Cu" "F.Paste" "F.Mask")
      (net 24 "MODE1") (pinfunction "M1_0") (pintype "bidirectional") (die_length 22.574))
    (pad "T3" smd circle (at -10.5 2.499 180) (size 0.5 0.5) (layers "F.Cu" "F.Paste" "F.Mask")
      (net 9 "GND") (pinfunction "GND") (pintype "passive"))
    (pad "T4" smd circle (at -9.5 2.499 180) (size 0.5 0.5) (layers "F.Cu" "F.Paste" "F.Mask")
      (net 9 "GND") (pinfunction "GND") (pintype "passive"))
    (pad "T5" smd circle (at -8.5 2.499 180) (size 0.5 0.5) (layers "F.Cu" "F.Paste" "F.Mask")
      (net 23 "MODE0") (pinfunction "M0_0") (pintype "bidirectional") (die_length 20.855))
    (pad "T6" smd circle (at -7.5 2.499 180) (size 0.5 0.5) (layers "F.Cu" "F.Paste" "F.Mask")
      (net 143 "3V3_SYS") (pinfunction "VCCO_0") (pintype "passive"))
    (pad "T7" smd circle (at -6.5 2.499 180) (size 0.5 0.5) (layers "F.Cu" "F.Paste" "F.Mask")
      (net 872 "unconnected-(U15H-IO_25_VRP_34-PadT7)") (pinfunction "IO_25_VRP_34") (pintype "bidirectional+no_connect") (die_length 9.857))
    (pad "T8" smd circle (at -5.5 2.499 180) (size 0.5 0.5) (layers "F.Cu" "F.Paste" "F.Mask")
      (net 144 "1V8_SYS") (pinfunction "VCCAUX_IO_G0") (pintype "passive"))
    (pad "T9" smd circle (at -4.5 2.499 180) (size 0.5 0.5) (layers "F.Cu" "F.Paste" "F.Mask")
      (net 9 "GND") (pinfunction "GND") (pintype "passive"))
    (pad "T10" smd circle (at -3.5 2.499 180) (size 0.5 0.5) (layers "F.Cu" "F.Paste" "F.Mask")
      (net 144 "1V8_SYS") (pinfunction "VCCAUX") (pintype "passive"))
    (pad "T11" smd circle (at -2.5 2.499 180) (size 0.5 0.5) (layers "F.Cu" "F.Paste" "F.Mask")
      (net 9 "GND") (pinfunction "GND") (pintype "passive"))
    (pad "T12" smd circle (at -1.5 2.499 180) (size 0.5 0.5) (layers "F.Cu" "F.Paste" "F.Mask")
      (net 147 "1V0_SYS") (pinfunction "VCCBRAM") (pintype "passive"))
    (pad "T13" smd circle (at -0.5 2.499 180) (size 0.5 0.5) (layers "F.Cu" "F.Paste" "F.Mask")
      (net 9 "GND") (pinfunction "GND") (pintype "passive"))
    (pad "T14" smd circle (at 0.499 2.499 180) (size 0.5 0.5) (layers "F.Cu" "F.Paste" "F.Mask")
      (net 147 "1V0_SYS") (pinfunction "VCCINT") (pintype "passive"))
    (pad "T15" smd circle (at 1.499 2.499 180) (size 0.5 0.5) (layers "F.Cu" "F.Paste" "F.Mask")
      (net 9 "GND") (pinfunction "GND") (pintype "passive"))
    (pad "T16" smd circle (at 2.499 2.499 180) (size 0.5 0.5) (layers "F.Cu" "F.Paste" "F.Mask")
      (net 77 "VDDQ") (pinfunction "VCCO_13") (pintype "passive"))
    (pad "T17" smd circle (at 3.499 2.499 180) (size 0.5 0.5) (layers "F.Cu" "F.Paste" "F.Mask")
      (net 257 "CB4") (pinfunction "IO_L23N_T3_13") (pintype "bidirectional") (die_length 10.353))
    (pad "T18" smd circle (at 4.499 2.499 180) (size 0.5 0.5) (layers "F.Cu" "F.Paste" "F.Mask")
      (net 258 "CB0") (pinfunction "IO_L19P_T3_13") (pintype "bidirectional") (die_length 9.92))
    (pad "T19" smd circle (at 5.499 2.499 180) (size 0.5 0.5) (layers "F.Cu" "F.Paste" "F.Mask")
      (net 873 "unconnected-(U15B-IO_L19N_T3_VREF_13-PadT19)") (pinfunction "IO_L19N_T3_VREF_13") (pintype "bidirectional+no_connect") (die_length 9.055))
    (pad "T20" smd circle (at 6.499 2.499 180) (size 0.5 0.5) (layers "F.Cu" "F.Paste" "F.Mask")
      (net 874 "unconnected-(U15B-IO_L16P_T2_13-PadT20)") (pinfunction "IO_L16P_T2_13") (pintype "bidirectional+no_connect") (die_length 9.491))
    (pad "T21" smd circle (at 7.499 2.499 180) (size 0.5 0.5) (layers "F.Cu" "F.Paste" "F.Mask")
      (net 9 "GND") (pinfunction "GND") (pintype "passive"))
    (pad "T22" smd circle (at 8.499 2.499 180) (size 0.5 0.5) (layers "F.Cu" "F.Paste" "F.Mask")
      (net 282 "CB7") (pinfunction "IO_L17P_T2_13") (pintype "bidirectional") (die_length 11.169))
    (pad "T23" smd circle (at 9.499 2.499 180) (size 0.5 0.5) (layers "F.Cu" "F.Paste" "F.Mask")
      (net 295 "CB3") (pinfunction "IO_L17N_T2_13") (pintype "bidirectional") (die_length 11.495))
    (pad "T24" smd circle (at 10.499 2.499 180) (size 0.5 0.5) (layers "F.Cu" "F.Paste" "F.Mask")
      (net 875 "unconnected-(U15B-IO_L15P_T2_DQS_13-PadT24)") (pinfunction "IO_L15P_T2_DQS_13") (pintype "bidirectional+no_connect") (die_length 13.293))
    (pad "T25" smd circle (at 11.499 2.499 180) (size 0.5 0.5) (layers "F.Cu" "F.Paste" "F.Mask")
      (net 876 "unconnected-(U15B-IO_L15N_T2_DQS_13-PadT25)") (pinfunction "IO_L15N_T2_DQS_13") (pintype "bidirectional+no_connect") (die_length 13.562))
    (pad "T26" smd circle (at 12.499 2.499 180) (size 0.5 0.5) (layers "F.Cu" "F.Paste" "F.Mask")
      (net 77 "VDDQ") (pinfunction "VCCO_13") (pintype "passive"))
    (pad "U1" smd circle (at -12.5 3.499 180) (size 0.5 0.5) (layers "F.Cu" "F.Paste" "F.Mask")
      (net 249 "DQ20") (pinfunction "IO_L2N_T0_34") (pintype "bidirectional") (die_length 17.749))
    (pad "U2" smd circle (at -11.5 3.499 180) (size 0.5 0.5) (layers "F.Cu" "F.Paste" "F.Mask")
      (net 246 "DQ8") (pinfunction "IO_L2P_T0_34") (pintype "bidirectional") (die_length 16.314))
    (pad "U3" smd circle (at -10.5 3.499 180) (size 0.5 0.5) (layers "F.Cu" "F.Paste" "F.Mask")
      (net 77 "VDDQ") (pinfunction "VCCO_34") (pintype "passive"))
    (pad "U4" smd circle (at -9.5 3.499 180) (size 0.5 0.5) (layers "F.Cu" "F.Paste" "F.Mask")
      (net 877 "unconnected-(U15H-IO_0_VRN_34-PadU4)") (pinfunction "IO_0_VRN_34") (pintype "bidirectional+no_connect") (die_length 17.697))
    (pad "U5" smd circle (at -8.5 3.499 180) (size 0.5 0.5) (layers "F.Cu" "F.Paste" "F.Mask")
      (net 242 "DQ0") (pinfunction "IO_L1N_T0_34") (pintype "bidirectional") (die_length 13.682))
    (pad "U6" smd circle (at -7.5 3.499 180) (size 0.5 0.5) (layers "F.Cu" "F.Paste" "F.Mask")
      (net 298 "DQ5") (pinfunction "IO_L1P_T0_34") (pintype "bidirectional") (die_length 13.683))
    (pad "U7" smd circle (at -6.5 3.499 180) (size 0.5 0.5) (layers "F.Cu" "F.Paste" "F.Mask")
      (net 241 "DQ4") (pinfunction "IO_L5P_T0_34") (pintype "bidirectional") (die_length 12.718))
    (pad "U8" smd circle (at -5.5 3.499 180) (size 0.5 0.5) (layers "F.Cu" "F.Paste" "F.Mask")
      (net 9 "GND") (pinfunction "GND") (pintype "passive"))
    (pad "U9" smd circle (at -4.5 3.499 180) (size 0.5 0.5) (layers "F.Cu" "F.Paste" "F.Mask")
      (net 309 "VRN") (pinfunction "IO_0_VRN_33") (pintype "bidirectional") (die_length 7.601))
    (pad "U10" smd circle (at -3.5 3.499 180) (size 0.5 0.5) (layers "F.Cu" "F.Paste" "F.Mask")
      (net 9 "GND") (pinfunction "GND") (pintype "passive"))
    (pad "U11" smd circle (at -2.5 3.499 180) (size 0.5 0.5) (layers "F.Cu" "F.Paste" "F.Mask")
      (net 144 "1V8_SYS") (pinfunction "VCCAUX") (pintype "passive"))
    (pad "U12" smd circle (at -1.5 3.499 180) (size 0.5 0.5) (layers "F.Cu" "F.Paste" "F.Mask")
      (net 9 "GND") (pinfunction "GND") (pintype "passive"))
    (pad "U13" smd circle (at -0.5 3.499 180) (size 0.5 0.5) (layers "F.Cu" "F.Paste" "F.Mask")
      (net 147 "1V0_SYS") (pinfunction "VCCBRAM") (pintype "passive"))
    (pad "U14" smd circle (at 0.499 3.499 180) (size 0.5 0.5) (layers "F.Cu" "F.Paste" "F.Mask")
      (net 9 "GND") (pinfunction "GND") (pintype "passive"))
    (pad "U15" smd circle (at 1.499 3.499 180) (size 0.5 0.5) (layers "F.Cu" "F.Paste" "F.Mask")
      (net 147 "1V0_SYS") (pinfunction "VCCINT") (pintype "passive"))
    (pad "U16" smd circle (at 2.499 3.499 180) (size 0.5 0.5) (layers "F.Cu" "F.Paste" "F.Mask")
      (net 278 "CB5") (pinfunction "IO_25_13") (pintype "bidirectional") (die_length 9.654))
    (pad "U17" smd circle (at 3.499 3.499 180) (size 0.5 0.5) (layers "F.Cu" "F.Paste" "F.Mask")
      (net 272 "CB1") (pinfunction "IO_L23P_T3_13") (pintype "bidirectional") (die_length 11.04))
    (pad "U18" smd circle (at 4.499 3.499 180) (size 0.5 0.5) (layers "F.Cu" "F.Paste" "F.Mask")
      (net 9 "GND") (pinfunction "GND") (pintype "passive"))
    (pad "U19" smd circle (at 5.499 3.499 180) (size 0.5 0.5) (layers "F.Cu" "F.Paste" "F.Mask")
      (net 878 "unconnected-(U15B-IO_L18P_T2_13-PadU19)") (pinfunction "IO_L18P_T2_13") (pintype "bidirectional+no_connect") (die_length 8.112))
    (pad "U20" smd circle (at 6.499 3.499 180) (size 0.5 0.5) (layers "F.Cu" "F.Paste" "F.Mask")
      (net 879 "unconnected-(U15B-IO_L18N_T2_13-PadU20)") (pinfunction "IO_L18N_T2_13") (pintype "bidirectional+no_connect") (die_length 9.928))
    (pad "U21" smd circle (at 7.499 3.499 180) (size 0.5 0.5) (layers "F.Cu" "F.Paste" "F.Mask")
      (net 880 "unconnected-(U15A-IO_0_12-PadU21)") (pinfunction "IO_0_12") (pintype "bidirectional+no_connect") (die_length 9.631))
    (pad "U22" smd circle (at 8.499 3.499 180) (size 0.5 0.5) (layers "F.Cu" "F.Paste" "F.Mask")
      (net 881 "unconnected-(U15A-IO_L1P_T0_12-PadU22)") (pinfunction "IO_L1P_T0_12") (pintype "bidirectional+no_connect") (die_length 10.705))
    (pad "U23" smd circle (at 9.499 3.499 180) (size 0.5 0.5) (layers "F.Cu" "F.Paste" "F.Mask")
      (net 143 "3V3_SYS") (pinfunction "VCCO_12") (pintype "passive"))
    (pad "U24" smd circle (at 10.499 3.499 180) (size 0.5 0.5) (layers "F.Cu" "F.Paste" "F.Mask")
      (net 796 "ETH_SEL") (pinfunction "IO_L2P_T0_12") (pintype "bidirectional") (die_length 12.37))
    (pad "U25" smd circle (at 11.499 3.499 180) (size 0.5 0.5) (layers "F.Cu" "F.Paste" "F.Mask")
      (net 37 "ETH_RXD3") (pinfunction "IO_L2N_T0_12") (pintype "bidirectional") (die_length 14.162))
    (pad "U26" smd circle (at 12.499 3.499 180) (size 0.5 0.5) (layers "F.Cu" "F.Paste" "F.Mask")
      (net 35 "ETH_TX_EN") (pinfunction "IO_L4P_T0_12") (pintype "bidirectional") (die_length 15.43))
    (pad "V1" smd circle (at -12.5 4.499 180) (size 0.5 0.5) (layers "F.Cu" "F.Paste" "F.Mask")
      (net 250 "DQ16") (pinfunction "IO_L8N_T1_34") (pintype "bidirectional") (die_length 17.73))
    (pad "V2" smd circle (at -11.5 4.499 180) (size 0.5 0.5) (layers "F.Cu" "F.Paste" "F.Mask")
      (net 294 "DQ21") (pinfunction "IO_L8P_T1_34") (pintype "bidirectional") (die_length 16.717))
    (pad "V3" smd circle (at -10.5 4.499 180) (size 0.5 0.5) (layers "F.Cu" "F.Paste" "F.Mask")
      (net 319 "DQS10_P") (pinfunction "IO_L4P_T0_34") (pintype "bidirectional") (die_length 16.996))
    (pad "V4" smd circle (at -9.5 4.499 180) (size 0.5 0.5) (layers "F.Cu" "F.Paste" "F.Mask")
      (net 275 "DQ13") (pinfunction "IO_L6P_T0_34") (pintype "bidirectional") (die_length 16.475))
    (pad "V5" smd circle (at -8.5 4.499 180) (size 0.5 0.5) (layers "F.Cu" "F.Paste" "F.Mask")
      (net 9 "GND") (pinfunction "GND") (pintype "passive"))
    (pad "V6" smd circle (at -7.5 4.499 180) (size 0.5 0.5) (layers "F.Cu" "F.Paste" "F.Mask")
      (net 288 "DQ1") (pinfunction "IO_L5N_T0_34") (pintype "bidirectional") (die_length 13.667))
    (pad "V7" smd circle (at -6.5 4.499 180) (size 0.5 0.5) (layers "F.Cu" "F.Paste" "F.Mask")
      (net 882 "unconnected-(U15G-IO_L2N_T0_33-PadV7)") (pinfunction "IO_L2N_T0_33") (pintype "bidirectional+no_connect") (die_length 12.123))
    (pad "V8" smd circle (at -5.5 4.499 180) (size 0.5 0.5) (layers "F.Cu" "F.Paste" "F.Mask")
      (net 889 "unconnected-(U15G-IO_L2P_T0_33-PadV8)") (pinfunction "IO_L2P_T0_33") (pintype "bidirectional+no_connect") (die_length 11.194))
    (pad "V9" smd circle (at -4.5 4.499 180) (size 0.5 0.5) (layers "F.Cu" "F.Paste" "F.Mask")
      (net 237 "~{CS0}") (pinfunction "IO_L6P_T0_33") (pintype "bidirectional") (die_length 10.483))
    (pad "V10" smd circle (at -3.5 4.499 180) (size 0.5 0.5) (layers "F.Cu" "F.Paste" "F.Mask")
      (net 77 "VDDQ") (pinfunction "VCCO_33") (pintype "passive"))
    (pad "V11" smd circle (at -2.5 4.499 180) (size 0.5 0.5) (layers "F.Cu" "F.Paste" "F.Mask")
      (net 230 "~{CS2}\\C0") (pinfunction "IO_L1P_T0_33") (pintype "bidirectional") (die_length 9.051))
    (pad "V12" smd circle (at -1.5 4.499 180) (size 0.5 0.5) (layers "F.Cu" "F.Paste" "F.Mask")
      (net 310 "VRP") (pinfunction "IO_25_VRP_33") (pintype "bidirectional") (die_length 8.364))
    (pad "V13" smd circle (at -0.5 4.499 180) (size 0.5 0.5) (layers "F.Cu" "F.Paste" "F.Mask")
      (net 890 "unconnected-(U15F-IO_0_VRN_32-PadV13)") (pinfunction "IO_0_VRN_32") (pintype "bidirectional+no_connect") (die_length 8.061))
    (pad "V14" smd circle (at 0.499 4.499 180) (size 0.5 0.5) (layers "F.Cu" "F.Paste" "F.Mask")
      (net 215 "DQ56") (pinfunction "IO_L24P_T3_32") (pintype "bidirectional") (die_length 12.558))
    (pad "V15" smd circle (at 1.499 4.499 180) (size 0.5 0.5) (layers "F.Cu" "F.Paste" "F.Mask")
      (net 9 "GND") (pinfunction "GND") (pintype "passive"))
    (pad "V16" smd circle (at 2.499 4.499 180) (size 0.5 0.5) (layers "F.Cu" "F.Paste" "F.Mask")
      (net 342 "DQS7_P") (pinfunction "IO_L20P_T3_32") (pintype "bidirectional") (die_length 18.47))
    (pad "V17" smd circle (at 3.499 4.499 180) (size 0.5 0.5) (layers "F.Cu" "F.Paste" "F.Mask")
      (net 344 "DQS7_N") (pinfunction "IO_L20N_T3_32") (pintype "bidirectional") (die_length 18.818))
    (pad "V18" smd circle (at 4.499 4.499 180) (size 0.5 0.5) (layers "F.Cu" "F.Paste" "F.Mask")
      (net 197 "DQ63") (pinfunction "IO_L23P_T3_32") (pintype "bidirectional") (die_length 17.507))
    (pad "V19" smd circle (at 5.499 4.499 180) (size 0.5 0.5) (layers "F.Cu" "F.Paste" "F.Mask")
      (net 196 "DQ59") (pinfunction "IO_L23N_T3_32") (pintype "bidirectional") (die_length 18.005))
    (pad "V20" smd circle (at 6.499 4.499 180) (size 0.5 0.5) (layers "F.Cu" "F.Paste" "F.Mask")
      (net 143 "3V3_SYS") (pinfunction "VCCO_12") (pintype "passive"))
    (pad "V21" smd circle (at 7.499 4.499 180) (size 0.5 0.5) (layers "F.Cu" "F.Paste" "F.Mask")
      (net 901 "unconnected-(U15A-IO_L6P_T0_12-PadV21)") (pinfunction "IO_L6P_T0_12") (pintype "bidirectional+no_connect") (die_length 8.805))
    (pad "V22" smd circle (at 8.499 4.499 180) (size 0.5 0.5) (layers "F.Cu" "F.Paste" "F.Mask")
      (net 902 "unconnected-(U15A-IO_L1N_T0_12-PadV22)") (pinfunction "IO_L1N_T0_12") (pintype "bidirectional+no_connect") (die_length 10.787))
    (pad "V23" smd circle (at 9.499 4.499 180) (size 0.5 0.5) (layers "F.Cu" "F.Paste" "F.Mask")
      (net 905 "unconnected-(U15A-IO_L3P_T0_DQS_12-PadV23)") (pinfunction "IO_L3P_T0_DQS_12") (pintype "bidirectional+no_connect") (die_length 12.224))
    (pad "V24" smd circle (at 10.499 4.499 180) (size 0.5 0.5) (layers "F.Cu" "F.Paste" "F.Mask")
      (net 906 "unconnected-(U15A-IO_L3N_T0_DQS_12-PadV24)") (pinfunction "IO_L3N_T0_DQS_12") (pintype "bidirectional+no_connect") (die_length 12.691))
    (pad "V25" smd circle (at 11.499 4.499 180) (size 0.5 0.5) (layers "F.Cu" "F.Paste" "F.Mask")
      (net 9 "GND") (pinfunction "GND") (pintype "passive"))
    (pad "V26" smd circle (at 12.499 4.499 180) (size 0.5 0.5) (layers "F.Cu" "F.Paste" "F.Mask")
      (net 41 "ETH_RXD2") (pinfunction "IO_L4N_T0_12") (pintype "bidirectional") (die_length 15.219))
    (pad "W1" smd circle (at -12.5 5.499 180) (size 0.5 0.5) (layers "F.Cu" "F.Paste" "F.Mask")
      (net 323 "DQS11_P") (pinfunction "IO_L10P_T1_34") (pintype "bidirectional") (die_length 18.423))
    (pad "W2" smd circle (at -11.5 5.499 180) (size 0.5 0.5) (layers "F.Cu" "F.Paste" "F.Mask")
      (net 9 "GND") (pinfunction "GND") (pintype "passive"))
    (pad "W3" smd circle (at -10.5 5.499 180) (size 0.5 0.5) (layers "F.Cu" "F.Paste" "F.Mask")
      (net 321 "DQS10_N") (pinfunction "IO_L4N_T0_34") (pintype "bidirectional") (die_length 18.698))
    (pad "W4" smd circle (at -9.5 5.499 180) (size 0.5 0.5) (layers "F.Cu" "F.Paste" "F.Mask")
      (net 245 "DQ12") (pinfunction "IO_L6N_T0_VREF_34") (pintype "bidirectional") (die_length 18.8))
    (pad "W5" smd circle (at -8.5 5.499 180) (size 0.5 0.5) (layers "F.Cu" "F.Paste" "F.Mask")
      (net 317 "DQS9_N") (pinfunction "IO_L3N_T0_DQS_34") (pintype "bidirectional") (die_length 17.539))
    (pad "W6" smd circle (at -7.5 5.499 180) (size 0.5 0.5) (layers "F.Cu" "F.Paste" "F.Mask")
      (net 316 "DQS9_P") (pinfunction "IO_L3P_T0_DQS_34") (pintype "bidirectional") (die_length 17.741))
    (pad "W7" smd circle (at -6.5 5.499 180) (size 0.5 0.5) (layers "F.Cu" "F.Paste" "F.Mask")
      (net 77 "VDDQ") (pinfunction "VCCO_33") (pintype "passive"))
    (pad "W8" smd circle (at -5.5 5.499 180) (size 0.5 0.5) (layers "F.Cu" "F.Paste" "F.Mask")
      (net 909 "unconnected-(U15G-IO_L6N_T0_VREF_33-PadW8)") (pinfunction "IO_L6N_T0_VREF_33") (pintype "bidirectional+no_connect") (die_length 12.359))
    (pad "W9" smd circle (at -4.5 5.499 180) (size 0.5 0.5) (layers "F.Cu" "F.Paste" "F.Mask")
      (net 231 "ODT1\\NC") (pinfunction "IO_L3N_T0_DQS_33") (pintype "bidirectional") (die_length 12.347))
    (pad "W10" smd circle (at -3.5 5.499 180) (size 0.5 0.5) (layers "F.Cu" "F.Paste" "F.Mask")
      (net 201 "NC\\C2") (pinfunction "IO_L3P_T0_DQS_33") (pintype "bidirectional") (die_length 12.577))
    (pad "W11" smd circle (at -2.5 5.499 180) (size 0.5 0.5) (layers "F.Cu" "F.Paste" "F.Mask")
      (net 198 "~{CS3}\\C1,NC") (pinfunction "IO_L1N_T0_33") (pintype "bidirectional") (die_length 9.991))
    (pad "W12" smd circle (at -1.5 5.499 180) (size 0.5 0.5) (layers "F.Cu" "F.Paste" "F.Mask")
      (net 9 "GND") (pinfunction "GND") (pintype "passive"))
    (pad "W13" smd circle (at -0.5 5.499 180) (size 0.5 0.5) (layers "F.Cu" "F.Paste" "F.Mask")
      (net 910 "unconnected-(U15F-IO_25_VRP_32-PadW13)") (pinfunction "IO_25_VRP_32") (pintype "bidirectional+no_connect") (die_length 8.841))
    (pad "W14" smd circle (at 0.499 5.499 180) (size 0.5 0.5) (layers "F.Cu" "F.Paste" "F.Mask")
      (net 221 "DQ60") (pinfunction "IO_L24N_T3_32") (pintype "bidirectional") (die_length 12.441))
    (pad "W15" smd circle (at 1.499 5.499 180) (size 0.5 0.5) (layers "F.Cu" "F.Paste" "F.Mask")
      (net 343 "DQS16_P") (pinfunction "IO_L22P_T3_32") (pintype "bidirectional") (die_length 13.547))
    (pad "W16" smd circle (at 2.499 5.499 180) (size 0.5 0.5) (layers "F.Cu" "F.Paste" "F.Mask")
      (net 345 "DQS16_N") (pinfunction "IO_L22N_T3_32") (pintype "bidirectional") (die_length 15.068))
    (pad "W17" smd circle (at 3.499 5.499 180) (size 0.5 0.5) (layers "F.Cu" "F.Paste" "F.Mask")
      (net 77 "VDDQ") (pinfunction "VCCO_32") (pintype "passive"))
    (pad "W18" smd circle (at 4.499 5.499 180) (size 0.5 0.5) (layers "F.Cu" "F.Paste" "F.Mask")
      (net 217 "DQ62") (pinfunction "IO_L21P_T3_DQS_32") (pintype "bidirectional") (die_length 16.431))
    (pad "W19" smd circle (at 5.499 5.499 180) (size 0.5 0.5) (layers "F.Cu" "F.Paste" "F.Mask")
      (net 216 "DQ58") (pinfunction "IO_L21N_T3_DQS_32") (pintype "bidirectional") (die_length 16.437))
    (pad "W20" smd circle (at 6.499 5.499 180) (size 0.5 0.5) (layers "F.Cu" "F.Paste" "F.Mask")
      (net 911 "unconnected-(U15A-IO_L15P_T2_DQS_12-PadW20)") (pinfunction "IO_L15P_T2_DQS_12") (pintype "bidirectional+no_connect") (die_length 9.921))
    (pad "W21" smd circle (at 7.499 5.499 180) (size 0.5 0.5) (layers "F.Cu" "F.Paste" "F.Mask")
      (net 912 "unconnected-(U15A-IO_L6N_T0_VREF_12-PadW21)") (pinfunction "IO_L6N_T0_VREF_12") (pintype "bidirectional+no_connect") (die_length 9.947))
    (pad "W22" smd circle (at 8.499 5.499 180) (size 0.5 0.5) (layers "F.Cu" "F.Paste" "F.Mask")
      (net 9 "GND") (pinfunction "GND") (pintype "passive"))
    (pad "W23" smd circle (at 9.499 5.499 180) (size 0.5 0.5) (layers "F.Cu" "F.Paste" "F.Mask")
      (net 913 "unconnected-(U15A-IO_L8P_T1_12-PadW23)") (pinfunction "IO_L8P_T1_12") (pintype "bidirectional+no_connect") (die_length 12.009))
    (pad "W24" smd circle (at 10.499 5.499 180) (size 0.5 0.5) (layers "F.Cu" "F.Paste" "F.Mask")
      (net 36 "ETH_TXD0") (pinfunction "IO_L8N_T1_12") (pintype "bidirectional") (die_length 13.111))
    (pad "W25" smd circle (at 11.499 5.499 180) (size 0.5 0.5) (layers "F.Cu" "F.Paste" "F.Mask")
      (net 27 "ETH_RXD1") (pinfunction "IO_L5P_T0_12") (pintype "bidirectional") (die_length 14.107))
    (pad "W26" smd circle (at 12.499 5.499 180) (size 0.5 0.5) (layers "F.Cu" "F.Paste" "F.Mask")
      (net 26 "ETH_RXD0") (pinfunction "IO_L5N_T0_12") (pintype "bidirectional") (die_length 15.45))
    (pad "Y1" smd circle (at -12.5 6.499 180) (size 0.5 0.5) (layers "F.Cu" "F.Paste" "F.Mask")
      (net 325 "DQS11_N") (pinfunction "IO_L10N_T1_34") (pintype "bidirectional") (die_length 20.111))
    (pad "Y2" smd circle (at -11.5 6.499 180) (size 0.5 0.5) (layers "F.Cu" "F.Paste" "F.Mask")
      (net 281 "DQ17") (pinfunction "IO_L7N_T1_34") (pintype "bidirectional") (die_length 18.743))
    (pad "Y3" smd circle (at -10.5 6.499 180) (size 0.5 0.5) (layers "F.Cu" "F.Paste" "F.Mask")
      (net 293 "DQ9") (pinfunction "IO_L7P_T1_34") (pintype "bidirectional") (die_length 18.285))
    (pad "Y4" smd circle (at -9.5 6.499 180) (size 0.5 0.5) (layers "F.Cu" "F.Paste" "F.Mask")
      (net 77 "VDDQ") (pinfunction "VCCO_34") (pintype "passive"))
    (pad "Y5" smd circle (at -8.5 6.499 180) (size 0.5 0.5) (layers "F.Cu" "F.Paste" "F.Mask")
      (net 315 "DQS0_N") (pinfunction "IO_L17N_T2_34") (pintype "bidirectional") (die_length 15.693))
    (pad "Y6" smd circle (at -7.5 6.499 180) (size 0.5 0.5) (layers "F.Cu" "F.Paste" "F.Mask")
      (net 314 "DQS0_P") (pinfunction "IO_L17P_T2_34") (pintype "bidirectional") (die_length 17.912))
    (pad "Y7" smd circle (at -6.5 6.499 180) (size 0.5 0.5) (layers "F.Cu" "F.Paste" "F.Mask")
      (net 658 "Net-(U15G-IO_L4N_T0_33)") (pinfunction "IO_L4N_T0_33") (pintype "bidirectional") (die_length 13.835))
    (pad "Y8" smd circle (at -5.5 6.499 180) (size 0.5 0.5) (layers "F.Cu" "F.Paste" "F.Mask")
      (net 264 "~{ACT}") (pinfunction "IO_L4P_T0_33") (pintype "bidirectional") (die_length 13.201))
    (pad "Y9" smd circle (at -4.5 6.499 180) (size 0.5 0.5) (layers "F.Cu" "F.Paste" "F.Mask")
      (net 9 "GND") (pinfunction "GND") (pintype "passive"))
    (pad "Y10" smd circle (at -3.5 6.499 180) (size 0.5 0.5) (layers "F.Cu" "F.Paste" "F.Mask")
      (net 209 "~{SAVE}") (pinfunction "IO_L5N_T0_33") (pintype "bidirectional") (die_length 14.206))
    (pad "Y11" smd circle (at -2.5 6.499 180) (size 0.5 0.5) (layers "F.Cu" "F.Paste" "F.Mask")
      (net 234 "~{CS1}\\NC") (pinfunction "IO_L5P_T0_33") (pintype "bidirectional") (die_length 15.036))
    (pad "Y12" smd circle (at -1.5 6.499 180) (size 0.5 0.5) (layers "F.Cu" "F.Paste" "F.Mask")
      (net 208 "A10\\AP") (pinfunction "IO_L18N_T2_33") (pintype "bidirectional") (die_length 14.615))
    (pad "Y13" smd circle (at -0.5 6.499 180) (size 0.5 0.5) (layers "F.Cu" "F.Paste" "F.Mask")
      (net 235 "ODT0") (pinfunction "IO_L18P_T2_33") (pintype "bidirectional") (die_length 15.191))
    (pad "Y14" smd circle (at 0.499 6.499 180) (size 0.5 0.5) (layers "F.Cu" "F.Paste" "F.Mask")
      (net 77 "VDDQ") (pinfunction "VCCO_32") (pintype "passive"))
    (pad "Y15" smd circle (at 1.499 6.499 180) (size 0.5 0.5) (layers "F.Cu" "F.Paste" "F.Mask")
      (net 191 "DQ61") (pinfunction "IO_L9P_T1_DQS_32") (pintype "bidirectional") (die_length 13.423))
    (pad "Y16" smd circle (at 2.499 6.499 180) (size 0.5 0.5) (layers "F.Cu" "F.Paste" "F.Mask")
      (net 192 "DQ57") (pinfunction "IO_L9N_T1_DQS_32") (pintype "bidirectional") (die_length 13.009))
    (pad "Y17" smd circle (at 3.499 6.499 180) (size 0.5 0.5) (layers "F.Cu" "F.Paste" "F.Mask")
      (net 338 "DQS6_P") (pinfunction "IO_L19P_T3_32") (pintype "bidirectional") (die_length 15.853))
    (pad "Y18" smd circle (at 4.499 6.499 180) (size 0.5 0.5) (layers "F.Cu" "F.Paste" "F.Mask")
      (net 340 "DQS6_N") (pinfunction "IO_L19N_T3_VREF_32") (pintype "bidirectional") (die_length 15))
    (pad "Y19" smd circle (at 5.499 6.499 180) (size 0.5 0.5) (layers "F.Cu" "F.Paste" "F.Mask")
      (net 9 "GND") (pinfunction "GND") (pintype "passive"))
    (pad "Y20" smd circle (at 6.499 6.499 180) (size 0.5 0.5) (layers "F.Cu" "F.Paste" "F.Mask")
      (net 183 "ETH_INT_N") (pinfunction "IO_25_12") (pintype "bidirectional") (die_length 8.585))
    (pad "Y21" smd circle (at 7.499 6.499 180) (size 0.5 0.5) (layers "F.Cu" "F.Paste" "F.Mask")
      (net 33 "ETH_TXD3") (pinfunction "IO_L15N_T2_DQS_12") (pintype "bidirectional") (die_length 9.864))
    (pad "Y22" smd circle (at 8.499 6.499 180) (size 0.5 0.5) (layers "F.Cu" "F.Paste" "F.Mask")
      (net 32 "ETH_TXD2") (pinfunction "IO_L13P_T2_MRCC_12") (pintype "bidirectional") (die_length 11.571))
    (pad "Y23" smd circle (at 9.499 6.499 180) (size 0.5 0.5) (layers "F.Cu" "F.Paste" "F.Mask")
      (net 40 "ETH_RX_CLK") (pinfunction "IO_L12P_T1_MRCC_12") (pintype "bidirectional") (die_length 12.692))
    (pad "Y24" smd circle (at 10.499 6.499 180) (size 0.5 0.5) (layers "F.Cu" "F.Paste" "F.Mask")
      (net 143 "3V3_SYS") (pinfunction "VCCO_12") (pintype "passive"))
    (pad "Y25" smd circle (at 11.499 6.499 180) (size 0.5 0.5) (layers "F.Cu" "F.Paste" "F.Mask")
      (net 38 "ETH_RX_DV") (pinfunction "IO_L10P_T1_12") (pintype "bidirectional") (die_length 14.135))
    (pad "Y26" smd circle (at 12.499 6.499 180) (size 0.5 0.5) (layers "F.Cu" "F.Paste" "F.Mask")
      (net 31 "ETH_TXD1") (pinfunction "IO_L10N_T1_12") (pintype "bidirectional") (die_length 15.98))
  )

  (footprint "data-center-rdimm-ddr4-tester-footprints:Bus_DDR4_Socket_DIMM_2199155-1" (layer "F.Cu")
    (at 246.636328 55.060008 180)
    (property "Author" "Antmicro")
    (property "License" "Apache-2.0")
    (property "MPN" "2199155-1")
    (property "Manufacturer" "TE Connectivity")
    (property "Sheetfile" "DDR4.kicad_sch")
    (property "Sheetname" "DDR4")
    (property "ki_description" "DDR4 RDIMM 288 Pin SMT type")
    (attr smd)
    (fp_text reference "U14" (at -5.583672 1.360008 180) (layer "F.SilkS")
        (effects (font (size 0.7 0.7) (thickness 0.15)) (justify left bottom))
    )
    (fp_text value "Bus_DDR4_2199155-1" (at -7.9 2.3 180) (layer "F.Fab") hide
        (effects (font (size 0.7 0.7) (thickness 0.15)) (justify left bottom))
    )
    (fp_text user "${REFERENCE}" (at -7.901 3.7 180) (layer "F.Fab") hide
        (effects (font (size 0.7 0.7) (thickness 0.15)) (justify left bottom))
    )
    (fp_text user "License: Apache-2.0" (at -7.901 6.402 180) (layer "F.Fab") hide
        (effects (font (size 0.7 0.7) (thickness 0.15)) (justify left bottom))
    )
    (fp_text user "Author: Antmicro" (at -7.901 5 180) (layer "F.Fab") hide
        (effects (font (size 0.7 0.7) (thickness 0.15)) (justify left bottom))
    )
    (fp_circle (center -0.4 1.1) (end -0.35 1.15)
      (stroke (width 0.15) (type solid)) (fill solid) (layer "F.SilkS"))
    (fp_rect (start -7.776 -5.751) (end 134.425 1.15)
      (stroke (width 0.05) (type solid)) (fill none) (layer "F.CrtYd"))
    (pad "1" smd rect (at 0 0 270) (size 1.8 0.57) (layers "F.Cu" "F.Paste" "F.Mask")
      (net 308 "NC") (pinfunction "12V/NC") (pintype "passive"))
    (pad "2" smd rect (at 0.848 0 270) (size 1.8 0.57) (layers "F.Cu" "F.Paste" "F.Mask")
      (net 9 "GND") (pinfunction "VSS") (pintype "passive"))
    (pad "3" smd rect (at 1.699 0 270) (size 1.8 0.57) (layers "F.Cu" "F.Paste" "F.Mask")
      (net 241 "DQ4") (pinfunction "DQ4") (pintype "passive"))
    (pad "4" smd rect (at 2.548 0 270) (size 1.8 0.57) (layers "F.Cu" "F.Paste" "F.Mask")
      (net 9 "GND") (pinfunction "VSS") (pintype "passive"))
    (pad "5" smd rect (at 3.398 0 270) (size 1.8 0.57) (layers "F.Cu" "F.Paste" "F.Mask")
      (net 242 "DQ0") (pinfunction "DQ0") (pintype "passive"))
    (pad "6" smd rect (at 4.248 0 270) (size 1.8 0.57) (layers "F.Cu" "F.Paste" "F.Mask")
      (net 9 "GND") (pinfunction "VSS") (pintype "passive"))
    (pad "7" smd rect (at 5.099 0 270) (size 1.8 0.57) (layers "F.Cu" "F.Paste" "F.Mask")
      (net 316 "DQS9_P") (pinfunction "DQS9_t") (pintype "passive"))
    (pad "8" smd rect (at 5.95 0 270) (size 1.8 0.57) (layers "F.Cu" "F.Paste" "F.Mask")
      (net 317 "DQS9_N") (pinfunction "DQS9_c") (pintype "passive"))
    (pad "9" smd rect (at 6.799 0 270) (size 1.8 0.57) (layers "F.Cu" "F.Paste" "F.Mask")
      (net 9 "GND") (pinfunction "VSS") (pintype "passive"))
    (pad "10" smd rect (at 7.65 0 270) (size 1.8 0.57) (layers "F.Cu" "F.Paste" "F.Mask")
      (net 244 "DQ6") (pinfunction "DQ6") (pintype "passive"))
    (pad "11" smd rect (at 8.499 0 270) (size 1.8 0.57) (layers "F.Cu" "F.Paste" "F.Mask")
      (net 9 "GND") (pinfunction "VSS") (pintype "passive"))
    (pad "12" smd rect (at 9.349 0 270) (size 1.8 0.57) (layers "F.Cu" "F.Paste" "F.Mask")
      (net 243 "DQ2") (pinfunction "DQ2") (pintype "passive"))
    (pad "13" smd rect (at 10.198 0 270) (size 1.8 0.57) (layers "F.Cu" "F.Paste" "F.Mask")
      (net 9 "GND") (pinfunction "VSS") (pintype "passive"))
    (pad "14" smd rect (at 11.05 0 270) (size 1.8 0.57) (layers "F.Cu" "F.Paste" "F.Mask")
      (net 245 "DQ12") (pinfunction "DQ12") (pintype "passive"))
    (pad "15" smd rect (at 11.9 0 270) (size 1.8 0.57) (layers "F.Cu" "F.Paste" "F.Mask")
      (net 9 "GND") (pinfunction "VSS") (pintype "passive"))
    (pad "16" smd rect (at 12.749 0 270) (size 1.8 0.57) (layers "F.Cu" "F.Paste" "F.Mask")
      (net 246 "DQ8") (pinfunction "DQ8") (pintype "passive"))
    (pad "17" smd rect (at 13.598 0 270) (size 1.8 0.57) (layers "F.Cu" "F.Paste" "F.Mask")
      (net 9 "GND") (pinfunction "VSS") (pintype "passive"))
    (pad "18" smd rect (at 14.448 0 270) (size 1.8 0.57) (layers "F.Cu" "F.Paste" "F.Mask")
      (net 319 "DQS10_P") (pinfunction "DQS10_t") (pintype "passive"))
    (pad "19" smd rect (at 15.3 0 270) (size 1.8 0.57) (layers "F.Cu" "F.Paste" "F.Mask")
      (net 321 "DQS10_N") (pinfunction "DQS10_c") (pintype "passive"))
    (pad "20" smd rect (at 16.149 0 270) (size 1.8 0.57) (layers "F.Cu" "F.Paste" "F.Mask")
      (net 9 "GND") (pinfunction "VSS") (pintype "passive"))
    (pad "21" smd rect (at 16.998 0 270) (size 1.8 0.57) (layers "F.Cu" "F.Paste" "F.Mask")
      (net 247 "DQ14") (pinfunction "DQ14") (pintype "passive"))
    (pad "22" smd rect (at 17.85 0 270) (size 1.8 0.57) (layers "F.Cu" "F.Paste" "F.Mask")
      (net 9 "GND") (pinfunction "VSS") (pintype "passive"))
    (pad "23" smd rect (at 18.699 0 270) (size 1.8 0.57) (layers "F.Cu" "F.Paste" "F.Mask")
      (net 248 "DQ10") (pinfunction "DQ10") (pintype "passive"))
    (pad "24" smd rect (at 19.55 0 270) (size 1.8 0.57) (layers "F.Cu" "F.Paste" "F.Mask")
      (net 9 "GND") (pinfunction "VSS") (pintype "passive"))
    (pad "25" smd rect (at 20.399 0 270) (size 1.8 0.57) (layers "F.Cu" "F.Paste" "F.Mask")
      (net 249 "DQ20") (pinfunction "DQ20") (pintype "passive"))
    (pad "26" smd rect (at 21.248 0 270) (size 1.8 0.57) (layers "F.Cu" "F.Paste" "F.Mask")
      (net 9 "GND") (pinfunction "VSS") (pintype "passive"))
    (pad "27" smd rect (at 22.1 0 270) (size 1.8 0.57) (layers "F.Cu" "F.Paste" "F.Mask")
      (net 250 "DQ16") (pinfunction "DQ16") (pintype "passive"))
    (pad "28" smd rect (at 22.949 0 270) (size 1.8 0.57) (layers "F.Cu" "F.Paste" "F.Mask")
      (net 9 "GND") (pinfunction "VSS") (pintype "passive"))
    (pad "29" smd rect (at 23.8 0 270) (size 1.8 0.57) (layers "F.Cu" "F.Paste" "F.Mask")
      (net 323 "DQS11_P") (pinfunction "DQS11_t") (pintype "passive"))
    (pad "30" smd rect (at 24.649 0 270) (size 1.8 0.57) (layers "F.Cu" "F.Paste" "F.Mask")
      (net 325 "DQS11_N") (pinfunction "DQS11_c") (pintype "passive"))
    (pad "31" smd rect (at 25.498 0 270) (size 1.8 0.57) (layers "F.Cu" "F.Paste" "F.Mask")
      (net 9 "GND") (pinfunction "VSS") (pintype "passive"))
    (pad "32" smd rect (at 26.35 0 270) (size 1.8 0.57) (layers "F.Cu" "F.Paste" "F.Mask")
      (net 251 "DQ22") (pinfunction "DQ22") (pintype "passive"))
    (pad "33" smd rect (at 27.199 0 270) (size 1.8 0.57) (layers "F.Cu" "F.Paste" "F.Mask")
      (net 9 "GND") (pinfunction "VSS") (pintype "passive"))
    (pad "34" smd rect (at 28.05 0 270) (size 1.8 0.57) (layers "F.Cu" "F.Paste" "F.Mask")
      (net 253 "DQ18") (pinfunction "DQ18") (pintype "passive"))
    (pad "35" smd rect (at 28.899 0 270) (size 1.8 0.57) (layers "F.Cu" "F.Paste" "F.Mask")
      (net 9 "GND") (pinfunction "VSS") (pintype "passive"))
    (pad "36" smd rect (at 29.749 0 270) (size 1.8 0.57) (layers "F.Cu" "F.Paste" "F.Mask")
      (net 252 "DQ28") (pinfunction "DQ28") (pintype "passive"))
    (pad "37" smd rect (at 30.6 0 270) (size 1.8 0.57) (layers "F.Cu" "F.Paste" "F.Mask")
      (net 9 "GND") (pinfunction "VSS") (pintype "passive"))
    (pad "38" smd rect (at 31.449 0 270) (size 1.8 0.57) (layers "F.Cu" "F.Paste" "F.Mask")
      (net 254 "DQ24") (pinfunction "DQ24") (pintype "passive"))
    (pad "39" smd rect (at 32.298 0 270) (size 1.8 0.57) (layers "F.Cu" "F.Paste" "F.Mask")
      (net 9 "GND") (pinfunction "VSS") (pintype "passive"))
    (pad "40" smd rect (at 33.149 0 270) (size 1.8 0.57) (layers "F.Cu" "F.Paste" "F.Mask")
      (net 327 "DQS12_P") (pinfunction "DQS12_t") (pintype "passive"))
    (pad "41" smd rect (at 33.999 0 270) (size 1.8 0.57) (layers "F.Cu" "F.Paste" "F.Mask")
      (net 329 "DQS12_N") (pinfunction "DQS12_c") (pintype "passive"))
    (pad "42" smd rect (at 34.85 0 270) (size 1.8 0.57) (layers "F.Cu" "F.Paste" "F.Mask")
      (net 9 "GND") (pinfunction "VSS") (pintype "passive"))
    (pad "43" smd rect (at 35.7 0 270) (size 1.8 0.57) (layers "F.Cu" "F.Paste" "F.Mask")
      (net 255 "DQ30") (pinfunction "DQ30") (pintype "passive"))
    (pad "44" smd rect (at 36.548 0 270) (size 1.8 0.57) (layers "F.Cu" "F.Paste" "F.Mask")
      (net 9 "GND") (pinfunction "VSS") (pintype "passive"))
    (pad "45" smd rect (at 37.399 0 270) (size 1.8 0.57) (layers "F.Cu" "F.Paste" "F.Mask")
      (net 256 "DQ26") (pinfunction "DQ26") (pintype "passive"))
    (pad "46" smd rect (at 38.249 0 270) (size 1.8 0.57) (layers "F.Cu" "F.Paste" "F.Mask")
      (net 9 "GND") (pinfunction "VSS") (pintype "passive"))
    (pad "47" smd rect (at 39.1 0 270) (size 1.8 0.57) (layers "F.Cu" "F.Paste" "F.Mask")
      (net 257 "CB4") (pinfunction "CB4") (pintype "passive"))
    (pad "48" smd rect (at 39.95 0 270) (size 1.8 0.57) (layers "F.Cu" "F.Paste" "F.Mask")
      (net 9 "GND") (pinfunction "VSS") (pintype "passive"))
    (pad "49" smd rect (at 40.798 0 270) (size 1.8 0.57) (layers "F.Cu" "F.Paste" "F.Mask")
      (net 258 "CB0") (pinfunction "CB0") (pintype "passive"))
    (pad "50" smd rect (at 41.649 0 270) (size 1.8 0.57) (layers "F.Cu" "F.Paste" "F.Mask")
      (net 9 "GND") (pinfunction "VSS") (pintype "passive"))
    (pad "51" smd rect (at 42.499 0 270) (size 1.8 0.57) (layers "F.Cu" "F.Paste" "F.Mask")
      (net 347 "DQS17_P") (pinfunction "DQS17_t") (pintype "passive"))
    (pad "52" smd rect (at 43.35 0 270) (size 1.8 0.57) (layers "F.Cu" "F.Paste" "F.Mask")
      (net 349 "DQS17_N") (pinfunction "DQS17_c") (pintype "passive"))
    (pad "53" smd rect (at 44.2 0 270) (size 1.8 0.57) (layers "F.Cu" "F.Paste" "F.Mask")
      (net 9 "GND") (pinfunction "VSS") (pintype "passive"))
    (pad "54" smd rect (at 45.048 0 270) (size 1.8 0.57) (layers "F.Cu" "F.Paste" "F.Mask")
      (net 259 "CB6") (pinfunction "CB6") (pintype "passive"))
    (pad "55" smd rect (at 45.898 0 270) (size 1.8 0.57) (layers "F.Cu" "F.Paste" "F.Mask")
      (net 9 "GND") (pinfunction "VSS") (pintype "passive"))
    (pad "56" smd rect (at 46.749 0 270) (size 1.8 0.57) (layers "F.Cu" "F.Paste" "F.Mask")
      (net 260 "CB2") (pinfunction "CB2") (pintype "passive"))
    (pad "57" smd rect (at 47.6 0 270) (size 1.8 0.57) (layers "F.Cu" "F.Paste" "F.Mask")
      (net 789 "DDR_PRESENCE") (pinfunction "Presence") (pintype "passive"))
    (pad "58" smd rect (at 48.45 0 270) (size 1.8 0.57) (layers "F.Cu" "F.Paste" "F.Mask")
      (net 262 "~{RESET}") (pinfunction "RESET_n") (pintype "passive"))
    (pad "59" smd rect (at 49.298 0 270) (size 1.8 0.57) (layers "F.Cu" "F.Paste" "F.Mask")
      (net 77 "VDDQ") (pinfunction "VDD") (pintype "passive"))
    (pad "60" smd rect (at 50.148 0 270) (size 1.8 0.57) (layers "F.Cu" "F.Paste" "F.Mask")
      (net 261 "CKE0") (pinfunction "CKE0") (pintype "passive"))
    (pad "61" smd rect (at 50.999 0 270) (size 1.8 0.57) (layers "F.Cu" "F.Paste" "F.Mask")
      (net 77 "VDDQ") (pinfunction "VDD") (pintype "passive"))
    (pad "62" smd rect (at 51.85 0 270) (size 1.8 0.57) (layers "F.Cu" "F.Paste" "F.Mask")
      (net 264 "~{ACT}") (pinfunction "ACT_n") (pintype "passive"))
    (pad "63" smd rect (at 52.7 0 270) (size 1.8 0.57) (layers "F.Cu" "F.Paste" "F.Mask")
      (net 263 "BG0") (pinfunction "BG0") (pintype "passive"))
    (pad "64" smd rect (at 53.548 0 270) (size 1.8 0.57) (layers "F.Cu" "F.Paste" "F.Mask")
      (net 77 "VDDQ") (pinfunction "VDD") (pintype "passive"))
    (pad "65" smd rect (at 54.398 0 270) (size 1.8 0.57) (layers "F.Cu" "F.Paste" "F.Mask")
      (net 265 "A12\\~{BC}") (pinfunction "A12/BC_n") (pintype "passive"))
    (pad "66" smd rect (at 55.249 0 270) (size 1.8 0.57) (layers "F.Cu" "F.Paste" "F.Mask")
      (net 266 "A9") (pinfunction "A9") (pintype "passive"))
    (pad "67" smd rect (at 56.1 0 270) (size 1.8 0.57) (layers "F.Cu" "F.Paste" "F.Mask")
      (net 77 "VDDQ") (pinfunction "VDD") (pintype "passive"))
    (pad "68" smd rect (at 56.95 0 270) (size 1.8 0.57) (layers "F.Cu" "F.Paste" "F.Mask")
      (net 268 "A8") (pinfunction "A8") (pintype "passive"))
    (pad "69" smd rect (at 57.798 0 270) (size 1.8 0.57) (layers "F.Cu" "F.Paste" "F.Mask")
      (net 267 "A6") (pinfunction "A6") (pintype "passive"))
    (pad "70" smd rect (at 58.648 0 270) (size 1.8 0.57) (layers "F.Cu" "F.Paste" "F.Mask")
      (net 77 "VDDQ") (pinfunction "VDD") (pintype "passive"))
    (pad "71" smd rect (at 59.499 0 270) (size 1.8 0.57) (layers "F.Cu" "F.Paste" "F.Mask")
      (net 269 "A3") (pinfunction "A3") (pintype "passive"))
    (pad "72" smd rect (at 60.35 0 270) (size 1.8 0.57) (layers "F.Cu" "F.Paste" "F.Mask")
      (net 270 "A1") (pinfunction "A1") (pintype "passive"))
    (pad "73" smd rect (at 61.2 0 270) (size 1.8 0.57) (layers "F.Cu" "F.Paste" "F.Mask")
      (net 77 "VDDQ") (pinfunction "VDD") (pintype "passive"))
    (pad "74" smd rect (at 62.048 0 270) (size 1.8 0.57) (layers "F.Cu" "F.Paste" "F.Mask")
      (net 355 "CK0_P") (pinfunction "CK0_t") (pintype "passive"))
    (pad "75" smd rect (at 62.898 0 270) (size 1.8 0.57) (layers "F.Cu" "F.Paste" "F.Mask")
      (net 356 "CK0_N") (pinfunction "CK0_c") (pintype "passive"))
    (pad "76" smd rect (at 63.749 0 270) (size 1.8 0.57) (layers "F.Cu" "F.Paste" "F.Mask")
      (net 77 "VDDQ") (pinfunction "VDD") (pintype "passive"))
    (pad "77" smd rect (at 64.599 0 270) (size 1.8 0.57) (layers "F.Cu" "F.Paste" "F.Mask")
      (net 186 "VTT") (pinfunction "VTT") (pintype "passive"))
    (pad "78" smd rect (at 70.549 0 270) (size 1.8 0.57) (layers "F.Cu" "F.Paste" "F.Mask")
      (net 187 "~{EVENT}") (pinfunction "EVENT_n") (pintype "passive"))
    (pad "79" smd rect (at 71.4 0 270) (size 1.8 0.57) (layers "F.Cu" "F.Paste" "F.Mask")
      (net 240 "A0") (pinfunction "A0") (pintype "passive"))
    (pad "80" smd rect (at 72.248 0 270) (size 1.8 0.57) (layers "F.Cu" "F.Paste" "F.Mask")
      (net 77 "VDDQ") (pinfunction "VDD") (pintype "passive"))
    (pad "81" smd rect (at 73.099 0 270) (size 1.8 0.57) (layers "F.Cu" "F.Paste" "F.Mask")
      (net 239 "BA0") (pinfunction "BA0") (pintype "passive"))
    (pad "82" smd rect (at 73.95 0 270) (size 1.8 0.57) (layers "F.Cu" "F.Paste" "F.Mask")
      (net 238 "~{RAS}\\A16") (pinfunction "RAS_n/A16") (pintype "passive"))
    (pad "83" smd rect (at 74.799 0 270) (size 1.8 0.57) (layers "F.Cu" "F.Paste" "F.Mask")
      (net 77 "VDDQ") (pinfunction "VDD") (pintype "passive"))
    (pad "84" smd rect (at 75.65 0 270) (size 1.8 0.57) (layers "F.Cu" "F.Paste" "F.Mask")
      (net 237 "~{CS0}") (pinfunction "CS0_n") (pintype "passive"))
    (pad "85" smd rect (at 76.498 0 270) (size 1.8 0.57) (layers "F.Cu" "F.Paste" "F.Mask")
      (net 77 "VDDQ") (pinfunction "VDD") (pintype "passive"))
    (pad "86" smd rect (at 77.349 0 270) (size 1.8 0.57) (layers "F.Cu" "F.Paste" "F.Mask")
      (net 236 "~{CAS}\\A15") (pinfunction "CAS_n/A15") (pintype "passive"))
    (pad "87" smd rect (at 78.2 0 270) (size 1.8 0.57) (layers "F.Cu" "F.Paste" "F.Mask")
      (net 235 "ODT0") (pinfunction "ODT0") (pintype "passive"))
    (pad "88" smd rect (at 79.049 0 270) (size 1.8 0.57) (layers "F.Cu" "F.Paste" "F.Mask")
      (net 77 "VDDQ") (pinfunction "VDD") (pintype "passive"))
    (pad "89" smd rect (at 79.9 0 270) (size 1.8 0.57) (layers "F.Cu" "F.Paste" "F.Mask")
      (net 234 "~{CS1}\\NC") (pinfunction "CS1_n") (pintype "passive"))
    (pad "90" smd rect (at 80.748 0 270) (size 1.8 0.57) (layers "F.Cu" "F.Paste" "F.Mask")
      (net 77 "VDDQ") (pinfunction "VDD") (pintype "passive"))
    (pad "91" smd rect (at 81.599 0 270) (size 1.8 0.57) (layers "F.Cu" "F.Paste" "F.Mask")
      (net 231 "ODT1\\NC") (pinfunction "ODT1") (pintype "passive"))
    (pad "92" smd rect (at 82.45 0 270) (size 1.8 0.57) (layers "F.Cu" "F.Paste" "F.Mask")
      (net 77 "VDDQ") (pinfunction "VDD") (pintype "passive"))
    (pad "93" smd rect (at 83.299 0 270) (size 1.8 0.57) (layers "F.Cu" "F.Paste" "F.Mask")
      (net 230 "~{CS2}\\C0") (pinfunction "C0/CS2_n") (pintype "passive"))
    (pad "94" smd rect (at 84.15 0 270) (size 1.8 0.57) (layers "F.Cu" "F.Paste" "F.Mask")
      (net 9 "GND") (pinfunction "VSS") (pintype "passive"))
    (pad "95" smd rect (at 84.998 0 270) (size 1.8 0.57) (layers "F.Cu" "F.Paste" "F.Mask")
      (net 233 "DQ36") (pinfunction "DQ36") (pintype "passive"))
    (pad "96" smd rect (at 85.849 0 270) (size 1.8 0.57) (layers "F.Cu" "F.Paste" "F.Mask")
      (net 9 "GND") (pinfunction "VSS") (pintype "passive"))
    (pad "97" smd rect (at 86.7 0 270) (size 1.8 0.57) (layers "F.Cu" "F.Paste" "F.Mask")
      (net 232 "DQ32") (pinfunction "DQ32") (pintype "passive"))
    (pad "98" smd rect (at 87.549 0 270) (size 1.8 0.57) (layers "F.Cu" "F.Paste" "F.Mask")
      (net 9 "GND") (pinfunction "VSS") (pintype "passive"))
    (pad "99" smd rect (at 88.4 0 270) (size 1.8 0.57) (layers "F.Cu" "F.Paste" "F.Mask")
      (net 331 "DQS13_P") (pinfunction "DQS13_t") (pintype "passive"))
    (pad "100" smd rect (at 89.248 0 270) (size 1.8 0.57) (layers "F.Cu" "F.Paste" "F.Mask")
      (net 333 "DQS13_N") (pinfunction "DQS13_c") (pintype "passive"))
    (pad "101" smd rect (at 90.099 0 270) (size 1.8 0.57) (layers "F.Cu" "F.Paste" "F.Mask")
      (net 9 "GND") (pinfunction "VSS") (pintype "passive"))
    (pad "102" smd rect (at 90.95 0 270) (size 1.8 0.57) (layers "F.Cu" "F.Paste" "F.Mask")
      (net 228 "DQ38") (pinfunction "DQ38") (pintype "passive"))
    (pad "103" smd rect (at 91.799 0 270) (size 1.8 0.57) (layers "F.Cu" "F.Paste" "F.Mask")
      (net 9 "GND") (pinfunction "VSS") (pintype "passive"))
    (pad "104" smd rect (at 92.65 0 270) (size 1.8 0.57) (layers "F.Cu" "F.Paste" "F.Mask")
      (net 227 "DQ34") (pinfunction "DQ34") (pintype "passive"))
    (pad "105" smd rect (at 93.498 0 270) (size 1.8 0.57) (layers "F.Cu" "F.Paste" "F.Mask")
      (net 9 "GND") (pinfunction "VSS") (pintype "passive"))
    (pad "106" smd rect (at 94.349 0 270) (size 1.8 0.57) (layers "F.Cu" "F.Paste" "F.Mask")
      (net 226 "DQ44") (pinfunction "DQ44") (pintype "passive"))
    (pad "107" smd rect (at 95.2 0 270) (size 1.8 0.57) (layers "F.Cu" "F.Paste" "F.Mask")
      (net 9 "GND") (pinfunction "VSS") (pintype "passive"))
    (pad "108" smd rect (at 96.049 0 270) (size 1.8 0.57) (layers "F.Cu" "F.Paste" "F.Mask")
      (net 229 "DQ40") (pinfunction "DQ40") (pintype "passive"))
    (pad "109" smd rect (at 96.9 0 270) (size 1.8 0.57) (layers "F.Cu" "F.Paste" "F.Mask")
      (net 9 "GND") (pinfunction "VSS") (pintype "passive"))
    (pad "110" smd rect (at 97.748 0 270) (size 1.8 0.57) (layers "F.Cu" "F.Paste" "F.Mask")
      (net 335 "DQS14_P") (pinfunction "DQS14_t") (pintype "passive"))
    (pad "111" smd rect (at 98.599 0 270) (size 1.8 0.57) (layers "F.Cu" "F.Paste" "F.Mask")
      (net 337 "DQS14_N") (pinfunction "DQS14_c") (pintype "passive"))
    (pad "112" smd rect (at 99.45 0 270) (size 1.8 0.57) (layers "F.Cu" "F.Paste" "F.Mask")
      (net 9 "GND") (pinfunction "VSS") (pintype "passive"))
    (pad "113" smd rect (at 100.299 0 270) (size 1.8 0.57) (layers "F.Cu" "F.Paste" "F.Mask")
      (net 222 "DQ46") (pinfunction "DQ46") (pintype "passive"))
    (pad "114" smd rect (at 101.15 0 270) (size 1.8 0.57) (layers "F.Cu" "F.Paste" "F.Mask")
      (net 9 "GND") (pinfunction "VSS") (pintype "passive"))
    (pad "115" smd rect (at 101.998 0 270) (size 1.8 0.57) (layers "F.Cu" "F.Paste" "F.Mask")
      (net 224 "DQ42") (pinfunction "DQ42") (pintype "passive"))
    (pad "116" smd rect (at 102.849 0 270) (size 1.8 0.57) (layers "F.Cu" "F.Paste" "F.Mask")
      (net 9 "GND") (pinfunction "VSS") (pintype "passive"))
    (pad "117" smd rect (at 103.7 0 270) (size 1.8 0.57) (layers "F.Cu" "F.Paste" "F.Mask")
      (net 223 "DQ52") (pinfunction "DQ52") (pintype "passive"))
    (pad "118" smd rect (at 104.549 0 270) (size 1.8 0.57) (layers "F.Cu" "F.Paste" "F.Mask")
      (net 9 "GND") (pinfunction "VSS") (pintype "passive"))
    (pad "119" smd rect (at 105.4 0 270) (size 1.8 0.57) (layers "F.Cu" "F.Paste" "F.Mask")
      (net 225 "DQ48") (pinfunction "DQ48") (pintype "passive"))
    (pad "120" smd rect (at 106.248 0 270) (size 1.8 0.57) (layers "F.Cu" "F.Paste" "F.Mask")
      (net 9 "GND") (pinfunction "VSS") (pintype "passive"))
    (pad "121" smd rect (at 107.099 0 270) (size 1.8 0.57) (layers "F.Cu" "F.Paste" "F.Mask")
      (net 339 "DQS15_P") (pinfunction "DQS15_t") (pintype "passive"))
    (pad "122" smd rect (at 107.95 0 270) (size 1.8 0.57) (layers "F.Cu" "F.Paste" "F.Mask")
      (net 341 "DQS15_N") (pinfunction "DQS15_c") (pintype "passive"))
    (pad "123" smd rect (at 108.799 0 270) (size 1.8 0.57) (layers "F.Cu" "F.Paste" "F.Mask")
      (net 9 "GND") (pinfunction "VSS") (pintype "passive"))
    (pad "124" smd rect (at 109.65 0 270) (size 1.8 0.57) (layers "F.Cu" "F.Paste" "F.Mask")
      (net 220 "DQ54") (pinfunction "DQ54") (pintype "passive"))
    (pad "125" smd rect (at 110.498 0 270) (size 1.8 0.57) (layers "F.Cu" "F.Paste" "F.Mask")
      (net 9 "GND") (pinfunction "VSS") (pintype "passive"))
    (pad "126" smd rect (at 111.349 0 270) (size 1.8 0.57) (layers "F.Cu" "F.Paste" "F.Mask")
      (net 219 "DQ50") (pinfunction "DQ50") (pintype "passive"))
    (pad "127" smd rect (at 112.2 0 270) (size 1.8 0.57) (layers "F.Cu" "F.Paste" "F.Mask")
      (net 9 "GND") (pinfunction "VSS") (pintype "passive"))
    (pad "128" smd rect (at 113.049 0 270) (size 1.8 0.57) (layers "F.Cu" "F.Paste" "F.Mask")
      (net 221 "DQ60") (pinfunction "DQ60") (pintype "passive"))
    (pad "129" smd rect (at 113.9 0 270) (size 1.8 0.57) (layers "F.Cu" "F.Paste" "F.Mask")
      (net 9 "GND") (pinfunction "VSS") (pintype "passive"))
    (pad "130" smd rect (at 114.749 0 270) (size 1.8 0.57) (layers "F.Cu" "F.Paste" "F.Mask")
      (net 215 "DQ56") (pinfunction "DQ56") (pintype "passive"))
    (pad "131" smd rect (at 115.599 0 270) (size 1.8 0.57) (layers "F.Cu" "F.Paste" "F.Mask")
      (net 9 "GND") (pinfunction "VSS") (pintype "passive"))
    (pad "132" smd rect (at 116.45 0 270) (size 1.8 0.57) (layers "F.Cu" "F.Paste" "F.Mask")
      (net 343 "DQS16_P") (pinfunction "DQS16_t") (pintype "passive"))
    (pad "133" smd rect (at 117.299 0 270) (size 1.8 0.57) (layers "F.Cu" "F.Paste" "F.Mask")
      (net 345 "DQS16_N") (pinfunction "DQS16_c") (pintype "passive"))
    (pad "134" smd rect (at 118.15 0 270) (size 1.8 0.57) (layers "F.Cu" "F.Paste" "F.Mask")
      (net 9 "GND") (pinfunction "VSS") (pintype "passive"))
    (pad "135" smd rect (at 118.999 0 270) (size 1.8 0.57) (layers "F.Cu" "F.Paste" "F.Mask")
      (net 217 "DQ62") (pinfunction "DQ62") (pintype "passive"))
    (pad "136" smd rect (at 119.849 0 270) (size 1.8 0.57) (layers "F.Cu" "F.Paste" "F.Mask")
      (net 9 "GND") (pinfunction "VSS") (pintype "passive"))
    (pad "137" smd rect (at 120.7 0 270) (size 1.8 0.57) (layers "F.Cu" "F.Paste" "F.Mask")
      (net 216 "DQ58") (pinfunction "DQ58") (pintype "passive"))
    (pad "138" smd rect (at 121.549 0 270) (size 1.8 0.57) (layers "F.Cu" "F.Paste" "F.Mask")
      (net 9 "GND") (pinfunction "VSS") (pintype "passive"))
    (pad "139" smd rect (at 122.4 0 270) (size 1.8 0.57) (layers "F.Cu" "F.Paste" "F.Mask")
      (net 218 "SA0") (pinfunction "SA0") (pintype "passive"))
    (pad "140" smd rect (at 123.249 0 270) (size 1.8 0.57) (layers "F.Cu" "F.Paste" "F.Mask")
      (net 214 "SA1") (pinfunction "SA1") (pintype "passive"))
    (pad "141" smd rect (at 124.099 0 270) (size 1.8 0.57) (layers "F.Cu" "F.Paste" "F.Mask")
      (net 351 "SCL_2V5") (pinfunction "SCL") (pintype "passive"))
    (pad "142" smd rect (at 124.95 0 270) (size 1.8 0.57) (layers "F.Cu" "F.Paste" "F.Mask")
      (net 184 "VPP") (pinfunction "VPP") (pintype "passive"))
    (pad "143" smd rect (at 125.799 0 270) (size 1.8 0.57) (layers "F.Cu" "F.Paste" "F.Mask")
      (net 184 "VPP") (pinfunction "VPP") (pintype "passive"))
    (pad "144" smd rect (at 126.65 0 270) (size 1.8 0.57) (layers "F.Cu" "F.Paste" "F.Mask")
      (net 705 "unconnected-(U14B-RFU-Pad144)") (pinfunction "RFU") (pintype "no_connect"))
    (pad "145" smd rect (at 0 -4.601 270) (size 1.8 0.57) (layers "F.Cu" "F.Paste" "F.Mask")
      (net 308 "NC") (pinfunction "12V/NC") (pintype "passive"))
    (pad "146" smd rect (at 0.848 -4.601 270) (size 1.8 0.57) (layers "F.Cu" "F.Paste" "F.Mask")
      (net 400 "VREFCA") (pinfunction "VREFCA") (pintype "passive"))
    (pad "147" smd rect (at 1.699 -4.601 270) (size 1.8 0.57) (layers "F.Cu" "F.Paste" "F.Mask")
      (net 9 "GND") (pinfunction "VSS") (pintype "passive"))
    (pad "148" smd rect (at 2.548 -4.601 270) (size 1.8 0.57) (layers "F.Cu" "F.Paste" "F.Mask")
      (net 298 "DQ5") (pinfunction "DQ5") (pintype "passive"))
    (pad "149" smd rect (at 3.398 -4.601 270) (size 1.8 0.57) (layers "F.Cu" "F.Paste" "F.Mask")
      (net 9 "GND") (pinfunction "VSS") (pintype "passive"))
    (pad "150" smd rect (at 4.248 -4.601 270) (size 1.8 0.57) (layers "F.Cu" "F.Paste" "F.Mask")
      (net 288 "DQ1") (pinfunction "DQ1") (pintype "passive"))
    (pad "151" smd rect (at 5.099 -4.601 270) (size 1.8 0.57) (layers "F.Cu" "F.Paste" "F.Mask")
      (net 9 "GND") (pinfunction "VSS") (pintype "passive"))
    (pad "152" smd rect (at 5.95 -4.601 270) (size 1.8 0.57) (layers "F.Cu" "F.Paste" "F.Mask")
      (net 315 "DQS0_N") (pinfunction "DQS0_c") (pintype "passive"))
    (pad "153" smd rect (at 6.799 -4.601 270) (size 1.8 0.57) (layers "F.Cu" "F.Paste" "F.Mask")
      (net 314 "DQS0_P") (pinfunction "DQS0_t") (pintype "passive"))
    (pad "154" smd rect (at 7.65 -4.601 270) (size 1.8 0.57) (layers "F.Cu" "F.Paste" "F.Mask")
      (net 9 "GND") (pinfunction "VSS") (pintype "passive"))
    (pad "155" smd rect (at 8.499 -4.601 270) (size 1.8 0.57) (layers "F.Cu" "F.Paste" "F.Mask")
      (net 297 "DQ7") (pinfunction "DQ7") (pintype "passive"))
    (pad "156" smd rect (at 9.349 -4.601 270) (size 1.8 0.57) (layers "F.Cu" "F.Paste" "F.Mask")
      (net 9 "GND") (pinfunction "VSS") (pintype "passive"))
    (pad "157" smd rect (at 10.198 -4.601 270) (size 1.8 0.57) (layers "F.Cu" "F.Paste" "F.Mask")
      (net 292 "DQ3") (pinfunction "DQ3") (pintype "passive"))
    (pad "158" smd rect (at 11.05 -4.601 270) (size 1.8 0.57) (layers "F.Cu" "F.Paste" "F.Mask")
      (net 9 "GND") (pinfunction "VSS") (pintype "passive"))
    (pad "159" smd rect (at 11.9 -4.601 270) (size 1.8 0.57) (layers "F.Cu" "F.Paste" "F.Mask")
      (net 275 "DQ13") (pinfunction "DQ13") (pintype "passive"))
    (pad "160" smd rect (at 12.749 -4.601 270) (size 1.8 0.57) (layers "F.Cu" "F.Paste" "F.Mask")
      (net 9 "GND") (pinfunction "VSS") (pintype "passive"))
    (pad "161" smd rect (at 13.598 -4.601 270) (size 1.8 0.57) (layers "F.Cu" "F.Paste" "F.Mask")
      (net 293 "DQ9") (pinfunction "DQ9") (pintype "passive"))
    (pad "162" smd rect (at 14.448 -4.601 270) (size 1.8 0.57) (layers "F.Cu" "F.Paste" "F.Mask")
      (net 9 "GND") (pinfunction "VSS") (pintype "passive"))
    (pad "163" smd rect (at 15.3 -4.601 270) (size 1.8 0.57) (layers "F.Cu" "F.Paste" "F.Mask")
      (net 320 "DQS1_N") (pinfunction "DQS1_c") (pintype "passive"))
    (pad "164" smd rect (at 16.149 -4.601 270) (size 1.8 0.57) (layers "F.Cu" "F.Paste" "F.Mask")
      (net 318 "DQS1_P") (pinfunction "DQS_1_t") (pintype "passive"))
    (pad "165" smd rect (at 16.998 -4.601 270) (size 1.8 0.57) (layers "F.Cu" "F.Paste" "F.Mask")
      (net 9 "GND") (pinfunction "VSS") (pintype "passive"))
    (pad "166" smd rect (at 17.85 -4.601 270) (size 1.8 0.57) (layers "F.Cu" "F.Paste" "F.Mask")
      (net 273 "DQ15") (pinfunction "DQ15") (pintype "passive"))
    (pad "167" smd rect (at 18.699 -4.601 270) (size 1.8 0.57) (layers "F.Cu" "F.Paste" "F.Mask")
      (net 9 "GND") (pinfunction "VSS") (pintype "passive"))
    (pad "168" smd rect (at 19.55 -4.601 270) (size 1.8 0.57) (layers "F.Cu" "F.Paste" "F.Mask")
      (net 274 "DQ11") (pinfunction "DQ11") (pintype "passive"))
    (pad "169" smd rect (at 20.399 -4.601 270) (size 1.8 0.57) (layers "F.Cu" "F.Paste" "F.Mask")
      (net 9 "GND") (pinfunction "VSS") (pintype "passive"))
    (pad "170" smd rect (at 21.248 -4.601 270) (size 1.8 0.57) (layers "F.Cu" "F.Paste" "F.Mask")
      (net 294 "DQ21") (pinfunction "DQ21") (pintype "passive"))
    (pad "171" smd rect (at 22.1 -4.601 270) (size 1.8 0.57) (layers "F.Cu" "F.Paste" "F.Mask")
      (net 9 "GND") (pinfunction "VSS") (pintype "passive"))
    (pad "172" smd rect (at 22.949 -4.601 270) (size 1.8 0.57) (layers "F.Cu" "F.Paste" "F.Mask")
      (net 281 "DQ17") (pinfunction "DQ17") (pintype "passive"))
    (pad "173" smd rect (at 23.8 -4.601 270) (size 1.8 0.57) (layers "F.Cu" "F.Paste" "F.Mask")
      (net 9 "GND") (pinfunction "VSS") (pintype "passive"))
    (pad "174" smd rect (at 24.649 -4.601 270) (size 1.8 0.57) (layers "F.Cu" "F.Paste" "F.Mask")
      (net 324 "DQS2_N") (pinfunction "DQS2_c") (pintype "passive"))
    (pad "175" smd rect (at 25.498 -4.601 270) (size 1.8 0.57) (layers "F.Cu" "F.Paste" "F.Mask")
      (net 322 "DQS2_P") (pinfunction "DQS2_t") (pintype "passive"))
    (pad "176" smd rect (at 26.35 -4.601 270) (size 1.8 0.57) (layers "F.Cu" "F.Paste" "F.Mask")
      (net 9 "GND") (pinfunction "VSS") (pintype "passive"))
    (pad "177" smd rect (at 27.199 -4.601 270) (size 1.8 0.57) (layers "F.Cu" "F.Paste" "F.Mask")
      (net 277 "DQ23") (pinfunction "DQ23") (pintype "passive"))
    (pad "178" smd rect (at 28.05 -4.601 270) (size 1.8 0.57) (layers "F.Cu" "F.Paste" "F.Mask")
      (net 9 "GND") (pinfunction "VSS") (pintype "passive"))
    (pad "179" smd rect (at 28.899 -4.601 270) (size 1.8 0.57) (layers "F.Cu" "F.Paste" "F.Mask")
      (net 286 "DQ19") (pinfunction "DQ19") (pintype "passive"))
    (pad "180" smd rect (at 29.749 -4.601 270) (size 1.8 0.57) (layers "F.Cu" "F.Paste" "F.Mask")
      (net 9 "GND") (pinfunction "VSS") (pintype "passive"))
    (pad "181" smd rect (at 30.6 -4.601 270) (size 1.8 0.57) (layers "F.Cu" "F.Paste" "F.Mask")
      (net 285 "DQ29") (pinfunction "DQ29") (pintype "passive"))
    (pad "182" smd rect (at 31.449 -4.601 270) (size 1.8 0.57) (layers "F.Cu" "F.Paste" "F.Mask")
      (net 9 "GND") (pinfunction "VSS") (pintype "passive"))
    (pad "183" smd rect (at 32.298 -4.601 270) (size 1.8 0.57) (layers "F.Cu" "F.Paste" "F.Mask")
      (net 271 "DQ25") (pinfunction "DQ25") (pintype "passive"))
    (pad "184" smd rect (at 33.149 -4.601 270) (size 1.8 0.57) (layers "F.Cu" "F.Paste" "F.Mask")
      (net 9 "GND") (pinfunction "VSS") (pintype "passive"))
    (pad "185" smd rect (at 33.999 -4.601 270) (size 1.8 0.57) (layers "F.Cu" "F.Paste" "F.Mask")
      (net 328 "DQS3_N") (pinfunction "DQS3_c") (pintype "passive"))
    (pad "186" smd rect (at 34.85 -4.601 270) (size 1.8 0.57) (layers "F.Cu" "F.Paste" "F.Mask")
      (net 326 "DQS3_P") (pinfunction "DQS3_t") (pintype "passive"))
    (pad "187" smd rect (at 35.7 -4.601 270) (size 1.8 0.57) (layers "F.Cu" "F.Paste" "F.Mask")
      (net 9 "GND") (pinfunction "VSS") (pintype "passive"))
    (pad "188" smd rect (at 36.548 -4.601 270) (size 1.8 0.57) (layers "F.Cu" "F.Paste" "F.Mask")
      (net 279 "DQ31") (pinfunction "DQ31") (pintype "passive"))
    (pad "189" smd rect (at 37.399 -4.601 270) (size 1.8 0.57) (layers "F.Cu" "F.Paste" "F.Mask")
      (net 9 "GND") (pinfunction "VSS") (pintype "passive"))
    (pad "190" smd rect (at 38.249 -4.601 270) (size 1.8 0.57) (layers "F.Cu" "F.Paste" "F.Mask")
      (net 287 "DQ27") (pinfunction "DQ27") (pintype "passive"))
    (pad "191" smd rect (at 39.1 -4.601 270) (size 1.8 0.57) (layers "F.Cu" "F.Paste" "F.Mask")
      (net 9 "GND") (pinfunction "VSS") (pintype "passive"))
    (pad "192" smd rect (at 39.95 -4.601 270) (size 1.8 0.57) (layers "F.Cu" "F.Paste" "F.Mask")
      (net 278 "CB5") (pinfunction "CB5") (pintype "passive"))
    (pad "193" smd rect (at 40.798 -4.601 270) (size 1.8 0.57) (layers "F.Cu" "F.Paste" "F.Mask")
      (net 9 "GND") (pinfunction "VSS") (pintype "passive"))
    (pad "194" smd rect (at 41.649 -4.601 270) (size 1.8 0.57) (layers "F.Cu" "F.Paste" "F.Mask")
      (net 272 "CB1") (pinfunction "CB1") (pintype "passive"))
    (pad "195" smd rect (at 42.499 -4.601 270) (size 1.8 0.57) (layers "F.Cu" "F.Paste" "F.Mask")
      (net 9 "GND") (pinfunction "VSS") (pintype "passive"))
    (pad "196" smd rect (at 43.35 -4.601 270) (size 1.8 0.57) (layers "F.Cu" "F.Paste" "F.Mask")
      (net 348 "DQS8_N") (pinfunction "DQS8_c") (pintype "passive"))
    (pad "197" smd rect (at 44.2 -4.601 270) (size 1.8 0.57) (layers "F.Cu" "F.Paste" "F.Mask")
      (net 346 "DQS8_P") (pinfunction "DQS8_t") (pintype "passive"))
    (pad "198" smd rect (at 45.048 -4.601 270) (size 1.8 0.57) (layers "F.Cu" "F.Paste" "F.Mask")
      (net 9 "GND") (pinfunction "VSS") (pintype "passive"))
    (pad "199" smd rect (at 45.898 -4.601 270) (size 1.8 0.57) (layers "F.Cu" "F.Paste" "F.Mask")
      (net 282 "CB7") (pinfunction "CB7") (pintype "passive"))
    (pad "200" smd rect (at 46.749 -4.601 270) (size 1.8 0.57) (layers "F.Cu" "F.Paste" "F.Mask")
      (net 9 "GND") (pinfunction "VSS") (pintype "passive"))
    (pad "201" smd rect (at 47.6 -4.601 270) (size 1.8 0.57) (layers "F.Cu" "F.Paste" "F.Mask")
      (net 295 "CB3") (pinfunction "CB3") (pintype "passive"))
    (pad "202" smd rect (at 48.45 -4.601 270) (size 1.8 0.57) (layers "F.Cu" "F.Paste" "F.Mask")
      (net 9 "GND") (pinfunction "VSS") (pintype "passive"))
    (pad "203" smd rect (at 49.298 -4.601 270) (size 1.8 0.57) (layers "F.Cu" "F.Paste" "F.Mask")
      (net 290 "CKE1\\NC") (pinfunction "CKE1") (pintype "passive"))
    (pad "204" smd rect (at 50.148 -4.601 270) (size 1.8 0.57) (layers "F.Cu" "F.Paste" "F.Mask")
      (net 77 "VDDQ") (pinfunction "VDD") (pintype "passive"))
    (pad "205" smd rect (at 50.999 -4.601 270) (size 1.8 0.57) (layers "F.Cu" "F.Paste" "F.Mask")
      (net 706 "unconnected-(U14B-RFU-Pad205)") (pinfunction "RFU") (pintype "no_connect"))
    (pad "206" smd rect (at 51.85 -4.601 270) (size 1.8 0.57) (layers "F.Cu" "F.Paste" "F.Mask")
      (net 77 "VDDQ") (pinfunction "VDD") (pintype "passive"))
    (pad "207" smd rect (at 52.7 -4.601 270) (size 1.8 0.57) (layers "F.Cu" "F.Paste" "F.Mask")
      (net 280 "BG1") (pinfunction "BG1") (pintype "passive"))
    (pad "208" smd rect (at 53.548 -4.601 270) (size 1.8 0.57) (layers "F.Cu" "F.Paste" "F.Mask")
      (net 296 "~{ALERT}") (pinfunction "ALERT_n") (pintype "passive"))
    (pad "209" smd rect (at 54.398 -4.601 270) (size 1.8 0.57) (layers "F.Cu" "F.Paste" "F.Mask")
      (net 77 "VDDQ") (pinfunction "VDD") (pintype "passive"))
    (pad "210" smd rect (at 55.249 -4.601 270) (size 1.8 0.57) (layers "F.Cu" "F.Paste" "F.Mask")
      (net 283 "A11") (pinfunction "A11") (pintype "passive"))
    (pad "211" smd rect (at 56.1 -4.601 270) (size 1.8 0.57) (layers "F.Cu" "F.Paste" "F.Mask")
      (net 284 "A7") (pinfunction "A7") (pintype "passive"))
    (pad "212" smd rect (at 56.95 -4.601 270) (size 1.8 0.57) (layers "F.Cu" "F.Paste" "F.Mask")
      (net 77 "VDDQ") (pinfunction "VDD") (pintype "passive"))
    (pad "213" smd rect (at 57.798 -4.601 270) (size 1.8 0.57) (layers "F.Cu" "F.Paste" "F.Mask")
      (net 276 "A5") (pinfunction "A5") (pintype "passive"))
    (pad "214" smd rect (at 58.648 -4.601 270) (size 1.8 0.57) (layers "F.Cu" "F.Paste" "F.Mask")
      (net 289 "A4") (pinfunction "A4") (pintype "passive"))
    (pad "215" smd rect (at 59.499 -4.601 270) (size 1.8 0.57) (layers "F.Cu" "F.Paste" "F.Mask")
      (net 77 "VDDQ") (pinfunction "VDD") (pintype "passive"))
    (pad "216" smd rect (at 60.35 -4.601 270) (size 1.8 0.57) (layers "F.Cu" "F.Paste" "F.Mask")
      (net 291 "A2") (pinfunction "A2") (pintype "passive"))
    (pad "217" smd rect (at 61.2 -4.601 270) (size 1.8 0.57) (layers "F.Cu" "F.Paste" "F.Mask")
      (net 77 "VDDQ") (pinfunction "VDD") (pintype "passive"))
    (pad "218" smd rect (at 62.048 -4.601 270) (size 1.8 0.57) (layers "F.Cu" "F.Paste" "F.Mask")
      (net 353 "CK1_P") (pinfunction "CK1_t") (pintype "passive"))
    (pad "219" smd rect (at 62.898 -4.601 270) (size 1.8 0.57) (layers "F.Cu" "F.Paste" "F.Mask")
      (net 354 "CK1_N") (pinfunction "CK1_c") (pintype "passive"))
    (pad "220" smd rect (at 63.749 -4.601 270) (size 1.8 0.57) (layers "F.Cu" "F.Paste" "F.Mask")
      (net 77 "VDDQ") (pinfunction "VDD") (pintype "passive"))
    (pad "221" smd rect (at 64.599 -4.601 270) (size 1.8 0.57) (layers "F.Cu" "F.Paste" "F.Mask")
      (net 186 "VTT") (pinfunction "VTT") (pintype "passive"))
    (pad "222" smd rect (at 70.549 -4.601 270) (size 1.8 0.57) (layers "F.Cu" "F.Paste" "F.Mask")
      (net 199 "PARITY") (pinfunction "PARITY") (pintype "passive"))
    (pad "223" smd rect (at 71.4 -4.601 270) (size 1.8 0.57) (layers "F.Cu" "F.Paste" "F.Mask")
      (net 77 "VDDQ") (pinfunction "VDD") (pintype "passive"))
    (pad "224" smd rect (at 72.248 -4.601 270) (size 1.8 0.57) (layers "F.Cu" "F.Paste" "F.Mask")
      (net 211 "BA1") (pinfunction "BA1") (pintype "passive"))
    (pad "225" smd rect (at 73.099 -4.601 270) (size 1.8 0.57) (layers "F.Cu" "F.Paste" "F.Mask")
      (net 208 "A10\\AP") (pinfunction "A10/AP") (pintype "passive"))
    (pad "226" smd rect (at 73.95 -4.601 270) (size 1.8 0.57) (layers "F.Cu" "F.Paste" "F.Mask")
      (net 77 "VDDQ") (pinfunction "VDD") (pintype "passive"))
    (pad "227" smd rect (at 74.799 -4.601 270) (size 1.8 0.57) (layers "F.Cu" "F.Paste" "F.Mask")
      (net 707 "unconnected-(U14B-RFU-Pad227)") (pinfunction "RFU") (pintype "no_connect"))
    (pad "228" smd rect (at 75.65 -4.601 270) (size 1.8 0.57) (layers "F.Cu" "F.Paste" "F.Mask")
      (net 210 "~{WE}\\A14") (pinfunction "WE_n/A14") (pintype "passive"))
    (pad "229" smd rect (at 76.498 -4.601 270) (size 1.8 0.57) (layers "F.Cu" "F.Paste" "F.Mask")
      (net 77 "VDDQ") (pinfunction "VDD") (pintype "passive"))
    (pad "230" smd rect (at 77.349 -4.601 270) (size 1.8 0.57) (layers "F.Cu" "F.Paste" "F.Mask")
      (net 209 "~{SAVE}") (pinfunction "SAVE_n") (pintype "passive"))
    (pad "231" smd rect (at 78.2 -4.601 270) (size 1.8 0.57) (layers "F.Cu" "F.Paste" "F.Mask")
      (net 77 "VDDQ") (pinfunction "VDD") (pintype "passive"))
    (pad "232" smd rect (at 79.049 -4.601 270) (size 1.8 0.57) (layers "F.Cu" "F.Paste" "F.Mask")
      (net 207 "A13") (pinfunction "A13") (pintype "passive"))
    (pad "233" smd rect (at 79.9 -4.601 270) (size 1.8 0.57) (layers "F.Cu" "F.Paste" "F.Mask")
      (net 77 "VDDQ") (pinfunction "VDD") (pintype "passive"))
    (pad "234" smd rect (at 80.748 -4.601 270) (size 1.8 0.57) (layers "F.Cu" "F.Paste" "F.Mask")
      (net 200 "A17") (pinfunction "NC/A17") (pintype "passive"))
    (pad "235" smd rect (at 81.599 -4.601 270) (size 1.8 0.57) (layers "F.Cu" "F.Paste" "F.Mask")
      (net 201 "NC\\C2") (pinfunction "NC/C2") (pintype "passive"))
    (pad "236" smd rect (at 82.45 -4.601 270) (size 1.8 0.57) (layers "F.Cu" "F.Paste" "F.Mask")
      (net 77 "VDDQ") (pinfunction "VDD") (pintype "passive"))
    (pad "237" smd rect (at 83.299 -4.601 270) (size 1.8 0.57) (layers "F.Cu" "F.Paste" "F.Mask")
      (net 198 "~{CS3}\\C1,NC") (pinfunction "CS3_n/C1") (pintype "passive"))
    (pad "238" smd rect (at 84.15 -4.601 270) (size 1.8 0.57) (layers "F.Cu" "F.Paste" "F.Mask")
      (net 195 "SA2") (pinfunction "SA2") (pintype "passive"))
    (pad "239" smd rect (at 84.998 -4.601 270) (size 1.8 0.57) (layers "F.Cu" "F.Paste" "F.Mask")
      (net 9 "GND") (pinfunction "VSS") (pintype "passive"))
    (pad "240" smd rect (at 85.849 -4.601 270) (size 1.8 0.57) (layers "F.Cu" "F.Paste" "F.Mask")
      (net 212 "DQ37") (pinfunction "DQ37") (pintype "passive"))
    (pad "241" smd rect (at 86.7 -4.601 270) (size 1.8 0.57) (layers "F.Cu" "F.Paste" "F.Mask")
      (net 9 "GND") (pinfunction "VSS") (pintype "passive"))
    (pad "242" smd rect (at 87.549 -4.601 270) (size 1.8 0.57) (layers "F.Cu" "F.Paste" "F.Mask")
      (net 194 "DQ33") (pinfunction "DQ33") (pintype "passive"))
    (pad "243" smd rect (at 88.4 -4.601 270) (size 1.8 0.57) (layers "F.Cu" "F.Paste" "F.Mask")
      (net 9 "GND") (pinfunction "VSS") (pintype "passive"))
    (pad "244" smd rect (at 89.248 -4.601 270) (size 1.8 0.57) (layers "F.Cu" "F.Paste" "F.Mask")
      (net 332 "DQS4_N") (pinfunction "DQS4_c") (pintype "passive"))
    (pad "245" smd rect (at 90.099 -4.601 270) (size 1.8 0.57) (layers "F.Cu" "F.Paste" "F.Mask")
      (net 330 "DQS4_P") (pinfunction "DQS4_t") (pintype "passive"))
    (pad "246" smd rect (at 90.95 -4.601 270) (size 1.8 0.57) (layers "F.Cu" "F.Paste" "F.Mask")
      (net 9 "GND") (pinfunction "VSS") (pintype "passive"))
    (pad "247" smd rect (at 91.799 -4.601 270) (size 1.8 0.57) (layers "F.Cu" "F.Paste" "F.Mask")
      (net 202 "DQ39") (pinfunction "DQ39") (pintype "passive"))
    (pad "248" smd rect (at 92.65 -4.601 270) (size 1.8 0.57) (layers "F.Cu" "F.Paste" "F.Mask")
      (net 9 "GND") (pinfunction "VSS") (pintype "passive"))
    (pad "249" smd rect (at 93.498 -4.601 270) (size 1.8 0.57) (layers "F.Cu" "F.Paste" "F.Mask")
      (net 213 "DQ35") (pinfunction "DQ35") (pintype "passive"))
    (pad "250" smd rect (at 94.349 -4.601 270) (size 1.8 0.57) (layers "F.Cu" "F.Paste" "F.Mask")
      (net 9 "GND") (pinfunction "VSS") (pintype "passive"))
    (pad "251" smd rect (at 95.2 -4.601 270) (size 1.8 0.57) (layers "F.Cu" "F.Paste" "F.Mask")
      (net 203 "DQ45") (pinfunction "DQ45") (pintype "passive"))
    (pad "252" smd rect (at 96.049 -4.601 270) (size 1.8 0.57) (layers "F.Cu" "F.Paste" "F.Mask")
      (net 9 "GND") (pinfunction "VSS") (pintype "passive"))
    (pad "253" smd rect (at 96.9 -4.601 270) (size 1.8 0.57) (layers "F.Cu" "F.Paste" "F.Mask")
      (net 189 "DQ41") (pinfunction "DQ41") (pintype "passive"))
    (pad "254" smd rect (at 97.748 -4.601 270) (size 1.8 0.57) (layers "F.Cu" "F.Paste" "F.Mask")
      (net 9 "GND") (pinfunction "VSS") (pintype "passive"))
    (pad "255" smd rect (at 98.599 -4.601 270) (size 1.8 0.57) (layers "F.Cu" "F.Paste" "F.Mask")
      (net 336 "DQS5_N") (pinfunction "DQS5_c") (pintype "passive"))
    (pad "256" smd rect (at 99.45 -4.601 270) (size 1.8 0.57) (layers "F.Cu" "F.Paste" "F.Mask")
      (net 334 "DQS5_P") (pinfunction "DQS5_t") (pintype "passive"))
    (pad "257" smd rect (at 100.299 -4.601 270) (size 1.8 0.57) (layers "F.Cu" "F.Paste" "F.Mask")
      (net 9 "GND") (pinfunction "VSS") (pintype "passive"))
    (pad "258" smd rect (at 101.15 -4.601 270) (size 1.8 0.57) (layers "F.Cu" "F.Paste" "F.Mask")
      (net 205 "DQ47") (pinfunction "DQ47") (pintype "passive"))
    (pad "259" smd rect (at 101.998 -4.601 270) (size 1.8 0.57) (layers "F.Cu" "F.Paste" "F.Mask")
      (net 9 "GND") (pinfunction "VSS") (pintype "passive"))
    (pad "260" smd rect (at 102.849 -4.601 270) (size 1.8 0.57) (layers "F.Cu" "F.Paste" "F.Mask")
      (net 188 "DQ43") (pinfunction "DQ43") (pintype "passive"))
    (pad "261" smd rect (at 103.7 -4.601 270) (size 1.8 0.57) (layers "F.Cu" "F.Paste" "F.Mask")
      (net 9 "GND") (pinfunction "VSS") (pintype "passive"))
    (pad "262" smd rect (at 104.549 -4.601 270) (size 1.8 0.57) (layers "F.Cu" "F.Paste" "F.Mask")
      (net 204 "DQ53") (pinfunction "DQ53") (pintype "passive"))
    (pad "263" smd rect (at 105.4 -4.601 270) (size 1.8 0.57) (layers "F.Cu" "F.Paste" "F.Mask")
      (net 9 "GND") (pinfunction "VSS") (pintype "passive"))
    (pad "264" smd rect (at 106.248 -4.601 270) (size 1.8 0.57) (layers "F.Cu" "F.Paste" "F.Mask")
      (net 190 "DQ49") (pinfunction "DQ49") (pintype "passive"))
    (pad "265" smd rect (at 107.099 -4.601 270) (size 1.8 0.57) (layers "F.Cu" "F.Paste" "F.Mask")
      (net 9 "GND") (pinfunction "VSS") (pintype "passive"))
    (pad "266" smd rect (at 107.95 -4.601 270) (size 1.8 0.57) (layers "F.Cu" "F.Paste" "F.Mask")
      (net 340 "DQS6_N") (pinfunction "DQS6_c") (pintype "passive"))
    (pad "267" smd rect (at 108.799 -4.601 270) (size 1.8 0.57) (layers "F.Cu" "F.Paste" "F.Mask")
      (net 338 "DQS6_P") (pinfunction "DQS6_t") (pintype "passive"))
    (pad "268" smd rect (at 109.65 -4.601 270) (size 1.8 0.57) (layers "F.Cu" "F.Paste" "F.Mask")
      (net 9 "GND") (pinfunction "VSS") (pintype "passive"))
    (pad "269" smd rect (at 110.498 -4.601 270) (size 1.8 0.57) (layers "F.Cu" "F.Paste" "F.Mask")
      (net 206 "DQ55") (pinfunction "DQ55") (pintype "passive"))
    (pad "270" smd rect (at 111.349 -4.601 270) (size 1.8 0.57) (layers "F.Cu" "F.Paste" "F.Mask")
      (net 9 "GND") (pinfunction "VSS") (pintype "passive"))
    (pad "271" smd rect (at 112.2 -4.601 270) (size 1.8 0.57) (layers "F.Cu" "F.Paste" "F.Mask")
      (net 193 "DQ51") (pinfunction "DQ51") (pintype "passive"))
    (pad "272" smd rect (at 113.049 -4.601 270) (size 1.8 0.57) (layers "F.Cu" "F.Paste" "F.Mask")
      (net 9 "GND") (pinfunction "VSS") (pintype "passive"))
    (pad "273" smd rect (at 113.9 -4.601 270) (size 1.8 0.57) (layers "F.Cu" "F.Paste" "F.Mask")
      (net 191 "DQ61") (pinfunction "DQ61") (pintype "passive"))
    (pad "274" smd rect (at 114.749 -4.601 270) (size 1.8 0.57) (layers "F.Cu" "F.Paste" "F.Mask")
      (net 9 "GND") (pinfunction "VSS") (pintype "passive"))
    (pad "275" smd rect (at 115.599 -4.601 270) (size 1.8 0.57) (layers "F.Cu" "F.Paste" "F.Mask")
      (net 192 "DQ57") (pinfunction "DQ57") (pintype "passive"))
    (pad "276" smd rect (at 116.45 -4.601 270) (size 1.8 0.57) (layers "F.Cu" "F.Paste" "F.Mask")
      (net 9 "GND") (pinfunction "VSS") (pintype "passive"))
    (pad "277" smd rect (at 117.299 -4.601 270) (size 1.8 0.57) (layers "F.Cu" "F.Paste" "F.Mask")
      (net 344 "DQS7_N") (pinfunction "DQS7_c") (pintype "passive"))
    (pad "278" smd rect (at 118.15 -4.601 270) (size 1.8 0.57) (layers "F.Cu" "F.Paste" "F.Mask")
      (net 342 "DQS7_P") (pinfunction "DQS7_t") (pintype "passive"))
    (pad "279" smd rect (at 118.999 -4.601 270) (size 1.8 0.57) (layers "F.Cu" "F.Paste" "F.Mask")
      (net 9 "GND") (pinfunction "VSS") (pintype "passive"))
    (pad "280" smd rect (at 119.849 -4.601 270) (size 1.8 0.57) (layers "F.Cu" "F.Paste" "F.Mask")
      (net 197 "DQ63") (pinfunction "DQ63") (pintype "passive"))
    (pad "281" smd rect (at 120.7 -4.601 270) (size 1.8 0.57) (layers "F.Cu" "F.Paste" "F.Mask")
      (net 9 "GND") (pinfunction "VSS") (pintype "passive"))
    (pad "282" smd rect (at 121.549 -4.601 270) (size 1.8 0.57) (layers "F.Cu" "F.Paste" "F.Mask")
      (net 196 "DQ59") (pinfunction "DQ59") (pintype "passive"))
    (pad "283" smd rect (at 122.4 -4.601 270) (size 1.8 0.57) (layers "F.Cu" "F.Paste" "F.Mask")
      (net 9 "GND") (pinfunction "VSS") (pintype "passive"))
    (pad "284" smd rect (at 123.249 -4.601 270) (size 1.8 0.57) (layers "F.Cu" "F.Paste" "F.Mask")
      (net 185 "VDDSPD") (pinfunction "VDDSPD") (pintype "passive"))
    (pad "285" smd rect (at 124.099 -4.601 270) (size 1.8 0.57) (layers "F.Cu" "F.Paste" "F.Mask")
      (net 350 "SDA_2V5") (pinfunction "SDA") (pintype "passive"))
    (pad "286" smd rect (at 124.95 -4.601 270) (size 1.8 0.57) (layers "F.Cu" "F.Paste" "F.Mask")
      (net 184 "VPP") (pinfunction "VPP") (pintype "passive"))
    (pad "287" smd rect (at 125.799 -4.601 270) (size 1.8 0.57) (layers "F.Cu" "F.Paste" "F.Mask")
      (net 184 "VPP") (pinfunction "VPP") (pintype "passive"))
    (pad "288" smd rect (at 126.65 -4.601 270) (size 1.8 0.57) (layers "F.Cu" "F.Paste" "F.Mask")
      (net 184 "VPP") (pinfunction "VPP") (pintype "passive"))
    (pad "MP1" thru_hole roundrect (at -5.651 -2.301) (size 1.8 3.05) (drill oval 1.2 2.45) (layers "*.Cu" "*.Mask") (roundrect_rratio 0.5)
      (net 708 "unconnected-(U14B-MP-PadMP1)") (pinfunction "MP") (pintype "passive+no_connect"))
    (pad "MP2" thru_hole roundrect (at 68.9 -2.301) (size 1.8 3.05) (drill oval 1.2 2.45) (layers "*.Cu" "*.Mask") (roundrect_rratio 0.5)
      (net 709 "unconnected-(U14B-MP-PadMP2)") (pinfunction "MP") (pintype "passive+no_connect"))
    (pad "MP3" thru_hole roundrect (at 132.3 -2.301) (size 1.8 3.05) (drill oval 1.2 2.45) (layers "*.Cu" "*.Mask") (roundrect_rratio 0.5)
      (net 710 "unconnected-(U14B-MP-PadMP3)") (pinfunction "MP") (pintype "passive+no_connect"))
  )

  (footprint "data-center-rdimm-ddr4-tester-footprints:Testpoint_smd_1mm" (layer "F.Cu")
    (at 143.536328 89.810008 90)
    (property "Author" "Antmicro")
    (property "License" "Apache-2.0")
    (property "MPN" "")
    (property "Manufacturer" "")
    (property "Sheetfile" "supply.kicad_sch")
    (property "Sheetname" "Supply")
    (property "ki_description" "Test Point 1mm")
    (attr exclude_from_pos_files)
    (fp_text reference "1V0" (at -0.339992 0.413672 180) (layer "F.SilkS")
        (effects (font (size 0.7 0.7) (thickness 0.15)) (justify left bottom))
    )
    (fp_text value "TP_1mm_SMD" (at 0 1.4 90) (layer "F.Fab") hide
        (effects (font (size 0.7 0.7) (thickness 0.15)) (justify left bottom))
    )
    (fp_text user "License: Apache-2.0" (at -0.5 5.2 90) (layer "F.Fab") hide
        (effects (font (size 0.7 0.7) (thickness 0.15)) (justify left bottom))
    )
    (fp_text user "${REFERENCE}" (at -0.5 2.8 90) (layer "F.Fab") hide
        (effects (font (size 0.7 0.7) (thickness 0.15)) (justify left bottom))
    )
    (fp_text user "Author: Antmicro" (at -0.5 4 90) (layer "F.Fab") hide
        (effects (font (size 0.7 0.7) (thickness 0.15)) (justify left bottom))
    )
    (pad "1" smd circle (at 0 0 90) (size 1 1) (layers "F.Cu" "F.Mask")
      (net 300 "VCC1V0") (pinfunction "1") (pintype "passive"))
  )

  (footprint "data-center-rdimm-ddr4-tester-footprints:C_0402_1005Metric" (layer "F.Cu")
    (at 175.94 107.11 -90)
    (descr "Capacitor SMD 0402")
    (tags "capacitor SMD 0402")
    (property "Author" "Antmicro")
    (property "Dielectric" "X5R")
    (property "License" "Apache-2.0")
    (property "MPN" "GRM155R61H104KE14D")
    (property "Manufacturer" "Murata")
    (property "Sheetfile" "fpga-banks-16-34.kicad_sch")
    (property "Sheetname" "FPGA banks 16-34")
    (property "Val" "100n")
    (property "Voltage" "50V")
    (property "ki_description" " ")
    (attr smd)
    (fp_text reference "C145" (at 1.34 0.6 -90) (layer "F.SilkS")
        (effects (font (size 0.7 0.7) (thickness 0.15)) (justify left bottom))
    )
    (fp_text value "C_100n_0402" (at 0 1.4 -90) (layer "F.Fab") hide
        (effects (font (size 0.7 0.7) (thickness 0.15)) (justify left bottom))
    )
    (fp_text user "License: Apache-2.0" (at -0.932 5.17 -90) (layer "F.Fab") hide
        (effects (font (size 0.7 0.7) (thickness 0.15)) (justify left bottom))
    )
    (fp_text user "${REFERENCE}" (at -0.932 3.168 -90) (layer "F.Fab") hide
        (effects (font (size 0.7 0.7) (thickness 0.15)) (justify left bottom))
    )
    (fp_text user "Author: Antmicro" (at -0.932 4.17 -90) (layer "F.Fab") hide
        (effects (font (size 0.7 0.7) (thickness 0.15)) (justify left bottom))
    )
    (fp_rect (start -0.94 -0.47) (end 0.94 0.47)
      (stroke (width 0.05) (type solid)) (fill none) (layer "F.CrtYd"))
    (fp_rect (start -0.499 -0.249) (end 0.499 0.249)
      (stroke (width 0.15) (type solid)) (fill none) (layer "F.Fab"))
    (pad "1" smd roundrect (at -0.484 0 270) (size 0.59 0.64) (layers "F.Cu" "F.Paste" "F.Mask") (roundrect_rratio 0.25)
      (net 143 "3V3_SYS") (pintype "passive"))
    (pad "2" smd roundrect (at 0.484 0 270) (size 0.59 0.64) (layers "F.Cu" "F.Paste" "F.Mask") (roundrect_rratio 0.25)
      (net 9 "GND") (pintype "passive"))
  )

  (footprint "data-center-rdimm-ddr4-tester-footprints:Oscillator_SMD_Abracon_ASFLMB_5x3.2x0.85mm" (layer "F.Cu")
    (at 179.136328 107.75 90)
    (property "Author" "Antmicro")
    (property "License" "Apache-2.0")
    (property "MPN" "ASFLMB-100.000MHZ-XY-T")
    (property "Manufacturer" "Abracon")
    (property "Sheetfile" "fpga-banks-16-34.kicad_sch")
    (property "Sheetname" "FPGA banks 16-34")
    (property "ki_description" "MEMS OSC XO 100.0000MHZ LVCMOS")
    (property "ki_keywords" "MEMS OSC XO 100.0000MHZ LVCMOS")
    (attr smd)
    (fp_text reference "U1" (at 2.04 -2.756328 180) (layer "F.SilkS")
        (effects (font (size 0.7 0.7) (thickness 0.15)) (justify left bottom))
    )
    (fp_text value "Oscillator_SMD_100MHz_ASFLMB" (at 0 3.8 90) (layer "F.Fab") hide
        (effects (font (size 0.7 0.7) (thickness 0.15)) (justify left bottom))
    )
    (fp_text user "${REFERENCE}" (at -2.8 5.06 90) (layer "F.Fab") hide
        (effects (font (size 0.7 0.7) (thickness 0.15)) (justify left bottom))
    )
    (fp_text user "Author: Antmicro" (at -2.8 6.259 90) (layer "F.Fab") hide
        (effects (font (size 0.7 0.7) (thickness 0.15)) (justify left bottom))
    )
    (fp_text user "License: Apache-2.0" (at -2.8 7.459 90) (layer "F.Fab") hide
        (effects (font (size 0.7 0.7) (thickness 0.15)) (justify left bottom))
    )
    (fp_line (start -1.6 -2.5) (end -1.6 -1.9)
      (stroke (width 0.15) (type solid)) (layer "F.SilkS"))
    (fp_line (start -1.6 -0.4) (end -1.6 0.6)
      (stroke (width 0.15) (type solid)) (layer "F.SilkS"))
    (fp_line (start -1.6 2.1) (end -1.6 2.7)
      (stroke (width 0.15) (type solid)) (layer "F.SilkS"))
    (fp_line (start -1.6 2.7) (end 1.8 2.7)
      (stroke (width 0.15) (type solid)) (layer "F.SilkS"))
    (fp_line (start 1.8 -2.5) (end -1.6 -2.5)
      (stroke (width 0.15) (type solid)) (layer "F.SilkS"))
    (fp_line (start 1.8 -1.9) (end 1.8 -2.5)
      (stroke (width 0.15) (type solid)) (layer "F.SilkS"))
    (fp_line (start 1.8 0.6) (end 1.8 -0.4)
      (stroke (width 0.15) (type solid)) (layer "F.SilkS"))
    (fp_line (start 1.8 2.7) (end 1.8 2.1)
      (stroke (width 0.15) (type solid)) (layer "F.SilkS"))
    (fp_circle (center -1.9 -2.1) (end -1.9 -2.05)
      (stroke (width 0.15) (type solid)) (fill solid) (layer "F.SilkS"))
    (fp_rect (start 2 -2.7) (end -1.8 2.9)
      (stroke (width 0.05) (type solid)) (fill none) (layer "F.CrtYd"))
    (pad "1" smd rect (at -1.049 -1.17 270) (size 1.1 1.2) (layers "F.Cu" "F.Paste" "F.Mask")
      (net 143 "3V3_SYS") (pinfunction "~{STDB}") (pintype "input"))
    (pad "2" smd rect (at -1.049 1.369) (size 1.2 1.1) (layers "F.Cu" "F.Paste" "F.Mask")
      (net 9 "GND") (pinfunction "GND") (pintype "unspecified"))
    (pad "3" smd rect (at 1.252 1.369) (size 1.2 1.1) (layers "F.Cu" "F.Paste" "F.Mask")
      (net 311 "GCLK100") (pinfunction "OUT") (pintype "output"))
    (pad "4" smd rect (at 1.252 -1.17) (size 1.2 1.1) (layers "F.Cu" "F.Paste" "F.Mask")
      (net 143 "3V3_SYS") (pinfunction "V_{DD}") (pintype "power_in"))
  )

  (footprint "data-center-rdimm-ddr4-tester-footprints:Testpoint_smd_1mm" (layer "F.Cu")
    (at 223.5 112.2 180)
    (property "Author" "Antmicro")
    (property "License" "Apache-2.0")
    (property "MPN" "")
    (property "Manufacturer" "")
    (property "Sheetfile" "config-spi.kicad_sch")
    (property "Sheetname" "Config SPI flash")
    (property "ki_description" "Test Point 1mm")
    (attr exclude_from_pos_files)
    (fp_text reference "PUDC_B1" (at 0.64 0.53 180) (layer "F.SilkS")
        (effects (font (size 0.7 0.7) (thickness 0.15)) (justify left bottom))
    )
    (fp_text value "TP_1mm_SMD" (at 0 1.4 180) (layer "F.Fab") hide
        (effects (font (size 0.7 0.7) (thickness 0.15)) (justify left bottom))
    )
    (fp_text user "${REFERENCE}" (at -0.5 2.8 180) (layer "F.Fab") hide
        (effects (font (size 0.7 0.7) (thickness 0.15)) (justify left bottom))
    )
    (fp_text user "Author: Antmicro" (at -0.5 4 180) (layer "F.Fab") hide
        (effects (font (size 0.7 0.7) (thickness 0.15)) (justify left bottom))
    )
    (fp_text user "License: Apache-2.0" (at -0.5 5.2 180) (layer "F.Fab") hide
        (effects (font (size 0.7 0.7) (thickness 0.15)) (justify left bottom))
    )
    (pad "1" smd circle (at 0 0 180) (size 1 1) (layers "F.Cu" "F.Mask")
      (net 79 "PUDC_B") (pinfunction "1") (pintype "passive"))
  )

  (footprint "data-center-rdimm-ddr4-tester-footprints:C_0402_1005Metric" (layer "F.Cu")
    (at 114.41 111.75)
    (descr "Capacitor SMD 0402")
    (tags "capacitor SMD 0402")
    (property "Author" "Antmicro")
    (property "Dielectric" "X5R")
    (property "License" "Apache-2.0")
    (property "MPN" "GRM155R61H104KE14D")
    (property "Manufacturer" "Murata")
    (property "Sheetfile" "supply.kicad_sch")
    (property "Sheetname" "Supply")
    (property "Val" "100n")
    (property "Voltage" "50V")
    (property "ki_description" " ")
    (attr smd)
    (fp_text reference "C178" (at -3.67 0.32) (layer "F.SilkS")
        (effects (font (size 0.7 0.7) (thickness 0.15)) (justify left bottom))
    )
    (fp_text value "C_100n_0402" (at 0 1.4) (layer "F.Fab") hide
        (effects (font (size 0.7 0.7) (thickness 0.15)) (justify left bottom))
    )
    (fp_text user "${REFERENCE}" (at -0.932 3.168) (layer "F.Fab") hide
        (effects (font (size 0.7 0.7) (thickness 0.15)) (justify left bottom))
    )
    (fp_text user "Author: Antmicro" (at -0.932 4.17) (layer "F.Fab") hide
        (effects (font (size 0.7 0.7) (thickness 0.15)) (justify left bottom))
    )
    (fp_text user "License: Apache-2.0" (at -0.932 5.17) (layer "F.Fab") hide
        (effects (font (size 0.7 0.7) (thickness 0.15)) (justify left bottom))
    )
    (fp_rect (start -0.94 -0.47) (end 0.94 0.47)
      (stroke (width 0.05) (type solid)) (fill none) (layer "F.CrtYd"))
    (fp_rect (start -0.499 -0.249) (end 0.499 0.249)
      (stroke (width 0.15) (type solid)) (fill none) (layer "F.Fab"))
    (pad "1" smd roundrect (at -0.484 0) (size 0.59 0.64) (layers "F.Cu" "F.Paste" "F.Mask") (roundrect_rratio 0.25)
      (net 71 "Net-(IC1-BOOT)") (pintype "passive"))
    (pad "2" smd roundrect (at 0.484 0) (size 0.59 0.64) (layers "F.Cu" "F.Paste" "F.Mask") (roundrect_rratio 0.25)
      (net 73 "Net-(IC1-SW)") (pintype "passive"))
  )

  (footprint "data-center-rdimm-ddr4-tester-footprints:R_0402_1005Metric" (layer "F.Cu")
    (at 178.04 63.055 90)
    (descr "Resistor SMD 0402")
    (tags "resistor SMD 0402")
    (property "Author" "Antmicro")
    (property "License" "Apache-2.0")
    (property "MPN" "CR0402-FX-1002GLF")
    (property "Manufacturer" "Bourns")
    (property "Sheetfile" "fpga-banks-16-34.kicad_sch")
    (property "Sheetname" "FPGA banks 16-34")
    (property "Tolerance" "1%")
    (property "Val" "10k")
    (property "ki_description" "10k resistor in 0402 package with 1% tolerance")
    (attr smd)
    (fp_text reference "R163" (at -3.715 0.37 90) (layer "F.SilkS")
        (effects (font (size 0.7 0.7) (thickness 0.15)) (justify left bottom))
    )
    (fp_text value "R_10k_0402" (at 0 1.4 90) (layer "F.Fab") hide
        (effects (font (size 0.7 0.7) (thickness 0.15)) (justify left bottom))
    )
    (fp_text user "License: Apache-2.0" (at -0.95 5.169 90) (layer "F.Fab") hide
        (effects (font (size 0.7 0.7) (thickness 0.15)) (justify left bottom))
    )
    (fp_text user "${REFERENCE}" (at -0.95 3.168 90) (layer "F.Fab") hide
        (effects (font (size 0.7 0.7) (thickness 0.15)) (justify left bottom))
    )
    (fp_text user "Author: Antmicro" (at -0.95 4.169 90) (layer "F.Fab") hide
        (effects (font (size 0.7 0.7) (thickness 0.15)) (justify left bottom))
    )
    (fp_rect (start -0.93 -0.47) (end 0.93 0.47)
      (stroke (width 0.05) (type solid)) (fill none) (layer "F.CrtYd"))
    (fp_rect (start -0.5 -0.25) (end 0.5 0.25)
      (stroke (width 0.15) (type solid)) (fill none) (layer "F.Fab"))
    (pad "1" smd roundrect (at -0.485 0 90) (size 0.59 0.64) (layers "F.Cu" "F.Paste" "F.Mask") (roundrect_rratio 0.25)
      (net 658 "Net-(U15G-IO_L4N_T0_33)") (pintype "passive"))
    (pad "2" smd roundrect (at 0.485 0 90) (size 0.59 0.64) (layers "F.Cu" "F.Paste" "F.Mask") (roundrect_rratio 0.25)
      (net 187 "~{EVENT}") (pintype "passive"))
  )

  (footprint "data-center-rdimm-ddr4-tester-footprints:R_0402_1005Metric" (layer "F.Cu")
    (at 117.336328 64.160008 180)
    (descr "Resistor SMD 0402")
    (tags "resistor SMD 0402")
    (property "Author" "Antmicro")
    (property "Current" "1A")
    (property "DNP" "DNP")
    (property "License" "Apache-2.0")
    (property "MPN" "ERJ2GE0R00X")
    (property "Manufacturer" "Panasonic")
    (property "Sheetfile" "fpga-banks-16-34.kicad_sch")
    (property "Sheetname" "FPGA banks 16-34")
    (property "Tolerance" "")
    (property "Val" "0R")
    (property "dnp" "")
    (property "exclude_from_bom" "")
    (property "ki_description" "0R resistor in 0402 package with unspecified tolerance")
    (attr exclude_from_pos_files exclude_from_bom)
    (fp_text reference "R166" (at -0.813672 -0.349992 180) (layer "F.SilkS")
        (effects (font (size 0.7 0.7) (thickness 0.15)) (justify left bottom))
    )
    (fp_text value "R_0R_0402" (at 0 1.4 180) (layer "F.Fab") hide
        (effects (font (size 0.7 0.7) (thickness 0.15)) (justify left bottom))
    )
    (fp_text user "Author: Antmicro" (at -0.95 4.169 180) (layer "F.Fab") hide
        (effects (font (size 0.7 0.7) (thickness 0.15)) (justify left bottom))
    )
    (fp_text user "${REFERENCE}" (at -0.95 3.168 180) (layer "F.Fab") hide
        (effects (font (size 0.7 0.7) (thickness 0.15)) (justify left bottom))
    )
    (fp_text user "License: Apache-2.0" (at -0.95 5.169 180) (layer "F.Fab") hide
        (effects (font (size 0.7 0.7) (thickness 0.15)) (justify left bottom))
    )
    (fp_rect (start -0.93 -0.47) (end 0.93 0.47)
      (stroke (width 0.05) (type solid)) (fill none) (layer "F.CrtYd"))
    (fp_rect (start -0.5 -0.25) (end 0.5 0.25)
      (stroke (width 0.15) (type solid)) (fill none) (layer "F.Fab"))
    (pad "1" smd roundrect (at -0.485 0 180) (size 0.59 0.64) (layers "F.Cu" "F.Paste" "F.Mask") (roundrect_rratio 0.25)
      (net 185 "VDDSPD") (pintype "passive"))
    (pad "2" smd roundrect (at 0.485 0 180) (size 0.59 0.64) (layers "F.Cu" "F.Paste" "F.Mask") (roundrect_rratio 0.25)
      (net 214 "SA1") (pintype "passive"))
  )

  (footprint "data-center-rdimm-ddr4-tester-footprints:R_0402_1005Metric" (layer "F.Cu")
    (at 117.336328 65.160008 180)
    (descr "Resistor SMD 0402")
    (tags "resistor SMD 0402")
    (property "Author" "Antmicro")
    (property "Current" "1A")
    (property "DNP" "DNP")
    (property "License" "Apache-2.0")
    (property "MPN" "ERJ2GE0R00X")
    (property "Manufacturer" "Panasonic")
    (property "Sheetfile" "fpga-banks-16-34.kicad_sch")
    (property "Sheetname" "FPGA banks 16-34")
    (property "Tolerance" "")
    (property "Val" "0R")
    (property "dnp" "")
    (property "exclude_from_bom" "")
    (property "ki_description" "0R resistor in 0402 package with unspecified tolerance")
    (attr exclude_from_pos_files exclude_from_bom)
    (fp_text reference "R168" (at -0.813672 -0.349992 180) (layer "F.SilkS")
        (effects (font (size 0.7 0.7) (thickness 0.15)) (justify left bottom))
    )
    (fp_text value "R_0R_0402" (at 0 1.4 180) (layer "F.Fab") hide
        (effects (font (size 0.7 0.7) (thickness 0.15)) (justify left bottom))
    )
    (fp_text user "Author: Antmicro" (at -0.95 4.169 180) (layer "F.Fab") hide
        (effects (font (size 0.7 0.7) (thickness 0.15)) (justify left bottom))
    )
    (fp_text user "License: Apache-2.0" (at -0.95 5.169 180) (layer "F.Fab") hide
        (effects (font (size 0.7 0.7) (thickness 0.15)) (justify left bottom))
    )
    (fp_text user "${REFERENCE}" (at -0.95 3.168 180) (layer "F.Fab") hide
        (effects (font (size 0.7 0.7) (thickness 0.15)) (justify left bottom))
    )
    (fp_rect (start -0.93 -0.47) (end 0.93 0.47)
      (stroke (width 0.05) (type solid)) (fill none) (layer "F.CrtYd"))
    (fp_rect (start -0.5 -0.25) (end 0.5 0.25)
      (stroke (width 0.15) (type solid)) (fill none) (layer "F.Fab"))
    (pad "1" smd roundrect (at -0.485 0 180) (size 0.59 0.64) (layers "F.Cu" "F.Paste" "F.Mask") (roundrect_rratio 0.25)
      (net 185 "VDDSPD") (pintype "passive"))
    (pad "2" smd roundrect (at 0.485 0 180) (size 0.59 0.64) (layers "F.Cu" "F.Paste" "F.Mask") (roundrect_rratio 0.25)
      (net 218 "SA0") (pintype "passive"))
  )

  (footprint "data-center-rdimm-ddr4-tester-footprints:R_0402_1005Metric" (layer "F.Cu")
    (at 122.487128 74.106008 180)
    (descr "Resistor SMD 0402")
    (tags "resistor SMD 0402")
    (property "Author" "Antmicro")
    (property "License" "Apache-2.0")
    (property "MPN" "CR0402-FX-4701GLF")
    (property "Manufacturer" "Bourns")
    (property "Sheetfile" "fpga-banks-16-34.kicad_sch")
    (property "Sheetname" "FPGA banks 16-34")
    (property "Tolerance" "1%")
    (property "Val" "4k7")
    (property "ki_description" "4k7 resistor in 0402 package with 1% tolerance")
    (attr smd)
    (fp_text reference "R171" (at -0.802872 -0.373992 180) (layer "F.SilkS")
        (effects (font (size 0.7 0.7) (thickness 0.15)) (justify left bottom))
    )
    (fp_text value "R_4k7_0402" (at 0 1.4 180) (layer "F.Fab") hide
        (effects (font (size 0.7 0.7) (thickness 0.15)) (justify left bottom))
    )
    (fp_text user "License: Apache-2.0" (at -0.95 5.169 180) (layer "F.Fab") hide
        (effects (font (size 0.7 0.7) (thickness 0.15)) (justify left bottom))
    )
    (fp_text user "Author: Antmicro" (at -0.95 4.169 180) (layer "F.Fab") hide
        (effects (font (size 0.7 0.7) (thickness 0.15)) (justify left bottom))
    )
    (fp_text user "${REFERENCE}" (at -0.95 3.168 180) (layer "F.Fab") hide
        (effects (font (size 0.7 0.7) (thickness 0.15)) (justify left bottom))
    )
    (fp_rect (start -0.93 -0.47) (end 0.93 0.47)
      (stroke (width 0.05) (type solid)) (fill none) (layer "F.CrtYd"))
    (fp_rect (start -0.5 -0.25) (end 0.5 0.25)
      (stroke (width 0.15) (type solid)) (fill none) (layer "F.Fab"))
    (pad "1" smd roundrect (at -0.485 0 180) (size 0.59 0.64) (layers "F.Cu" "F.Paste" "F.Mask") (roundrect_rratio 0.25)
      (net 143 "3V3_SYS") (pintype "passive"))
    (pad "2" smd roundrect (at 0.485 0 180) (size 0.59 0.64) (layers "F.Cu" "F.Paste" "F.Mask") (roundrect_rratio 0.25)
      (net 358 "SCL_3V3") (pintype "passive"))
  )

  (footprint "data-center-rdimm-ddr4-tester-footprints:R_0402_1005Metric" (layer "F.Cu")
    (at 122.486328 66.185008 180)
    (descr "Resistor SMD 0402")
    (tags "resistor SMD 0402")
    (property "Author" "Antmicro")
    (property "License" "Apache-2.0")
    (property "MPN" "CR0402-FX-4701GLF")
    (property "Manufacturer" "Bourns")
    (property "Sheetfile" "fpga-banks-16-34.kicad_sch")
    (property "Sheetname" "FPGA banks 16-34")
    (property "Tolerance" "1%")
    (property "Val" "4k7")
    (property "ki_description" "4k7 resistor in 0402 package with 1% tolerance")
    (attr smd)
    (fp_text reference "R174" (at -1.053672 -0.364992 180) (layer "F.SilkS")
        (effects (font (size 0.7 0.7) (thickness 0.15)) (justify left bottom))
    )
    (fp_text value "R_4k7_0402" (at 0 1.4 180) (layer "F.Fab") hide
        (effects (font (size 0.7 0.7) (thickness 0.15)) (justify left bottom))
    )
    (fp_text user "Author: Antmicro" (at -0.95 4.169 180) (layer "F.Fab") hide
        (effects (font (size 0.7 0.7) (thickness 0.15)) (justify left bottom))
    )
    (fp_text user "License: Apache-2.0" (at -0.95 5.169 180) (layer "F.Fab") hide
        (effects (font (size 0.7 0.7) (thickness 0.15)) (justify left bottom))
    )
    (fp_text user "${REFERENCE}" (at -0.95 3.168 180) (layer "F.Fab") hide
        (effects (font (size 0.7 0.7) (thickness 0.15)) (justify left bottom))
    )
    (fp_rect (start -0.93 -0.47) (end 0.93 0.47)
      (stroke (width 0.05) (type solid)) (fill none) (layer "F.CrtYd"))
    (fp_rect (start -0.5 -0.25) (end 0.5 0.25)
      (stroke (width 0.15) (type solid)) (fill none) (layer "F.Fab"))
    (pad "1" smd roundrect (at -0.485 0 180) (size 0.59 0.64) (layers "F.Cu" "F.Paste" "F.Mask") (roundrect_rratio 0.25)
      (net 185 "VDDSPD") (pintype "passive"))
    (pad "2" smd roundrect (at 0.485 0 180) (size 0.59 0.64) (layers "F.Cu" "F.Paste" "F.Mask") (roundrect_rratio 0.25)
      (net 351 "SCL_2V5") (pintype "passive"))
  )

  (footprint "data-center-rdimm-ddr4-tester-footprints:Testpoint_smd_1mm" (layer "F.Cu")
    (at 118.964728 72.190808)
    (property "Author" "Antmicro")
    (property "License" "Apache-2.0")
    (property "MPN" "")
    (property "Manufacturer" "")
    (property "Sheetfile" "fpga-banks-16-34.kicad_sch")
    (property "Sheetname" "FPGA banks 16-34")
    (property "ki_description" "Test Point 1mm")
    (attr exclude_from_pos_files)
    (fp_text reference "TP12" (at -1.764728 -0.630808) (layer "F.SilkS")
        (effects (font (size 0.7 0.7) (thickness 0.15)) (justify left bottom))
    )
    (fp_text value "TP_1mm_SMD" (at 0 1.4) (layer "F.Fab") hide
        (effects (font (size 0.7 0.7) (thickness 0.15)) (justify left bottom))
    )
    (fp_text user "License: Apache-2.0" (at -0.5 5.2) (layer "F.Fab") hide
        (effects (font (size 0.7 0.7) (thickness 0.15)) (justify left bottom))
    )
    (fp_text user "${REFERENCE}" (at -0.5 2.8) (layer "F.Fab") hide
        (effects (font (size 0.7 0.7) (thickness 0.15)) (justify left bottom))
    )
    (fp_text user "Author: Antmicro" (at -0.5 4) (layer "F.Fab") hide
        (effects (font (size 0.7 0.7) (thickness 0.15)) (justify left bottom))
    )
    (pad "1" smd circle (at 0 0) (size 1 1) (layers "F.Cu" "F.Mask")
      (net 666 "Net-(U8-EN)") (pinfunction "1") (pintype "passive"))
  )

  (footprint "data-center-rdimm-ddr4-tester-footprints:R_0402_1005Metric" (layer "F.Cu")
    (at 120.587128 74.106008)
    (descr "Resistor SMD 0402")
    (tags "resistor SMD 0402")
    (property "Author" "Antmicro")
    (property "License" "Apache-2.0")
    (property "MPN" "CR0402-FX-4701GLF")
    (property "Manufacturer" "Bourns")
    (property "Sheetfile" "fpga-banks-16-34.kicad_sch")
    (property "Sheetname" "FPGA banks 16-34")
    (property "Tolerance" "1%")
    (property "Val" "4k7")
    (property "ki_description" "4k7 resistor in 0402 package with 1% tolerance")
    (attr smd)
    (fp_text reference "R172" (at -3.707128 0.343992) (layer "F.SilkS")
        (effects (font (size 0.7 0.7) (thickness 0.15)) (justify left bottom))
    )
    (fp_text value "R_4k7_0402" (at 0 1.4) (layer "F.Fab") hide
        (effects (font (size 0.7 0.7) (thickness 0.15)) (justify left bottom))
    )
    (fp_text user "${REFERENCE}" (at -0.95 3.168) (layer "F.Fab") hide
        (effects (font (size 0.7 0.7) (thickness 0.15)) (justify left bottom))
    )
    (fp_text user "Author: Antmicro" (at -0.95 4.169) (layer "F.Fab") hide
        (effects (font (size 0.7 0.7) (thickness 0.15)) (justify left bottom))
    )
    (fp_text user "License: Apache-2.0" (at -0.95 5.169) (layer "F.Fab") hide
        (effects (font (size 0.7 0.7) (thickness 0.15)) (justify left bottom))
    )
    (fp_rect (start -0.93 -0.47) (end 0.93 0.47)
      (stroke (width 0.05) (type solid)) (fill none) (layer "F.CrtYd"))
    (fp_rect (start -0.5 -0.25) (end 0.5 0.25)
      (stroke (width 0.15) (type solid)) (fill none) (layer "F.Fab"))
    (pad "1" smd roundrect (at -0.485 0) (size 0.59 0.64) (layers "F.Cu" "F.Paste" "F.Mask") (roundrect_rratio 0.25)
      (net 143 "3V3_SYS") (pintype "passive"))
    (pad "2" smd roundrect (at 0.485 0) (size 0.59 0.64) (layers "F.Cu" "F.Paste" "F.Mask") (roundrect_rratio 0.25)
      (net 357 "SDA_3V3") (pintype "passive"))
  )

  (footprint "data-center-rdimm-ddr4-tester-footprints:R_0402_1005Metric" (layer "F.Cu")
    (at 117.336328 63.160008 180)
    (descr "Resistor SMD 0402")
    (tags "resistor SMD 0402")
    (property "Author" "Antmicro")
    (property "Current" "1A")
    (property "DNP" "DNP")
    (property "License" "Apache-2.0")
    (property "MPN" "ERJ2GE0R00X")
    (property "Manufacturer" "Panasonic")
    (property "Sheetfile" "fpga-banks-16-34.kicad_sch")
    (property "Sheetname" "FPGA banks 16-34")
    (property "Tolerance" "")
    (property "Val" "0R")
    (property "dnp" "")
    (property "exclude_from_bom" "")
    (property "ki_description" "0R resistor in 0402 package with unspecified tolerance")
    (attr exclude_from_pos_files exclude_from_bom)
    (fp_text reference "R164" (at -0.813672 -0.349992 180) (layer "F.SilkS")
        (effects (font (size 0.7 0.7) (thickness 0.15)) (justify left bottom))
    )
    (fp_text value "R_0R_0402" (at 0 1.4 180) (layer "F.Fab") hide
        (effects (font (size 0.7 0.7) (thickness 0.15)) (justify left bottom))
    )
    (fp_text user "License: Apache-2.0" (at -0.95 5.169 180) (layer "F.Fab") hide
        (effects (font (size 0.7 0.7) (thickness 0.15)) (justify left bottom))
    )
    (fp_text user "${REFERENCE}" (at -0.95 3.168 180) (layer "F.Fab") hide
        (effects (font (size 0.7 0.7) (thickness 0.15)) (justify left bottom))
    )
    (fp_text user "Author: Antmicro" (at -0.95 4.169 180) (layer "F.Fab") hide
        (effects (font (size 0.7 0.7) (thickness 0.15)) (justify left bottom))
    )
    (fp_rect (start -0.93 -0.47) (end 0.93 0.47)
      (stroke (width 0.05) (type solid)) (fill none) (layer "F.CrtYd"))
    (fp_rect (start -0.5 -0.25) (end 0.5 0.25)
      (stroke (width 0.15) (type solid)) (fill none) (layer "F.Fab"))
    (pad "1" smd roundrect (at -0.485 0 180) (size 0.59 0.64) (layers "F.Cu" "F.Paste" "F.Mask") (roundrect_rratio 0.25)
      (net 185 "VDDSPD") (pintype "passive"))
    (pad "2" smd roundrect (at 0.485 0 180) (size 0.59 0.64) (layers "F.Cu" "F.Paste" "F.Mask") (roundrect_rratio 0.25)
      (net 195 "SA2") (pintype "passive"))
  )

  (footprint "data-center-rdimm-ddr4-tester-footprints:R_0402_1005Metric" (layer "F.Cu")
    (at 112.336328 65.160008 180)
    (descr "Resistor SMD 0402")
    (tags "resistor SMD 0402")
    (property "Author" "Antmicro")
    (property "Current" "1A")
    (property "License" "Apache-2.0")
    (property "MPN" "ERJ2GE0R00X")
    (property "Manufacturer" "Panasonic")
    (property "Sheetfile" "fpga-banks-16-34.kicad_sch")
    (property "Sheetname" "FPGA banks 16-34")
    (property "Tolerance" "")
    (property "Val" "0R")
    (property "ki_description" "0R resistor in 0402 package with unspecified tolerance")
    (attr smd)
    (fp_text reference "R169" (at 4.126328 -0.369992 180) (layer "F.SilkS")
        (effects (font (size 0.7 0.7) (thickness 0.15)) (justify left bottom))
    )
    (fp_text value "R_0R_0402" (at 0 1.4 180) (layer "F.Fab") hide
        (effects (font (size 0.7 0.7) (thickness 0.15)) (justify left bottom))
    )
    (fp_text user "License: Apache-2.0" (at -0.95 5.169 180) (layer "F.Fab") hide
        (effects (font (size 0.7 0.7) (thickness 0.15)) (justify left bottom))
    )
    (fp_text user "Author: Antmicro" (at -0.95 4.169 180) (layer "F.Fab") hide
        (effects (font (size 0.7 0.7) (thickness 0.15)) (justify left bottom))
    )
    (fp_text user "${REFERENCE}" (at -0.95 3.168 180) (layer "F.Fab") hide
        (effects (font (size 0.7 0.7) (thickness 0.15)) (justify left bottom))
    )
    (fp_rect (start -0.93 -0.47) (end 0.93 0.47)
      (stroke (width 0.05) (type solid)) (fill none) (layer "F.CrtYd"))
    (fp_rect (start -0.5 -0.25) (end 0.5 0.25)
      (stroke (width 0.15) (type solid)) (fill none) (layer "F.Fab"))
    (pad "1" smd roundrect (at -0.485 0 180) (size 0.59 0.64) (layers "F.Cu" "F.Paste" "F.Mask") (roundrect_rratio 0.25)
      (net 218 "SA0") (pintype "passive"))
    (pad "2" smd roundrect (at 0.485 0 180) (size 0.59 0.64) (layers "F.Cu" "F.Paste" "F.Mask") (roundrect_rratio 0.25)
      (net 9 "GND") (pintype "passive"))
  )

  (footprint "data-center-rdimm-ddr4-tester-footprints:R_0402_1005Metric" (layer "F.Cu")
    (at 112.336328 63.160008 180)
    (descr "Resistor SMD 0402")
    (tags "resistor SMD 0402")
    (property "Author" "Antmicro")
    (property "Current" "1A")
    (property "License" "Apache-2.0")
    (property "MPN" "ERJ2GE0R00X")
    (property "Manufacturer" "Panasonic")
    (property "Sheetfile" "fpga-banks-16-34.kicad_sch")
    (property "Sheetname" "FPGA banks 16-34")
    (property "Tolerance" "")
    (property "Val" "0R")
    (property "ki_description" "0R resistor in 0402 package with unspecified tolerance")
    (attr smd)
    (fp_text reference "R165" (at 4.126328 -0.369992 180) (layer "F.SilkS")
        (effects (font (size 0.7 0.7) (thickness 0.15)) (justify left bottom))
    )
    (fp_text value "R_0R_0402" (at 0 1.4 180) (layer "F.Fab") hide
        (effects (font (size 0.7 0.7) (thickness 0.15)) (justify left bottom))
    )
    (fp_text user "License: Apache-2.0" (at -0.95 5.169 180) (layer "F.Fab") hide
        (effects (font (size 0.7 0.7) (thickness 0.15)) (justify left bottom))
    )
    (fp_text user "Author: Antmicro" (at -0.95 4.169 180) (layer "F.Fab") hide
        (effects (font (size 0.7 0.7) (thickness 0.15)) (justify left bottom))
    )
    (fp_text user "${REFERENCE}" (at -0.95 3.168 180) (layer "F.Fab") hide
        (effects (font (size 0.7 0.7) (thickness 0.15)) (justify left bottom))
    )
    (fp_rect (start -0.93 -0.47) (end 0.93 0.47)
      (stroke (width 0.05) (type solid)) (fill none) (layer "F.CrtYd"))
    (fp_rect (start -0.5 -0.25) (end 0.5 0.25)
      (stroke (width 0.15) (type solid)) (fill none) (layer "F.Fab"))
    (pad "1" smd roundrect (at -0.485 0 180) (size 0.59 0.64) (layers "F.Cu" "F.Paste" "F.Mask") (roundrect_rratio 0.25)
      (net 195 "SA2") (pintype "passive"))
    (pad "2" smd roundrect (at 0.485 0 180) (size 0.59 0.64) (layers "F.Cu" "F.Paste" "F.Mask") (roundrect_rratio 0.25)
      (net 9 "GND") (pintype "passive"))
  )

  (footprint "data-center-rdimm-ddr4-tester-footprints:R_0402_1005Metric" (layer "F.Cu")
    (at 112.336328 64.160008 180)
    (descr "Resistor SMD 0402")
    (tags "resistor SMD 0402")
    (property "Author" "Antmicro")
    (property "Current" "1A")
    (property "License" "Apache-2.0")
    (property "MPN" "ERJ2GE0R00X")
    (property "Manufacturer" "Panasonic")
    (property "Sheetfile" "fpga-banks-16-34.kicad_sch")
    (property "Sheetname" "FPGA banks 16-34")
    (property "Tolerance" "")
    (property "Val" "0R")
    (property "ki_description" "0R resistor in 0402 package with unspecified tolerance")
    (attr smd)
    (fp_text reference "R167" (at 4.126328 -0.369992 180) (layer "F.SilkS")
        (effects (font (size 0.7 0.7) (thickness 0.15)) (justify left bottom))
    )
    (fp_text value "R_0R_0402" (at 0 1.4 180) (layer "F.Fab") hide
        (effects (font (size 0.7 0.7) (thickness 0.15)) (justify left bottom))
    )
    (fp_text user "Author: Antmicro" (at -0.95 4.169 180) (layer "F.Fab") hide
        (effects (font (size 0.7 0.7) (thickness 0.15)) (justify left bottom))
    )
    (fp_text user "${REFERENCE}" (at -0.95 3.168 180) (layer "F.Fab") hide
        (effects (font (size 0.7 0.7) (thickness 0.15)) (justify left bottom))
    )
    (fp_text user "License: Apache-2.0" (at -0.95 5.169 180) (layer "F.Fab") hide
        (effects (font (size 0.7 0.7) (thickness 0.15)) (justify left bottom))
    )
    (fp_rect (start -0.93 -0.47) (end 0.93 0.47)
      (stroke (width 0.05) (type solid)) (fill none) (layer "F.CrtYd"))
    (fp_rect (start -0.5 -0.25) (end 0.5 0.25)
      (stroke (width 0.15) (type solid)) (fill none) (layer "F.Fab"))
    (pad "1" smd roundrect (at -0.485 0 180) (size 0.59 0.64) (layers "F.Cu" "F.Paste" "F.Mask") (roundrect_rratio 0.25)
      (net 214 "SA1") (pintype "passive"))
    (pad "2" smd roundrect (at 0.485 0 180) (size 0.59 0.64) (layers "F.Cu" "F.Paste" "F.Mask") (roundrect_rratio 0.25)
      (net 9 "GND") (pintype "passive"))
  )

  (footprint "data-center-rdimm-ddr4-tester-footprints:R_0402_1005Metric" (layer "F.Cu")
    (at 177.04 63.055 90)
    (descr "Resistor SMD 0402")
    (tags "resistor SMD 0402")
    (property "Author" "Antmicro")
    (property "License" "Apache-2.0")
    (property "MPN" "CR0402-FX-4701GLF")
    (property "Manufacturer" "Bourns")
    (property "Sheetfile" "fpga-banks-16-34.kicad_sch")
    (property "Sheetname" "FPGA banks 16-34")
    (property "Tolerance" "1%")
    (property "Val" "4k7")
    (property "ki_description" "4k7 resistor in 0402 package with 1% tolerance")
    (attr smd)
    (fp_text reference "R170" (at -3.715 0.37 90) (layer "F.SilkS")
        (effects (font (size 0.7 0.7) (thickness 0.15)) (justify left bottom))
    )
    (fp_text value "R_4k7_0402" (at 0 1.4 90) (layer "F.Fab") hide
        (effects (font (size 0.7 0.7) (thickness 0.15)) (justify left bottom))
    )
    (fp_text user "Author: Antmicro" (at -0.95 4.169 90) (layer "F.Fab") hide
        (effects (font (size 0.7 0.7) (thickness 0.15)) (justify left bottom))
    )
    (fp_text user "License: Apache-2.0" (at -0.95 5.169 90) (layer "F.Fab") hide
        (effects (font (size 0.7 0.7) (thickness 0.15)) (justify left bottom))
    )
    (fp_text user "${REFERENCE}" (at -0.95 3.168 90) (layer "F.Fab") hide
        (effects (font (size 0.7 0.7) (thickness 0.15)) (justify left bottom))
    )
    (fp_rect (start -0.93 -0.47) (end 0.93 0.47)
      (stroke (width 0.05) (type solid)) (fill none) (layer "F.CrtYd"))
    (fp_rect (start -0.5 -0.25) (end 0.5 0.25)
      (stroke (width 0.15) (type solid)) (fill none) (layer "F.Fab"))
    (pad "1" smd roundrect (at -0.485 0 90) (size 0.59 0.64) (layers "F.Cu" "F.Paste" "F.Mask") (roundrect_rratio 0.25)
      (net 77 "VDDQ") (pintype "passive"))
    (pad "2" smd roundrect (at 0.485 0 90) (size 0.59 0.64) (layers "F.Cu" "F.Paste" "F.Mask") (roundrect_rratio 0.25)
      (net 187 "~{EVENT}") (pintype "passive"))
  )

  (footprint "data-center-rdimm-ddr4-tester-footprints:WSON-8_6x8x0.5mm_P1.27mm" (layer "F.Cu")
    (at 230.052 117.636)
    (property "Author" "Antmicro")
    (property "License" "Apache-2.0")
    (property "MPN" "S25FL128SAGNFI000")
    (property "Manufacturer" "Cypress Semiconductor")
    (property "Sheetfile" "config-spi.kicad_sch")
    (property "Sheetname" "Config SPI flash")
    (property "ki_description" "28 Mbit (16 Mbyte)/256 Mbit (32 Mbyte), 3.0V SPI Flash Memory")
    (property "ki_keywords" "28 Mbit (16 Mbyte)/256 Mbit (32 Mbyte), 3.0V SPI Flash Memory")
    (attr smd)
    (fp_text reference "U3" (at 0 -3.6) (layer "F.SilkS")
        (effects (font (size 0.7 0.7) (thickness 0.15)) (justify left bottom))
    )
    (fp_text value "S25FL128SAGNFI000" (at 0 4.3) (layer "F.Fab") hide
        (effects (font (size 0.7 0.7) (thickness 0.15)) (justify left bottom))
    )
    (fp_text user "${REFERENCE}" (at 0 10.903) (layer "F.Fab") hide
        (effects (font (size 0.7 0.7) (thickness 0.15)) (justify left bottom))
    )
    (fp_text user "Author: Antmicro" (at 0 12.104) (layer "F.Fab") hide
        (effects (font (size 0.7 0.7) (thickness 0.15)) (justify left bottom))
    )
    (fp_text user "License: Apache-2.0" (at 0 13.303) (layer "F.Fab") hide
        (effects (font (size 0.7 0.7) (thickness 0.15)) (justify left bottom))
    )
    (fp_line (start 4 -3.2) (end -3.975 -3.2)
      (stroke (width 0.15) (type solid)) (layer "F.SilkS"))
    (fp_line (start 4.0005 3.2) (end -3.9995 3.2)
      (stroke (width 0.15) (type solid)) (layer "F.SilkS"))
    (fp_circle (center -4.2 -2.4) (end -4.149 -2.4)
      (stroke (width 0.15) (type solid)) (fill solid) (layer "F.SilkS"))
    (fp_rect (start -4.7 -3.25) (end 4.7 3.25)
      (stroke (width 0.05) (type solid)) (fill none) (layer "F.CrtYd"))
    (fp_line (start -3.9995 3.0005) (end -3.9995 -1.9995)
      (stroke (width 0.15) (type solid)) (layer "F.Fab"))
    (fp_line (start -3.0015 -2.9995) (end -3.9995 -1.9995)
      (stroke (width 0.15) (type solid)) (layer "F.Fab"))
    (fp_line (start -3.0015 -2.9995) (end 3.9995 -2.9995)
      (stroke (width 0.15) (type solid)) (layer "F.Fab"))
    (fp_line (start 3.9995 -2.9995) (end 3.9995 3.0005)
      (stroke (width 0.15) (type solid)) (layer "F.Fab"))
    (fp_line (start 3.9995 3.0005) (end -3.9995 3.0005)
      (stroke (width 0.15) (type solid)) (layer "F.Fab"))
    (pad "1" smd roundrect (at -3.9995 -1.9045 270) (size 0.4 1.3) (layers "F.Cu" "F.Paste" "F.Mask") (roundrect_rratio 0.25)
      (net 596 "Net-(U3-~{CS})") (pinfunction "~{CS}") (pintype "input"))
    (pad "2" smd roundrect (at -3.9995 -0.6355 270) (size 0.4 1.3) (layers "F.Cu" "F.Paste" "F.Mask") (roundrect_rratio 0.25)
      (net 651 "Net-(U3-SO{slash}IO1)") (pinfunction "SO/IO1") (pintype "bidirectional"))
    (pad "3" smd roundrect (at -3.9995 0.6345 270) (size 0.4 1.3) (layers "F.Cu" "F.Paste" "F.Mask") (roundrect_rratio 0.25)
      (net 600 "Net-(U3-~{WP}{slash}IO2)") (pinfunction "~{WP}/IO2") (pintype "bidirectional"))
    (pad "4" smd roundrect (at -3.9995 1.9045 270) (size 0.4 1.3) (layers "F.Cu" "F.Paste" "F.Mask") (roundrect_rratio 0.25)
      (net 9 "GND") (pinfunction "V_{SS}") (pintype "power_in"))
    (pad "5" smd roundrect (at 3.9995 1.8755 270) (size 0.4 1.3) (layers "F.Cu" "F.Paste" "F.Mask") (roundrect_rratio 0.25)
      (net 650 "Net-(U3-SI{slash}IO0)") (pinfunction "SI/IO0") (pintype "bidirectional"))
    (pad "6" smd roundrect (at 3.9995 0.6035 270) (size 0.4 1.3) (layers "F.Cu" "F.Paste" "F.Mask") (roundrect_rratio 0.25)
      (net 597 "Net-(U3-SCK)") (pinfunction "SCK") (pintype "input"))
    (pad "7" smd roundrect (at 3.9995 -0.6655 270) (size 0.4 1.3) (layers "F.Cu" "F.Paste" "F.Mask") (roundrect_rratio 0.25)
      (net 599 "Net-(U3-~{HOLD}{slash}IO3)") (pinfunction "~{HOLD}/IO3") (pintype "bidirectional"))
    (pad "8" smd roundrect (at 3.9995 -1.9355 270) (size 0.4 1.3) (layers "F.Cu" "F.Paste" "F.Mask") (roundrect_rratio 0.25)
      (net 143 "3V3_SYS") (pinfunction "V_{CC}") (pintype "power_in"))
    (pad "9" smd roundrect (at -0.0005 -0.0005) (size 4.8 4.65) (layers "F.Cu" "F.Paste" "F.Mask") (roundrect_rratio 0.05)
      (chamfer_ratio 0.1) (chamfer top_left)
      (net 667 "unconnected-(U3-EP-Pad9)") (pinfunction "EP") (pintype "no_connect"))
  )

  (footprint "data-center-rdimm-ddr4-tester-footprints:R_0402_1005Metric" (layer "F.Cu")
    (at 145.046328 114.597157 90)
    (descr "Resistor SMD 0402")
    (tags "resistor SMD 0402")
    (property "Author" "Antmicro")
    (property "License" "Apache-2.0")
    (property "MPN" "CR0402-FX-1002GLF")
    (property "Manufacturer" "Bourns")
    (property "Sheetfile" "interfaces.kicad_sch")
    (property "Sheetname" "Interfaces")
    (property "Tolerance" "1%")
    (property "Val" "10k")
    (property "ki_description" "10k resistor in 0402 package with 1% tolerance")
    (attr smd)
    (fp_text reference "R130" (at -1.362843 -0.566328 90) (layer "F.SilkS")
        (effects (font (size 0.7 0.7) (thickness 0.15)) (justify left bottom))
    )
    (fp_text value "R_10k_0402" (at 0 1.4 90) (layer "F.Fab") hide
        (effects (font (size 0.7 0.7) (thickness 0.15)) (justify left bottom))
    )
    (fp_text user "${REFERENCE}" (at -0.95 3.168 90) (layer "F.Fab") hide
        (effects (font (size 0.7 0.7) (thickness 0.15)) (justify left bottom))
    )
    (fp_text user "Author: Antmicro" (at -0.95 4.169 90) (layer "F.Fab") hide
        (effects (font (size 0.7 0.7) (thickness 0.15)) (justify left bottom))
    )
    (fp_text user "License: Apache-2.0" (at -0.95 5.169 90) (layer "F.Fab") hide
        (effects (font (size 0.7 0.7) (thickness 0.15)) (justify left bottom))
    )
    (fp_rect (start -0.93 -0.47) (end 0.93 0.47)
      (stroke (width 0.05) (type solid)) (fill none) (layer "F.CrtYd"))
    (fp_rect (start -0.5 -0.25) (end 0.5 0.25)
      (stroke (width 0.15) (type solid)) (fill none) (layer "F.Fab"))
    (pad "1" smd roundrect (at -0.485 0 90) (size 0.59 0.64) (layers "F.Cu" "F.Paste" "F.Mask") (roundrect_rratio 0.25)
      (net 143 "3V3_SYS") (pintype "passive"))
    (pad "2" smd roundrect (at 0.485 0 90) (size 0.59 0.64) (layers "F.Cu" "F.Paste" "F.Mask") (roundrect_rratio 0.25)
      (net 657 "Net-(U7-~{RESET})") (pintype "passive"))
  )

  (footprint "data-center-rdimm-ddr4-tester-footprints:C_0402_1005Metric" (layer "F.Cu")
    (at 120.136328 95.81)
    (descr "Capacitor SMD 0402")
    (tags "capacitor SMD 0402")
    (property "Author" "Antmicro")
    (property "Dielectric" "X5R")
    (property "License" "Apache-2.0")
    (property "MPN" "GRM155R61H104KE14D")
    (property "Manufacturer" "Murata")
    (property "Sheetfile" "supply.kicad_sch")
    (property "Sheetname" "Supply")
    (property "Val" "100n")
    (property "Voltage" "50V")
    (property "ki_description" " ")
    (attr smd)
    (fp_text reference "C35" (at 0.353672 1.3) (layer "F.SilkS")
        (effects (font (size 0.7 0.7) (thickness 0.15)) (justify left bottom))
    )
    (fp_text value "C_100n_0402" (at 0 1.4) (layer "F.Fab") hide
        (effects (font (size 0.7 0.7) (thickness 0.15)) (justify left bottom))
    )
    (fp_text user "${REFERENCE}" (at -0.932 3.168) (layer "F.Fab") hide
        (effects (font (size 0.7 0.7) (thickness 0.15)) (justify left bottom))
    )
    (fp_text user "Author: Antmicro" (at -0.932 4.17) (layer "F.Fab") hide
        (effects (font (size 0.7 0.7) (thickness 0.15)) (justify left bottom))
    )
    (fp_text user "License: Apache-2.0" (at -0.932 5.17) (layer "F.Fab") hide
        (effects (font (size 0.7 0.7) (thickness 0.15)) (justify left bottom))
    )
    (fp_rect (start -0.94 -0.47) (end 0.94 0.47)
      (stroke (width 0.05) (type solid)) (fill none) (layer "F.CrtYd"))
    (fp_rect (start -0.499 -0.249) (end 0.499 0.249)
      (stroke (width 0.15) (type solid)) (fill none) (layer "F.Fab"))
    (pad "1" smd roundrect (at -0.484 0) (size 0.59 0.64) (layers "F.Cu" "F.Paste" "F.Mask") (roundrect_rratio 0.25)
      (net 105 "Net-(C35-Pad1)") (pintype "passive"))
    (pad "2" smd roundrect (at 0.484 0) (size 0.59 0.64) (layers "F.Cu" "F.Paste" "F.Mask") (roundrect_rratio 0.25)
      (net 1 "Net-(U2-SW)") (pintype "passive"))
  )

  (footprint "data-center-rdimm-ddr4-tester-footprints:C_0402_1005Metric" (layer "F.Cu")
    (at 119.411328 114.497157 180)
    (descr "Capacitor SMD 0402")
    (tags "capacitor SMD 0402")
    (property "Author" "Antmicro")
    (property "Dielectric" "")
    (property "License" "Apache-2.0")
    (property "MPN" "CGA2B3X7S2A472K050BB")
    (property "Manufacturer" "TDK")
    (property "Sheetfile" "supply.kicad_sch")
    (property "Sheetname" "Supply")
    (property "Val" "4n7")
    (property "Voltage" "")
    (property "ki_description" " ")
    (attr smd)
    (fp_text reference "C172" (at 4.911328 -3.222843 180) (layer "F.SilkS")
        (effects (font (size 0.7 0.7) (thickness 0.15)) (justify left bottom))
    )
    (fp_text value "C_4n7_0402" (at 0 1.4 180) (layer "F.Fab") hide
        (effects (font (size 0.7 0.7) (thickness 0.15)) (justify left bottom))
    )
    (fp_text user "License: Apache-2.0" (at -0.932 5.17 180) (layer "F.Fab") hide
        (effects (font (size 0.7 0.7) (thickness 0.15)) (justify left bottom))
    )
    (fp_text user "${REFERENCE}" (at -0.932 3.168 180) (layer "F.Fab") hide
        (effects (font (size 0.7 0.7) (thickness 0.15)) (justify left bottom))
    )
    (fp_text user "Author: Antmicro" (at -0.932 4.17 180) (layer "F.Fab") hide
        (effects (font (size 0.7 0.7) (thickness 0.15)) (justify left bottom))
    )
    (fp_rect (start -0.94 -0.47) (end 0.94 0.47)
      (stroke (width 0.05) (type solid)) (fill none) (layer "F.CrtYd"))
    (fp_rect (start -0.499 -0.249) (end 0.499 0.249)
      (stroke (width 0.15) (type solid)) (fill none) (layer "F.Fab"))
    (pad "1" smd roundrect (at -0.484 0 180) (size 0.59 0.64) (layers "F.Cu" "F.Paste" "F.Mask") (roundrect_rratio 0.25)
      (net 107 "Net-(C172-Pad1)") (pintype "passive"))
    (pad "2" smd roundrect (at 0.484 0 180) (size 0.59 0.64) (layers "F.Cu" "F.Paste" "F.Mask") (roundrect_rratio 0.25)
      (net 9 "GND") (pintype "passive"))
  )

  (footprint "data-center-rdimm-ddr4-tester-footprints:C_0402_1005Metric" (layer "F.Cu")
    (at 123.917728 71.655008 90)
    (descr "Capacitor SMD 0402")
    (tags "capacitor SMD 0402")
    (property "Author" "Antmicro")
    (property "Dielectric" "X5R")
    (property "License" "Apache-2.0")
    (property "MPN" "GRM155R61H104KE14D")
    (property "Manufacturer" "Murata")
    (property "Sheetfile" "fpga-banks-16-34.kicad_sch")
    (property "Sheetname" "FPGA banks 16-34")
    (property "Val" "100n")
    (property "Voltage" "50V")
    (property "ki_description" " ")
    (attr smd)
    (fp_text reference "C206" (at -1.364992 1.322272 90) (layer "F.SilkS")
        (effects (font (size 0.7 0.7) (thickness 0.15)) (justify left bottom))
    )
    (fp_text value "C_100n_0402" (at 0 1.4 90) (layer "F.Fab") hide
        (effects (font (size 0.7 0.7) (thickness 0.15)) (justify left bottom))
    )
    (fp_text user "${REFERENCE}" (at -0.932 3.168 90) (layer "F.Fab") hide
        (effects (font (size 0.7 0.7) (thickness 0.15)) (justify left bottom))
    )
    (fp_text user "Author: Antmicro" (at -0.932 4.17 90) (layer "F.Fab") hide
        (effects (font (size 0.7 0.7) (thickness 0.15)) (justify left bottom))
    )
    (fp_text user "License: Apache-2.0" (at -0.932 5.17 90) (layer "F.Fab") hide
        (effects (font (size 0.7 0.7) (thickness 0.15)) (justify left bottom))
    )
    (fp_rect (start -0.94 -0.47) (end 0.94 0.47)
      (stroke (width 0.05) (type solid)) (fill none) (layer "F.CrtYd"))
    (fp_rect (start -0.499 -0.249) (end 0.499 0.249)
      (stroke (width 0.15) (type solid)) (fill none) (layer "F.Fab"))
    (pad "1" smd roundrect (at -0.484 0 90) (size 0.59 0.64) (layers "F.Cu" "F.Paste" "F.Mask") (roundrect_rratio 0.25)
      (net 143 "3V3_SYS") (pintype "passive"))
    (pad "2" smd roundrect (at 0.484 0 90) (size 0.59 0.64) (layers "F.Cu" "F.Paste" "F.Mask") (roundrect_rratio 0.25)
      (net 9 "GND") (pintype "passive"))
  )

  (footprint "data-center-rdimm-ddr4-tester-footprints:C_0402_1005Metric" (layer "F.Cu")
    (at 123.917728 68.225008 -90)
    (descr "Capacitor SMD 0402")
    (tags "capacitor SMD 0402")
    (property "Author" "Antmicro")
    (property "Dielectric" "X5R")
    (property "License" "Apache-2.0")
    (property "MPN" "GRM155R61H104KE14D")
    (property "Manufacturer" "Murata")
    (property "Sheetfile" "fpga-banks-16-34.kicad_sch")
    (property "Sheetname" "FPGA banks 16-34")
    (property "Val" "100n")
    (property "Voltage" "50V")
    (property "ki_description" " ")
    (attr smd)
    (fp_text reference "C207" (at 1.494992 -1.322272 -90) (layer "F.SilkS")
        (effects (font (size 0.7 0.7) (thickness 0.15)) (justify left bottom))
    )
    (fp_text value "C_100n_0402" (at 0 1.4 -90) (layer "F.Fab") hide
        (effects (font (size 0.7 0.7) (thickness 0.15)) (justify left bottom))
    )
    (fp_text user "Author: Antmicro" (at -0.932 4.17 -90) (layer "F.Fab") hide
        (effects (font (size 0.7 0.7) (thickness 0.15)) (justify left bottom))
    )
    (fp_text user "${REFERENCE}" (at -0.932 3.168 -90) (layer "F.Fab") hide
        (effects (font (size 0.7 0.7) (thickness 0.15)) (justify left bottom))
    )
    (fp_text user "License: Apache-2.0" (at -0.932 5.17 -90) (layer "F.Fab") hide
        (effects (font (size 0.7 0.7) (thickness 0.15)) (justify left bottom))
    )
    (fp_rect (start -0.94 -0.47) (end 0.94 0.47)
      (stroke (width 0.05) (type solid)) (fill none) (layer "F.CrtYd"))
    (fp_rect (start -0.499 -0.249) (end 0.499 0.249)
      (stroke (width 0.15) (type solid)) (fill none) (layer "F.Fab"))
    (pad "1" smd roundrect (at -0.484 0 270) (size 0.59 0.64) (layers "F.Cu" "F.Paste" "F.Mask") (roundrect_rratio 0.25)
      (net 185 "VDDSPD") (pintype "passive"))
    (pad "2" smd roundrect (at 0.484 0 270) (size 0.59 0.64) (layers "F.Cu" "F.Paste" "F.Mask") (roundrect_rratio 0.25)
      (net 9 "GND") (pintype "passive"))
  )

  (footprint "data-center-rdimm-ddr4-tester-footprints:TSSOP-8_3x3mm_P0.65mm" (layer "F.Cu")
    (at 121.55 69.875 -90)
    (property "Author" "Antmicro")
    (property "License" "Apache-2.0")
    (property "MPN" "PCA9517ADMR2G")
    (property "Manufacturer" "ON Semiconductor")
    (property "Sheetfile" "fpga-banks-16-34.kicad_sch")
    (property "Sheetname" "FPGA banks 16-34")
    (property "ki_description" "Translation - Voltage Levels LEVEL TRANSLATING I2")
    (property "ki_keywords" "Translation - Voltage Levels LEVEL TRANSLATING I2")
    (attr smd)
    (fp_text reference "U8" (at -1.105 1.76 90) (layer "F.SilkS")
        (effects (font (size 0.7 0.7) (thickness 0.15)) (justify right bottom))
    )
    (fp_text value "PCA9517A_TSSOP" (at 0 2.8 90) (layer "F.Fab") hide
        (effects (font (size 0.7 0.7) (thickness 0.15)) (justify right bottom))
    )
    (fp_text user "${REFERENCE}" (at -1.789 6.58 90) (layer "F.Fab") hide
        (effects (font (size 0.7 0.7) (thickness 0.15)) (justify right bottom))
    )
    (fp_text user "Author: Antmicro" (at -1.789 7.78 90) (layer "F.Fab") hide
        (effects (font (size 0.7 0.7) (thickness 0.15)) (justify right bottom))
    )
    (fp_text user "License: Apache-2.0" (at -1.789 8.98 90) (layer "F.Fab") hide
        (effects (font (size 0.7 0.7) (thickness 0.15)) (justify right bottom))
    )
    (fp_line (start -1.55 1.561) (end 1.552 1.561)
      (stroke (width 0.15) (type solid)) (layer "F.SilkS"))
    (fp_line (start -1.525 -1.537) (end 1.552 -1.539)
      (stroke (width 0.15) (type solid)) (layer "F.SilkS"))
    (fp_circle (center -1.87 -1.4) (end -1.82 -1.4)
      (stroke (width 0.15) (type solid)) (fill solid) (layer "F.SilkS"))
    (fp_rect (start -3.15 -1.789) (end 3.15 1.811)
      (stroke (width 0.05) (type solid)) (fill none) (layer "F.CrtYd"))
    (fp_line (start -1.55 -0.937) (end -1.55 1.561)
      (stroke (width 0.15) (type solid)) (layer "F.Fab"))
    (fp_line (start -1.55 -0.937) (end -0.949 -1.539)
      (stroke (width 0.15) (type solid)) (layer "F.Fab"))
    (fp_line (start -1.55 1.561) (end 1.552 1.561)
      (stroke (width 0.15) (type solid)) (layer "F.Fab"))
    (fp_line (start -0.949 -1.539) (end 1.552 -1.539)
      (stroke (width 0.15) (type solid)) (layer "F.Fab"))
    (fp_line (start 1.552 -1.539) (end 1.552 1.561)
      (stroke (width 0.15) (type solid)) (layer "F.Fab"))
    (pad "1" smd roundrect (at -2.148 -0.962 270) (size 1.47 0.4) (layers "F.Cu" "F.Paste" "F.Mask") (roundrect_rratio 0.25)
      (net 185 "VDDSPD") (pinfunction "VREF_{1}") (pintype "power_in"))
    (pad "2" smd roundrect (at -2.148 -0.313 270) (size 1.47 0.4) (layers "F.Cu" "F.Paste" "F.Mask") (roundrect_rratio 0.25)
      (net 351 "SCL_2V5") (pinfunction "SCL_{1}") (pintype "bidirectional"))
    (pad "3" smd roundrect (at -2.148 0.338 270) (size 1.47 0.4) (layers "F.Cu" "F.Paste" "F.Mask") (roundrect_rratio 0.25)
      (net 350 "SDA_2V5") (pinfunction "SDA_{1}") (pintype "bidirectional"))
    (pad "4" smd roundrect (at -2.148 0.987 270) (size 1.47 0.4) (layers "F.Cu" "F.Paste" "F.Mask") (roundrect_rratio 0.25)
      (net 9 "GND") (pinfunction "GND") (pintype "power_in"))
    (pad "5" smd roundrect (at 2.151 0.987 270) (size 1.47 0.4) (layers "F.Cu" "F.Paste" "F.Mask") (roundrect_rratio 0.25)
      (net 666 "Net-(U8-EN)") (pinfunction "EN") (pintype "input"))
    (pad "6" smd roundrect (at 2.151 0.338 270) (size 1.47 0.4) (layers "F.Cu" "F.Paste" "F.Mask") (roundrect_rratio 0.25)
      (net 357 "SDA_3V3") (pinfunction "SDA_{2}") (pintype "bidirectional"))
    (pad "7" smd roundrect (at 2.151 -0.313 270) (size 1.47 0.4) (layers "F.Cu" "F.Paste" "F.Mask") (roundrect_rratio 0.25)
      (net 358 "SCL_3V3") (pinfunction "SCL_{2}") (pintype "bidirectional"))
    (pad "8" smd roundrect (at 2.151 -0.962 270) (size 1.47 0.4) (layers "F.Cu" "F.Paste" "F.Mask") (roundrect_rratio 0.25)
      (net 143 "3V3_SYS") (pinfunction "VREF_{2}") (pintype "power_in"))
  )

  (footprint "data-center-rdimm-ddr4-tester-footprints:R_0402_1005Metric" (layer "F.Cu")
    (at 120.586328 66.185008)
    (descr "Resistor SMD 0402")
    (tags "resistor SMD 0402")
    (property "Author" "Antmicro")
    (property "License" "Apache-2.0")
    (property "MPN" "CR0402-FX-4701GLF")
    (property "Manufacturer" "Bourns")
    (property "Sheetfile" "fpga-banks-16-34.kicad_sch")
    (property "Sheetname" "FPGA banks 16-34")
    (property "Tolerance" "1%")
    (property "Val" "4k7")
    (property "ki_description" "4k7 resistor in 0402 package with 1% tolerance")
    (attr smd)
    (fp_text reference "R173" (at -3.606328 0.324992) (layer "F.SilkS")
        (effects (font (size 0.7 0.7) (thickness 0.15)) (justify left bottom))
    )
    (fp_text value "R_4k7_0402" (at 0 1.4) (layer "F.Fab") hide
        (effects (font (size 0.7 0.7) (thickness 0.15)) (justify left bottom))
    )
    (fp_text user "${REFERENCE}" (at -0.95 3.168) (layer "F.Fab") hide
        (effects (font (size 0.7 0.7) (thickness 0.15)) (justify left bottom))
    )
    (fp_text user "License: Apache-2.0" (at -0.95 5.169) (layer "F.Fab") hide
        (effects (font (size 0.7 0.7) (thickness 0.15)) (justify left bottom))
    )
    (fp_text user "Author: Antmicro" (at -0.95 4.169) (layer "F.Fab") hide
        (effects (font (size 0.7 0.7) (thickness 0.15)) (justify left bottom))
    )
    (fp_rect (start -0.93 -0.47) (end 0.93 0.47)
      (stroke (width 0.05) (type solid)) (fill none) (layer "F.CrtYd"))
    (fp_rect (start -0.5 -0.25) (end 0.5 0.25)
      (stroke (width 0.15) (type solid)) (fill none) (layer "F.Fab"))
    (pad "1" smd roundrect (at -0.485 0) (size 0.59 0.64) (layers "F.Cu" "F.Paste" "F.Mask") (roundrect_rratio 0.25)
      (net 185 "VDDSPD") (pintype "passive"))
    (pad "2" smd roundrect (at 0.485 0) (size 0.59 0.64) (layers "F.Cu" "F.Paste" "F.Mask") (roundrect_rratio 0.25)
      (net 350 "SDA_2V5") (pintype "passive"))
  )

  (footprint "data-center-rdimm-ddr4-tester-footprints:L_1716_4441Metric" (layer "F.Cu")
    (at 148.299328 117.477008 -90)
    (property "Author" "Antmicro")
    (property "License" "Apache-2.0")
    (property "MPN" "SRP0420-1R5K")
    (property "Manufacturer" "Bourns")
    (property "MaxCur" "6A")
    (property "Sheetfile" "supply.kicad_sch")
    (property "Sheetname" "Supply")
    (property "Size" "4.40x4.10")
    (property "Val" "1u5/6A")
    (attr smd)
    (fp_text reference "L4" (at 2.942992 2.249328 -90) (layer "F.SilkS")
        (effects (font (size 0.7 0.7) (thickness 0.15)) (justify left bottom))
    )
    (fp_text value "L_1u5_6A_1716" (at 0 3.3 -90) (layer "F.Fab") hide
        (effects (font (size 0.7 0.7) (thickness 0.15)) (justify left bottom))
    )
    (fp_text user "License: Apache-2.0" (at -17.726 19.484 -90) (layer "F.Fab") hide
        (effects (font (size 0.7 0.7) (thickness 0.15)) (justify left bottom))
    )
    (fp_text user "Author: Antmicro" (at -17.726 18.283 -90) (layer "F.Fab") hide
        (effects (font (size 0.7 0.7) (thickness 0.15)) (justify left bottom))
    )
    (fp_text user "${REFERENCE}" (at -17.726 17.083 -90) (layer "F.Fab") hide
        (effects (font (size 0.7 0.7) (thickness 0.15)) (justify left bottom))
    )
    (fp_line (start -2.202 -2.0555) (end 2.248 -2.0555)
      (stroke (width 0.15) (type solid)) (layer "F.SilkS"))
    (fp_line (start -2.202 -1.5265) (end -2.202 -2.0555)
      (stroke (width 0.15) (type solid)) (layer "F.SilkS"))
    (fp_line (start -2.202 2.0535) (end -2.202 1.5245)
      (stroke (width 0.15) (type solid)) (layer "F.SilkS"))
    (fp_line (start -2.202 2.0535) (end 2.248 2.0535)
      (stroke (width 0.15) (type solid)) (layer "F.SilkS"))
    (fp_line (start 2.248 -2.0555) (end 2.248 -1.5265)
      (stroke (width 0.15) (type solid)) (layer "F.SilkS"))
    (fp_line (start 2.248 2.0535) (end 2.248 1.5245)
      (stroke (width 0.15) (type solid)) (layer "F.SilkS"))
    (fp_rect (start -2.775 -2.35) (end 2.775 2.35)
      (stroke (width 0.05) (type solid)) (fill none) (layer "F.CrtYd"))
    (fp_line (start -2.202 -2.0555) (end 2.248 -2.0555)
      (stroke (width 0.15) (type solid)) (layer "F.Fab"))
    (fp_line (start -2.202 2.0295) (end -2.202 -2.0305)
      (stroke (width 0.15) (type solid)) (layer "F.Fab"))
    (fp_line (start 2.248 -2.0305) (end 2.248 2.0295)
      (stroke (width 0.15) (type solid)) (layer "F.Fab"))
    (fp_line (start 2.248 2.0535) (end -2.202 2.0535)
      (stroke (width 0.15) (type solid)) (layer "F.Fab"))
    (pad "1" smd roundrect (at -2 -0.0015 270) (size 1.4 1.9) (layers "F.Cu" "F.Paste" "F.Mask") (roundrect_rratio 0.05)
      (net 8 "Net-(U5-SW)") (pintype "passive"))
    (pad "2" smd roundrect (at 2 -0.0015 270) (size 1.4 1.9) (layers "F.Cu" "F.Paste" "F.Mask") (roundrect_rratio 0.05)
      (net 176 "VCC1V2") (pintype "passive"))
  )

  (footprint "data-center-rdimm-ddr4-tester-footprints:R_0402_1005Metric" (layer "F.Cu")
    (at 155.149328 114.102008 90)
    (descr "Resistor SMD 0402")
    (tags "resistor SMD 0402")
    (property "Author" "Antmicro")
    (property "License" "Apache-2.0")
    (property "MPN" "CR0402-FX-1002GLF")
    (property "Manufacturer" "Bourns")
    (property "Sheetfile" "supply.kicad_sch")
    (property "Sheetname" "Supply")
    (property "Tolerance" "1%")
    (property "Val" "10k")
    (property "ki_description" "10k resistor in 0402 package with 1% tolerance")
    (attr smd)
    (fp_text reference "R46" (at -1.067992 2.200672 90) (layer "F.SilkS")
        (effects (font (size 0.7 0.7) (thickness 0.15)) (justify left bottom))
    )
    (fp_text value "R_10k_0402" (at 0 1.4 90) (layer "F.Fab") hide
        (effects (font (size 0.7 0.7) (thickness 0.15)) (justify left bottom))
    )
    (fp_text user "License: Apache-2.0" (at -0.95 5.169 90) (layer "F.Fab") hide
        (effects (font (size 0.7 0.7) (thickness 0.15)) (justify left bottom))
    )
    (fp_text user "${REFERENCE}" (at -0.95 3.168 90) (layer "F.Fab") hide
        (effects (font (size 0.7 0.7) (thickness 0.15)) (justify left bottom))
    )
    (fp_text user "Author: Antmicro" (at -0.95 4.169 90) (layer "F.Fab") hide
        (effects (font (size 0.7 0.7) (thickness 0.15)) (justify left bottom))
    )
    (fp_rect (start -0.93 -0.47) (end 0.93 0.47)
      (stroke (width 0.05) (type solid)) (fill none) (layer "F.CrtYd"))
    (fp_rect (start -0.5 -0.25) (end 0.5 0.25)
      (stroke (width 0.15) (type solid)) (fill none) (layer "F.Fab"))
    (pad "1" smd roundrect (at -0.485 0 90) (size 0.59 0.64) (layers "F.Cu" "F.Paste" "F.Mask") (roundrect_rratio 0.25)
      (net 625 "Net-(U5-FB)") (pintype "passive"))
    (pad "2" smd roundrect (at 0.485 0 90) (size 0.59 0.64) (layers "F.Cu" "F.Paste" "F.Mask") (roundrect_rratio 0.25)
      (net 9 "GND") (pintype "passive"))
  )

  (footprint "data-center-rdimm-ddr4-tester-footprints:AP62301WU-7-TSOT23-6" (layer "F.Cu")
    (at 152.499328 117.127008)
    (property "Author" "Antmicro")
    (property "License" "Apache-2.0")
    (property "MPN" "AP62301WU-7")
    (property "Manufacturer" "Diodes Incorporated")
    (property "Sheetfile" "supply.kicad_sch")
    (property "Sheetname" "Supply")
    (attr smd)
    (fp_text reference "U5" (at 1.310672 -0.917008) (layer "F.SilkS")
        (effects (font (size 0.7 0.7) (thickness 0.15)) (justify left bottom))
    )
    (fp_text value "AP62301WU-7" (at -0.005 2.6) (layer "F.Fab") hide
        (effects (font (size 0.7 0.7) (thickness 0.15)) (justify left bottom))
    )
    (fp_text user "${REFERENCE}" (at -1.893 6.168) (layer "F.Fab") hide
        (effects (font (size 0.7 0.7) (thickness 0.15)) (justify left bottom))
    )
    (fp_text user "License: Apache-2.0" (at -1.893 4.967) (layer "F.Fab") hide
        (effects (font (size 0.7 0.7) (thickness 0.15)) (justify left bottom))
    )
    (fp_text user "Author: Antmicro" (at -1.893 7.368) (layer "F.Fab") hide
        (effects (font (size 0.7 0.7) (thickness 0.15)) (justify left bottom))
    )
    (fp_line (start -1.4805 0.725) (end -1.4795 -0.725)
      (stroke (width 0.15) (type solid)) (layer "F.SilkS"))
    (fp_line (start -1.4805 0.725) (end -1.3905 0.725)
      (stroke (width 0.15) (type solid)) (layer "F.SilkS"))
    (fp_line (start -1.4795 -0.725) (end -1.3905 -0.725)
      (stroke (width 0.15) (type solid)) (layer "F.SilkS"))
    (fp_line (start 1.479 0.73) (end 1.38 0.73)
      (stroke (width 0.15) (type solid)) (layer "F.SilkS"))
    (fp_line (start 1.48 -0.72) (end 1.38 -0.72)
      (stroke (width 0.15) (type solid)) (layer "F.SilkS"))
    (fp_line (start 1.48 -0.72) (end 1.479 0.73)
      (stroke (width 0.15) (type solid)) (layer "F.SilkS"))
    (fp_circle (center -1.499 1.236) (end -1.45 1.236)
      (stroke (width 0.15) (type solid)) (fill solid) (layer "F.SilkS"))
    (fp_rect (start -1.65 -1.61) (end 1.65 1.61)
      (stroke (width 0.05) (type solid)) (fill none) (layer "F.CrtYd"))
    (fp_line (start -1.527 -0.833) (end 1.523 -0.833)
      (stroke (width 0.15) (type solid)) (layer "F.Fab"))
    (fp_line (start -1.527 0.491) (end -1.527 -0.833)
      (stroke (width 0.15) (type solid)) (layer "F.Fab"))
    (fp_line (start -1.527 0.491) (end -1.102 0.916)
      (stroke (width 0.15) (type solid)) (layer "F.Fab"))
    (fp_line (start -1.102 0.916) (end 1.523 0.916)
      (stroke (width 0.15) (type solid)) (layer "F.Fab"))
    (fp_line (start 1.523 -0.833) (end 1.523 0.916)
      (stroke (width 0.15) (type solid)) (layer "F.Fab"))
    (pad "1" smd rect (at -0.952 1.18) (size 0.7 0.8) (layers "F.Cu" "F.Paste" "F.Mask")
      (net 9 "GND") (pinfunction "GND") (pintype "power_in"))
    (pad "2" smd rect (at -0.001 1.18) (size 0.7 0.8) (layers "F.Cu" "F.Paste" "F.Mask")
      (net 8 "Net-(U5-SW)") (pinfunction "SW") (pintype "power_out"))
    (pad "3" smd rect (at 0.947 1.18) (size 0.7 0.8) (layers "F.Cu" "F.Paste" "F.Mask")
      (net 307 "5V0_SYS") (pinfunction "VIN") (pintype "power_in"))
    (pad "4" smd rect (at 0.947 -1.18) (size 0.7 0.8) (layers "F.Cu" "F.Paste" "F.Mask")
      (net 625 "Net-(U5-FB)") (pinfunction "FB") (pintype "input"))
    (pad "5" smd rect (at -0.001 -1.18) (size 0.7 0.8) (layers "F.Cu" "F.Paste" "F.Mask")
      (net 624 "Net-(U5-EN)") (pinfunction "EN") (pintype "input"))
    (pad "6" smd rect (at -0.952 -1.18) (size 0.7 0.8) (layers "F.Cu" "F.Paste" "F.Mask")
      (net 7 "Net-(U5-BST)") (pinfunction "BST") (pintype "output"))
  )

  (footprint "data-center-rdimm-ddr4-tester-footprints:R_0402_1005Metric" (layer "F.Cu")
    (at 141.421328 89.610008 180)
    (descr "Resistor SMD 0402")
    (tags "resistor SMD 0402")
    (property "Author" "Antmicro")
    (property "Current" "1A")
    (property "License" "Apache-2.0")
    (property "MPN" "ERJ2GE0R00X")
    (property "Manufacturer" "Panasonic")
    (property "Sheetfile" "supply.kicad_sch")
    (property "Sheetname" "Supply")
    (property "Tolerance" "")
    (property "Val" "0R")
    (property "ki_description" "0R resistor in 0402 package with unspecified tolerance")
    (attr smd)
    (fp_text reference "R38" (at -0.738672 -1.529992 180) (layer "F.SilkS")
        (effects (font (size 0.7 0.7) (thickness 0.15)) (justify left bottom))
    )
    (fp_text value "R_0R_0402" (at 0 1.4 180) (layer "F.Fab") hide
        (effects (font (size 0.7 0.7) (thickness 0.15)) (justify left bottom))
    )
    (fp_text user "License: Apache-2.0" (at -0.95 5.169 180) (layer "F.Fab") hide
        (effects (font (size 0.7 0.7) (thickness 0.15)) (justify left bottom))
    )
    (fp_text user "${REFERENCE}" (at -0.95 3.168 180) (layer "F.Fab") hide
        (effects (font (size 0.7 0.7) (thickness 0.15)) (justify left bottom))
    )
    (fp_text user "Author: Antmicro" (at -0.95 4.169 180) (layer "F.Fab") hide
        (effects (font (size 0.7 0.7) (thickness 0.15)) (justify left bottom))
    )
    (fp_rect (start -0.93 -0.47) (end 0.93 0.47)
      (stroke (width 0.05) (type solid)) (fill none) (layer "F.CrtYd"))
    (fp_rect (start -0.5 -0.25) (end 0.5 0.25)
      (stroke (width 0.15) (type solid)) (fill none) (layer "F.Fab"))
    (pad "1" smd roundrect (at -0.485 0 180) (size 0.59 0.64) (layers "F.Cu" "F.Paste" "F.Mask") (roundrect_rratio 0.25)
      (net 151 "/Supply/VCC_INT_EN") (pintype "passive"))
    (pad "2" smd roundrect (at 0.485 0 180) (size 0.59 0.64) (layers "F.Cu" "F.Paste" "F.Mask") (roundrect_rratio 0.25)
      (net 603 "Net-(U4-EN)") (pintype "passive"))
  )

  (footprint "data-center-rdimm-ddr4-tester-footprints:AP62301WU-7-TSOT23-6" (layer "F.Cu")
    (at 131.986328 92.710008 -90)
    (property "Author" "Antmicro")
    (property "License" "Apache-2.0")
    (property "MPN" "AP62301WU-7")
    (property "Manufacturer" "Diodes Incorporated")
    (property "Sheetfile" "supply.kicad_sch")
    (property "Sheetname" "Supply")
    (attr smd)
    (fp_text reference "U12" (at -1.440008 4.586328) (layer "F.SilkS")
        (effects (font (size 0.7 0.7) (thickness 0.15)) (justify left bottom))
    )
    (fp_text value "AP62301WU-7" (at -0.005 2.6 -90) (layer "F.Fab") hide
        (effects (font (size 0.7 0.7) (thickness 0.15)) (justify left bottom))
    )
    (fp_text user "License: Apache-2.0" (at -1.893 4.967 -90) (layer "F.Fab") hide
        (effects (font (size 0.7 0.7) (thickness 0.15)) (justify left bottom))
    )
    (fp_text user "${REFERENCE}" (at -1.893 6.168 -90) (layer "F.Fab") hide
        (effects (font (size 0.7 0.7) (thickness 0.15)) (justify left bottom))
    )
    (fp_text user "Author: Antmicro" (at -1.893 7.368 -90) (layer "F.Fab") hide
        (effects (font (size 0.7 0.7) (thickness 0.15)) (justify left bottom))
    )
    (fp_line (start -1.4805 0.725) (end -1.4795 -0.725)
      (stroke (width 0.15) (type solid)) (layer "F.SilkS"))
    (fp_line (start -1.4805 0.725) (end -1.3905 0.725)
      (stroke (width 0.15) (type solid)) (layer "F.SilkS"))
    (fp_line (start -1.4795 -0.725) (end -1.3905 -0.725)
      (stroke (width 0.15) (type solid)) (layer "F.SilkS"))
    (fp_line (start 1.479 0.73) (end 1.38 0.73)
      (stroke (width 0.15) (type solid)) (layer "F.SilkS"))
    (fp_line (start 1.48 -0.72) (end 1.38 -0.72)
      (stroke (width 0.15) (type solid)) (layer "F.SilkS"))
    (fp_line (start 1.48 -0.72) (end 1.479 0.73)
      (stroke (width 0.15) (type solid)) (layer "F.SilkS"))
    (fp_circle (center -1.499 1.236) (end -1.45 1.236)
      (stroke (width 0.15) (type solid)) (fill solid) (layer "F.SilkS"))
    (fp_rect (start -1.65 -1.61) (end 1.65 1.61)
      (stroke (width 0.05) (type solid)) (fill none) (layer "F.CrtYd"))
    (fp_line (start -1.527 -0.833) (end 1.523 -0.833)
      (stroke (width 0.15) (type solid)) (layer "F.Fab"))
    (fp_line (start -1.527 0.491) (end -1.527 -0.833)
      (stroke (width 0.15) (type solid)) (layer "F.Fab"))
    (fp_line (start -1.527 0.491) (end -1.102 0.916)
      (stroke (width 0.15) (type solid)) (layer "F.Fab"))
    (fp_line (start -1.102 0.916) (end 1.523 0.916)
      (stroke (width 0.15) (type solid)) (layer "F.Fab"))
    (fp_line (start 1.523 -0.833) (end 1.523 0.916)
      (stroke (width 0.15) (type solid)) (layer "F.Fab"))
    (pad "1" smd rect (at -0.952 1.18 270) (size 0.7 0.8) (layers "F.Cu" "F.Paste" "F.Mask")
      (net 9 "GND") (pinfunction "GND") (pintype "power_in"))
    (pad "2" smd rect (at -0.001 1.18 270) (size 0.7 0.8) (layers "F.Cu" "F.Paste" "F.Mask")
      (net 52 "Net-(U12-SW)") (pinfunction "SW") (pintype "power_out"))
    (pad "3" smd rect (at 0.947 1.18 270) (size 0.7 0.8) (layers "F.Cu" "F.Paste" "F.Mask")
      (net 307 "5V0_SYS") (pinfunction "VIN") (pintype "power_in"))
    (pad "4" smd rect (at 0.947 -1.18 270) (size 0.7 0.8) (layers "F.Cu" "F.Paste" "F.Mask")
      (net 653 "Net-(U12-FB)") (pinfunction "FB") (pintype "input"))
    (pad "5" smd rect (at -0.001 -1.18 270) (size 0.7 0.8) (layers "F.Cu" "F.Paste" "F.Mask")
      (net 643 "Net-(U12-EN)") (pinfunction "EN") (pintype "input"))
    (pad "6" smd rect (at -0.952 -1.18 270) (size 0.7 0.8) (layers "F.Cu" "F.Paste" "F.Mask")
      (net 51 "Net-(U12-BST)") (pinfunction "BST") (pintype "output"))
  )

  (footprint "data-center-rdimm-ddr4-tester-footprints:AP62301WU-7-TSOT23-6" (layer "F.Cu")
    (at 121.936328 106.240008)
    (property "Author" "Antmicro")
    (property "License" "Apache-2.0")
    (property "MPN" "AP62301WU-7")
    (property "Manufacturer" "Diodes Incorporated")
    (property "Sheetfile" "supply.kicad_sch")
    (property "Sheetname" "Supply")
    (attr smd)
    (fp_text reference "U9" (at -1.996328 -1.750008) (layer "F.SilkS")
        (effects (font (size 0.7 0.7) (thickness 0.15)) (justify left bottom))
    )
    (fp_text value "AP62301WU-7" (at -0.005 2.6) (layer "F.Fab") hide
        (effects (font (size 0.7 0.7) (thickness 0.15)) (justify left bottom))
    )
    (fp_text user "Author: Antmicro" (at -1.893 7.368) (layer "F.Fab") hide
        (effects (font (size 0.7 0.7) (thickness 0.15)) (justify left bottom))
    )
    (fp_text user "License: Apache-2.0" (at -1.893 4.967) (layer "F.Fab") hide
        (effects (font (size 0.7 0.7) (thickness 0.15)) (justify left bottom))
    )
    (fp_text user "${REFERENCE}" (at -1.893 6.168) (layer "F.Fab") hide
        (effects (font (size 0.7 0.7) (thickness 0.15)) (justify left bottom))
    )
    (fp_line (start -1.4805 0.725) (end -1.4795 -0.725)
      (stroke (width 0.15) (type solid)) (layer "F.SilkS"))
    (fp_line (start -1.4805 0.725) (end -1.3905 0.725)
      (stroke (width 0.15) (type solid)) (layer "F.SilkS"))
    (fp_line (start -1.4795 -0.725) (end -1.3905 -0.725)
      (stroke (width 0.15) (type solid)) (layer "F.SilkS"))
    (fp_line (start 1.479 0.73) (end 1.38 0.73)
      (stroke (width 0.15) (type solid)) (layer "F.SilkS"))
    (fp_line (start 1.48 -0.72) (end 1.38 -0.72)
      (stroke (width 0.15) (type solid)) (layer "F.SilkS"))
    (fp_line (start 1.48 -0.72) (end 1.479 0.73)
      (stroke (width 0.15) (type solid)) (layer "F.SilkS"))
    (fp_circle (center -1.499 1.236) (end -1.45 1.236)
      (stroke (width 0.15) (type solid)) (fill solid) (layer "F.SilkS"))
    (fp_rect (start -1.65 -1.61) (end 1.65 1.61)
      (stroke (width 0.05) (type solid)) (fill none) (layer "F.CrtYd"))
    (fp_line (start -1.527 -0.833) (end 1.523 -0.833)
      (stroke (width 0.15) (type solid)) (layer "F.Fab"))
    (fp_line (start -1.527 0.491) (end -1.527 -0.833)
      (stroke (width 0.15) (type solid)) (layer "F.Fab"))
    (fp_line (start -1.527 0.491) (end -1.102 0.916)
      (stroke (width 0.15) (type solid)) (layer "F.Fab"))
    (fp_line (start -1.102 0.916) (end 1.523 0.916)
      (stroke (width 0.15) (type solid)) (layer "F.Fab"))
    (fp_line (start 1.523 -0.833) (end 1.523 0.916)
      (stroke (width 0.15) (type solid)) (layer "F.Fab"))
    (pad "1" smd rect (at -0.952 1.18) (size 0.7 0.8) (layers "F.Cu" "F.Paste" "F.Mask")
      (net 9 "GND") (pinfunction "GND") (pintype "power_in"))
    (pad "2" smd rect (at -0.001 1.18) (size 0.7 0.8) (layers "F.Cu" "F.Paste" "F.Mask")
      (net 50 "Net-(U9-SW)") (pinfunction "SW") (pintype "power_out"))
    (pad "3" smd rect (at 0.947 1.18) (size 0.7 0.8) (layers "F.Cu" "F.Paste" "F.Mask")
      (net 307 "5V0_SYS") (pinfunction "VIN") (pintype "power_in"))
    (pad "4" smd rect (at 0.947 -1.18) (size 0.7 0.8) (layers "F.Cu" "F.Paste" "F.Mask")
      (net 644 "Net-(U9-FB)") (pinfunction "FB") (pintype "input"))
    (pad "5" smd rect (at -0.001 -1.18) (size 0.7 0.8) (layers "F.Cu" "F.Paste" "F.Mask")
      (net 642 "Net-(U9-EN)") (pinfunction "EN") (pintype "input"))
    (pad "6" smd rect (at -0.952 -1.18) (size 0.7 0.8) (layers "F.Cu" "F.Paste" "F.Mask")
      (net 49 "Net-(U9-BST)") (pinfunction "BST") (pintype "output"))
  )

  (footprint "data-center-rdimm-ddr4-tester-footprints:R_0402_1005Metric" (layer "F.Cu")
    (at 125.336328 105.400008 90)
    (descr "Resistor SMD 0402")
    (tags "resistor SMD 0402")
    (property "Author" "Antmicro")
    (property "License" "Apache-2.0")
    (property "MPN" "CR0402-FX-3162GLF")
    (property "Manufacturer" "Bourns")
    (property "Sheetfile" "supply.kicad_sch")
    (property "Sheetname" "Supply")
    (property "Tolerance" "1%")
    (property "Val" "31k6")
    (property "ki_description" "31k6 resistor in 0402 package with 1% tolerance")
    (attr smd)
    (fp_text reference "R49" (at -0.549992 2.203672 90) (layer "F.SilkS")
        (effects (font (size 0.7 0.7) (thickness 0.15)) (justify left bottom))
    )
    (fp_text value "R_31k6_0402" (at 0 1.4 90) (layer "F.Fab") hide
        (effects (font (size 0.7 0.7) (thickness 0.15)) (justify left bottom))
    )
    (fp_text user "License: Apache-2.0" (at -0.95 5.169 90) (layer "F.Fab") hide
        (effects (font (size 0.7 0.7) (thickness 0.15)) (justify left bottom))
    )
    (fp_text user "${REFERENCE}" (at -0.95 3.168 90) (layer "F.Fab") hide
        (effects (font (size 0.7 0.7) (thickness 0.15)) (justify left bottom))
    )
    (fp_text user "Author: Antmicro" (at -0.95 4.169 90) (layer "F.Fab") hide
        (effects (font (size 0.7 0.7) (thickness 0.15)) (justify left bottom))
    )
    (fp_rect (start -0.93 -0.47) (end 0.93 0.47)
      (stroke (width 0.05) (type solid)) (fill none) (layer "F.CrtYd"))
    (fp_rect (start -0.5 -0.25) (end 0.5 0.25)
      (stroke (width 0.15) (type solid)) (fill none) (layer "F.Fab"))
    (pad "1" smd roundrect (at -0.485 0 90) (size 0.59 0.64) (layers "F.Cu" "F.Paste" "F.Mask") (roundrect_rratio 0.25)
      (net 304 "VCC3V3") (pintype "passive"))
    (pad "2" smd roundrect (at 0.485 0 90) (size 0.59 0.64) (layers "F.Cu" "F.Paste" "F.Mask") (roundrect_rratio 0.25)
      (net 644 "Net-(U9-FB)") (pintype "passive"))
  )

  (footprint "data-center-rdimm-ddr4-tester-footprints:C_0402_1005Metric" (layer "F.Cu")
    (at 114.98 106.74 90)
    (descr "Capacitor SMD 0402")
    (tags "capacitor SMD 0402")
    (property "Author" "Antmicro")
    (property "Dielectric" "")
    (property "License" "Apache-2.0")
    (property "MPN" "04024W226MAT2A")
    (property "Manufacturer" "AVX")
    (property "Sheetfile" "supply.kicad_sch")
    (property "Sheetname" "Supply")
    (property "Val" "22u")
    (property "Voltage" "")
    (property "ki_description" " ")
    (attr smd)
    (fp_text reference "C216" (at -3.589992 0.353672 90) (layer "F.SilkS")
        (effects (font (size 0.7 0.7) (thickness 0.15)) (justify left bottom))
    )
    (fp_text value "C_22u_0402" (at 0 1.4 90) (layer "F.Fab") hide
        (effects (font (size 0.7 0.7) (thickness 0.15)) (justify left bottom))
    )
    (fp_text user "Author: Antmicro" (at -0.932 4.17 90) (layer "F.Fab") hide
        (effects (font (size 0.7 0.7) (thickness 0.15)) (justify left bottom))
    )
    (fp_text user "${REFERENCE}" (at -0.932 3.168 90) (layer "F.Fab") hide
        (effects (font (size 0.7 0.7) (thickness 0.15)) (justify left bottom))
    )
    (fp_text user "License: Apache-2.0" (at -0.932 5.17 90) (layer "F.Fab") hide
        (effects (font (size 0.7 0.7) (thickness 0.15)) (justify left bottom))
    )
    (fp_rect (start -0.94 -0.47) (end 0.94 0.47)
      (stroke (width 0.05) (type solid)) (fill none) (layer "F.CrtYd"))
    (fp_rect (start -0.499 -0.249) (end 0.499 0.249)
      (stroke (width 0.15) (type solid)) (fill none) (layer "F.Fab"))
    (pad "1" smd roundrect (at -0.484 0 90) (size 0.59 0.64) (layers "F.Cu" "F.Paste" "F.Mask") (roundrect_rratio 0.25)
      (net 304 "VCC3V3") (pintype "passive"))
    (pad "2" smd roundrect (at 0.484 0 90) (size 0.59 0.64) (layers "F.Cu" "F.Paste" "F.Mask") (roundrect_rratio 0.25)
      (net 9 "GND") (pintype "passive"))
  )

  (footprint "data-center-rdimm-ddr4-tester-footprints:C_0603_1608Metric" (layer "F.Cu")
    (at 123.916328 102.890008 90)
    (descr "Capacitor SMD 0603")
    (tags "capacitor 0603")
    (property "Author" "Antmicro")
    (property "Dielectric" "")
    (property "License" "Apache-2.0")
    (property "MPN" "GRM188R60J476ME15D")
    (property "Manufacturer" "Murata")
    (property "Sheetfile" "supply.kicad_sch")
    (property "Sheetname" "Supply")
    (property "Val" "47u")
    (property "Voltage" "")
    (property "ki_description" " ")
    (attr smd)
    (fp_text reference "C183" (at -1.269992 4.333672 90) (layer "F.SilkS")
        (effects (font (size 0.7 0.7) (thickness 0.15)) (justify left bottom))
    )
    (fp_text value "C_47u_0603" (at 0 1.6 90) (layer "F.Fab") hide
        (effects (font (size 0.7 0.7) (thickness 0.15)) (justify left bottom))
    )
    (fp_text user "Author: Antmicro" (at -1.682 4.894 90) (layer "F.Fab") hide
        (effects (font (size 0.7 0.7) (thickness 0.15)) (justify left bottom))
    )
    (fp_text user "${REFERENCE}" (at -1.682 3.895 90) (layer "F.Fab") hide
        (effects (font (size 0.7 0.7) (thickness 0.15)) (justify left bottom))
    )
    (fp_text user "License: Apache-2.0" (at -1.682 5.895 90) (layer "F.Fab") hide
        (effects (font (size 0.7 0.7) (thickness 0.15)) (justify left bottom))
    )
    (fp_line (start -0.3 -0.3) (end 0.3 -0.3)
      (stroke (width 0.15) (type solid)) (layer "F.SilkS"))
    (fp_line (start -0.3 0.3) (end 0.3 0.3)
      (stroke (width 0.15) (type solid)) (layer "F.SilkS"))
    (fp_rect (start -1.24 -0.7) (end 1.24 0.7)
      (stroke (width 0.05) (type solid)) (fill none) (layer "F.CrtYd"))
    (fp_rect (start -0.8 -0.4) (end 0.8 0.4)
      (stroke (width 0.15) (type solid)) (fill none) (layer "F.Fab"))
    (pad "1" smd roundrect (at -0.7 0 90) (size 0.6 0.8) (layers "F.Cu" "F.Paste" "F.Mask") (roundrect_rratio 0.2)
      (net 104 "VCC5V0") (pintype "passive"))
    (pad "2" smd roundrect (at 0.7 0 90) (size 0.6 0.8) (layers "F.Cu" "F.Paste" "F.Mask") (roundrect_rratio 0.2)
      (net 9 "GND") (pintype "passive"))
  )

  (footprint "data-center-rdimm-ddr4-tester-footprints:C_0603_1608Metric" (layer "F.Cu")
    (at 125.415171 102.893829 90)
    (descr "Capacitor SMD 0603")
    (tags "capacitor 0603")
    (property "Author" "Antmicro")
    (property "Dielectric" "")
    (property "License" "Apache-2.0")
    (property "MPN" "GRM188R60J476ME15D")
    (property "Manufacturer" "Murata")
    (property "Sheetfile" "supply.kicad_sch")
    (property "Sheetname" "Supply")
    (property "Val" "47u")
    (property "Voltage" "")
    (property "ki_description" " ")
    (attr smd)
    (fp_text reference "C180" (at -1.276171 3.754829 90) (layer "F.SilkS")
        (effects (font (size 0.7 0.7) (thickness 0.15)) (justify left bottom))
    )
    (fp_text value "C_47u_0603" (at 0 1.6 90) (layer "F.Fab") hide
        (effects (font (size 0.7 0.7) (thickness 0.15)) (justify left bottom))
    )
    (fp_text user "License: Apache-2.0" (at -1.682 5.895 90) (layer "F.Fab") hide
        (effects (font (size 0.7 0.7) (thickness 0.15)) (justify left bottom))
    )
    (fp_text user "Author: Antmicro" (at -1.682 4.894 90) (layer "F.Fab") hide
        (effects (font (size 0.7 0.7) (thickness 0.15)) (justify left bottom))
    )
    (fp_text user "${REFERENCE}" (at -1.682 3.895 90) (layer "F.Fab") hide
        (effects (font (size 0.7 0.7) (thickness 0.15)) (justify left bottom))
    )
    (fp_line (start -0.3 -0.3) (end 0.3 -0.3)
      (stroke (width 0.15) (type solid)) (layer "F.SilkS"))
    (fp_line (start -0.3 0.3) (end 0.3 0.3)
      (stroke (width 0.15) (type solid)) (layer "F.SilkS"))
    (fp_rect (start -1.24 -0.7) (end 1.24 0.7)
      (stroke (width 0.05) (type solid)) (fill none) (layer "F.CrtYd"))
    (fp_rect (start -0.8 -0.4) (end 0.8 0.4)
      (stroke (width 0.15) (type solid)) (fill none) (layer "F.Fab"))
    (pad "1" smd roundrect (at -0.7 0 90) (size 0.6 0.8) (layers "F.Cu" "F.Paste" "F.Mask") (roundrect_rratio 0.2)
      (net 104 "VCC5V0") (pintype "passive"))
    (pad "2" smd roundrect (at 0.7 0 90) (size 0.6 0.8) (layers "F.Cu" "F.Paste" "F.Mask") (roundrect_rratio 0.2)
      (net 9 "GND") (pintype "passive"))
  )

  (footprint "data-center-rdimm-ddr4-tester-footprints:C_0603_1608Metric" (layer "F.Cu")
    (at 126.915171 102.893829 90)
    (descr "Capacitor SMD 0603")
    (tags "capacitor 0603")
    (property "Author" "Antmicro")
    (property "Dielectric" "")
    (property "License" "Apache-2.0")
    (property "MPN" "GRM188R60J476ME15D")
    (property "Manufacturer" "Murata")
    (property "Sheetfile" "supply.kicad_sch")
    (property "Sheetname" "Supply")
    (property "Val" "47u")
    (property "Voltage" "")
    (property "ki_description" " ")
    (attr smd)
    (fp_text reference "C182" (at -1.286171 3.184829 90) (layer "F.SilkS")
        (effects (font (size 0.7 0.7) (thickness 0.15)) (justify left bottom))
    )
    (fp_text value "C_47u_0603" (at 0 1.6 90) (layer "F.Fab") hide
        (effects (font (size 0.7 0.7) (thickness 0.15)) (justify left bottom))
    )
    (fp_text user "License: Apache-2.0" (at -1.682 5.895 90) (layer "F.Fab") hide
        (effects (font (size 0.7 0.7) (thickness 0.15)) (justify left bottom))
    )
    (fp_text user "${REFERENCE}" (at -1.682 3.895 90) (layer "F.Fab") hide
        (effects (font (size 0.7 0.7) (thickness 0.15)) (justify left bottom))
    )
    (fp_text user "Author: Antmicro" (at -1.682 4.894 90) (layer "F.Fab") hide
        (effects (font (size 0.7 0.7) (thickness 0.15)) (justify left bottom))
    )
    (fp_line (start -0.3 -0.3) (end 0.3 -0.3)
      (stroke (width 0.15) (type solid)) (layer "F.SilkS"))
    (fp_line (start -0.3 0.3) (end 0.3 0.3)
      (stroke (width 0.15) (type solid)) (layer "F.SilkS"))
    (fp_rect (start -1.24 -0.7) (end 1.24 0.7)
      (stroke (width 0.05) (type solid)) (fill none) (layer "F.CrtYd"))
    (fp_rect (start -0.8 -0.4) (end 0.8 0.4)
      (stroke (width 0.15) (type solid)) (fill none) (layer "F.Fab"))
    (pad "1" smd roundrect (at -0.7 0 90) (size 0.6 0.8) (layers "F.Cu" "F.Paste" "F.Mask") (roundrect_rratio 0.2)
      (net 104 "VCC5V0") (pintype "passive"))
    (pad "2" smd roundrect (at 0.7 0 90) (size 0.6 0.8) (layers "F.Cu" "F.Paste" "F.Mask") (roundrect_rratio 0.2)
      (net 9 "GND") (pintype "passive"))
  )

  (footprint "data-center-rdimm-ddr4-tester-footprints:R_0402_1005Metric" (layer "F.Cu")
    (at 124.326328 105.405008 -90)
    (descr "Resistor SMD 0402")
    (tags "resistor SMD 0402")
    (property "Author" "Antmicro")
    (property "License" "Apache-2.0")
    (property "MPN" "CR0402-FX-1002GLF")
    (property "Manufacturer" "Bourns")
    (property "Sheetfile" "supply.kicad_sch")
    (property "Sheetname" "Supply")
    (property "Tolerance" "1%")
    (property "Val" "10k")
    (property "ki_description" "10k resistor in 0402 package with 1% tolerance")
    (attr smd)
    (fp_text reference "R82" (at 0.534992 -2.263672 -90) (layer "F.SilkS")
        (effects (font (size 0.7 0.7) (thickness 0.15)) (justify left bottom))
    )
    (fp_text value "R_10k_0402" (at 0 1.4 -90) (layer "F.Fab") hide
        (effects (font (size 0.7 0.7) (thickness 0.15)) (justify left bottom))
    )
    (fp_text user "License: Apache-2.0" (at -0.95 5.169 -90) (layer "F.Fab") hide
        (effects (font (size 0.7 0.7) (thickness 0.15)) (justify left bottom))
    )
    (fp_text user "${REFERENCE}" (at -0.95 3.168 -90) (layer "F.Fab") hide
        (effects (font (size 0.7 0.7) (thickness 0.15)) (justify left bottom))
    )
    (fp_text user "Author: Antmicro" (at -0.95 4.169 -90) (layer "F.Fab") hide
        (effects (font (size 0.7 0.7) (thickness 0.15)) (justify left bottom))
    )
    (fp_rect (start -0.93 -0.47) (end 0.93 0.47)
      (stroke (width 0.05) (type solid)) (fill none) (layer "F.CrtYd"))
    (fp_rect (start -0.5 -0.25) (end 0.5 0.25)
      (stroke (width 0.15) (type solid)) (fill none) (layer "F.Fab"))
    (pad "1" smd roundrect (at -0.485 0 270) (size 0.59 0.64) (layers "F.Cu" "F.Paste" "F.Mask") (roundrect_rratio 0.25)
      (net 644 "Net-(U9-FB)") (pintype "passive"))
    (pad "2" smd roundrect (at 0.485 0 270) (size 0.59 0.64) (layers "F.Cu" "F.Paste" "F.Mask") (roundrect_rratio 0.25)
      (net 9 "GND") (pintype "passive"))
  )

  (footprint "data-center-rdimm-ddr4-tester-footprints:C_0402_1005Metric" (layer "F.Cu")
    (at 114.166328 110.620008 180)
    (descr "Capacitor SMD 0402")
    (tags "capacitor SMD 0402")
    (property "Author" "Antmicro")
    (property "Dielectric" "")
    (property "License" "Apache-2.0")
    (property "MPN" "C1005X6S1A105K050BC")
    (property "Manufacturer" "TDK")
    (property "Sheetfile" "supply.kicad_sch")
    (property "Sheetname" "Supply")
    (property "Val" "1u")
    (property "Voltage" "")
    (property "ki_description" " ")
    (attr smd)
    (fp_text reference "C220" (at -2.133672 -1.879992 180) (layer "F.SilkS")
        (effects (font (size 0.7 0.7) (thickness 0.15)) (justify left bottom))
    )
    (fp_text value "C_1u_0402" (at 0 1.4 180) (layer "F.Fab") hide
        (effects (font (size 0.7 0.7) (thickness 0.15)) (justify left bottom))
    )
    (fp_text user "License: Apache-2.0" (at -0.932 5.17 180) (layer "F.Fab") hide
        (effects (font (size 0.7 0.7) (thickness 0.15)) (justify left bottom))
    )
    (fp_text user "Author: Antmicro" (at -0.932 4.17 180) (layer "F.Fab") hide
        (effects (font (size 0.7 0.7) (thickness 0.15)) (justify left bottom))
    )
    (fp_text user "${REFERENCE}" (at -0.932 3.168 180) (layer "F.Fab") hide
        (effects (font (size 0.7 0.7) (thickness 0.15)) (justify left bottom))
    )
    (fp_rect (start -0.94 -0.47) (end 0.94 0.47)
      (stroke (width 0.05) (type solid)) (fill none) (layer "F.CrtYd"))
    (fp_rect (start -0.499 -0.249) (end 0.499 0.249)
      (stroke (width 0.15) (type solid)) (fill none) (layer "F.Fab"))
    (pad "1" smd roundrect (at -0.484 0 180) (size 0.59 0.64) (layers "F.Cu" "F.Paste" "F.Mask") (roundrect_rratio 0.25)
      (net 304 "VCC3V3") (pintype "passive"))
    (pad "2" smd roundrect (at 0.484 0 180) (size 0.59 0.64) (layers "F.Cu" "F.Paste" "F.Mask") (roundrect_rratio 0.25)
      (net 9 "GND") (pintype "passive"))
  )

  (footprint "data-center-rdimm-ddr4-tester-footprints:C_0402_1005Metric" (layer "F.Cu")
    (at 142.036328 86.410008)
    (descr "Capacitor SMD 0402")
    (tags "capacitor SMD 0402")
    (property "Author" "Antmicro")
    (property "Dielectric" "")
    (property "License" "Apache-2.0")
    (property "MPN" "C1005X6S1A105K050BC")
    (property "Manufacturer" "TDK")
    (property "Sheetfile" "supply.kicad_sch")
    (property "Sheetname" "Supply")
    (property "Val" "1u")
    (property "Voltage" "")
    (property "ki_description" " ")
    (attr smd)
    (fp_text reference "C98" (at 0.773672 1.109992) (layer "F.SilkS")
        (effects (font (size 0.7 0.7) (thickness 0.15)) (justify left bottom))
    )
    (fp_text value "C_1u_0402" (at 0 1.4) (layer "F.Fab") hide
        (effects (font (size 0.7 0.7) (thickness 0.15)) (justify left bottom))
    )
    (fp_text user "Author: Antmicro" (at -0.932 4.17) (layer "F.Fab") hide
        (effects (font (size 0.7 0.7) (thickness 0.15)) (justify left bottom))
    )
    (fp_text user "License: Apache-2.0" (at -0.932 5.17) (layer "F.Fab") hide
        (effects (font (size 0.7 0.7) (thickness 0.15)) (justify left bottom))
    )
    (fp_text user "${REFERENCE}" (at -0.932 3.168) (layer "F.Fab") hide
        (effects (font (size 0.7 0.7) (thickness 0.15)) (justify left bottom))
    )
    (fp_rect (start -0.94 -0.47) (end 0.94 0.47)
      (stroke (width 0.05) (type solid)) (fill none) (layer "F.CrtYd"))
    (fp_rect (start -0.499 -0.249) (end 0.499 0.249)
      (stroke (width 0.15) (type solid)) (fill none) (layer "F.Fab"))
    (pad "1" smd roundrect (at -0.484 0) (size 0.59 0.64) (layers "F.Cu" "F.Paste" "F.Mask") (roundrect_rratio 0.25)
      (net 300 "VCC1V0") (pintype "passive"))
    (pad "2" smd roundrect (at 0.484 0) (size 0.59 0.64) (layers "F.Cu" "F.Paste" "F.Mask") (roundrect_rratio 0.25)
      (net 9 "GND") (pintype "passive"))
  )

  (footprint "data-center-rdimm-ddr4-tester-footprints:C_0402_1005Metric" (layer "F.Cu")
    (at 135.786328 89.585008 90)
    (descr "Capacitor SMD 0402")
    (tags "capacitor SMD 0402")
    (property "Author" "Antmicro")
    (property "Dielectric" "")
    (property "License" "Apache-2.0")
    (property "MPN" "CC0402MRX5R5BB106")
    (property "Manufacturer" "Yaego")
    (property "Sheetfile" "supply.kicad_sch")
    (property "Sheetname" "Supply")
    (property "Val" "10u")
    (property "Voltage" "")
    (property "ki_description" " ")
    (attr smd)
    (fp_text reference "C45" (at 0.825008 0.173672 90) (layer "F.SilkS")
        (effects (font (size 0.7 0.7) (thickness 0.15)) (justify left bottom))
    )
    (fp_text value "C_10u_0402" (at 0 1.4 90) (layer "F.Fab") hide
        (effects (font (size 0.7 0.7) (thickness 0.15)) (justify left bottom))
    )
    (fp_text user "License: Apache-2.0" (at -0.932 5.17 90) (layer "F.Fab") hide
        (effects (font (size 0.7 0.7) (thickness 0.15)) (justify left bottom))
    )
    (fp_text user "${REFERENCE}" (at -0.932 3.168 90) (layer "F.Fab") hide
        (effects (font (size 0.7 0.7) (thickness 0.15)) (justify left bottom))
    )
    (fp_text user "Author: Antmicro" (at -0.932 4.17 90) (layer "F.Fab") hide
        (effects (font (size 0.7 0.7) (thickness 0.15)) (justify left bottom))
    )
    (fp_rect (start -0.94 -0.47) (end 0.94 0.47)
      (stroke (width 0.05) (type solid)) (fill none) (layer "F.CrtYd"))
    (fp_rect (start -0.499 -0.249) (end 0.499 0.249)
      (stroke (width 0.15) (type solid)) (fill none) (layer "F.Fab"))
    (pad "1" smd roundrect (at -0.484 0 90) (size 0.59 0.64) (layers "F.Cu" "F.Paste" "F.Mask") (roundrect_rratio 0.25)
      (net 307 "5V0_SYS") (pintype "passive"))
    (pad "2" smd roundrect (at 0.484 0 90) (size 0.59 0.64) (layers "F.Cu" "F.Paste" "F.Mask") (roundrect_rratio 0.25)
      (net 9 "GND") (pintype "passive"))
  )

  (footprint "data-center-rdimm-ddr4-tester-footprints:C_0402_1005Metric" (layer "F.Cu")
    (at 140.936328 88.125008 90)
    (descr "Capacitor SMD 0402")
    (tags "capacitor SMD 0402")
    (property "Author" "Antmicro")
    (property "Dielectric" "X5R")
    (property "License" "Apache-2.0")
    (property "MPN" "GRM155R61H104KE14D")
    (property "Manufacturer" "Murata")
    (property "Sheetfile" "supply.kicad_sch")
    (property "Sheetname" "Supply")
    (property "Val" "100n")
    (property "Voltage" "50V")
    (property "ki_description" " ")
    (attr smd)
    (fp_text reference "C46" (at -1.094992 1.183672 90) (layer "F.SilkS")
        (effects (font (size 0.7 0.7) (thickness 0.15)) (justify left bottom))
    )
    (fp_text value "C_100n_0402" (at 0 1.4 90) (layer "F.Fab") hide
        (effects (font (size 0.7 0.7) (thickness 0.15)) (justify left bottom))
    )
    (fp_text user "Author: Antmicro" (at -0.932 4.17 90) (layer "F.Fab") hide
        (effects (font (size 0.7 0.7) (thickness 0.15)) (justify left bottom))
    )
    (fp_text user "License: Apache-2.0" (at -0.932 5.17 90) (layer "F.Fab") hide
        (effects (font (size 0.7 0.7) (thickness 0.15)) (justify left bottom))
    )
    (fp_text user "${REFERENCE}" (at -0.932 3.168 90) (layer "F.Fab") hide
        (effects (font (size 0.7 0.7) (thickness 0.15)) (justify left bottom))
    )
    (fp_rect (start -0.94 -0.47) (end 0.94 0.47)
      (stroke (width 0.05) (type solid)) (fill none) (layer "F.CrtYd"))
    (fp_rect (start -0.499 -0.249) (end 0.499 0.249)
      (stroke (width 0.15) (type solid)) (fill none) (layer "F.Fab"))
    (pad "1" smd roundrect (at -0.484 0 90) (size 0.59 0.64) (layers "F.Cu" "F.Paste" "F.Mask") (roundrect_rratio 0.25)
      (net 2 "Net-(U4-BST)") (pintype "passive"))
    (pad "2" smd roundrect (at 0.484 0 90) (size 0.59 0.64) (layers "F.Cu" "F.Paste" "F.Mask") (roundrect_rratio 0.25)
      (net 3 "Net-(U4-SW)") (pintype "passive"))
  )

  (footprint "data-center-rdimm-ddr4-tester-footprints:C_0402_1005Metric" (layer "F.Cu")
    (at 142.036328 85.410008)
    (descr "Capacitor SMD 0402")
    (tags "capacitor SMD 0402")
    (property "Author" "Antmicro")
    (property "Dielectric" "")
    (property "License" "Apache-2.0")
    (property "MPN" "04024W226MAT2A")
    (property "Manufacturer" "AVX")
    (property "Sheetfile" "supply.kicad_sch")
    (property "Sheetname" "Supply")
    (property "Val" "22u")
    (property "Voltage" "")
    (property "ki_description" " ")
    (attr smd)
    (fp_text reference "C97" (at 0.773672 1.109992) (layer "F.SilkS")
        (effects (font (size 0.7 0.7) (thickness 0.15)) (justify left bottom))
    )
    (fp_text value "C_22u_0402" (at 0 1.4) (layer "F.Fab") hide
        (effects (font (size 0.7 0.7) (thickness 0.15)) (justify left bottom))
    )
    (fp_text user "${REFERENCE}" (at -0.932 3.168) (layer "F.Fab") hide
        (effects (font (size 0.7 0.7) (thickness 0.15)) (justify left bottom))
    )
    (fp_text user "License: Apache-2.0" (at -0.932 5.17) (layer "F.Fab") hide
        (effects (font (size 0.7 0.7) (thickness 0.15)) (justify left bottom))
    )
    (fp_text user "Author: Antmicro" (at -0.932 4.17) (layer "F.Fab") hide
        (effects (font (size 0.7 0.7) (thickness 0.15)) (justify left bottom))
    )
    (fp_rect (start -0.94 -0.47) (end 0.94 0.47)
      (stroke (width 0.05) (type solid)) (fill none) (layer "F.CrtYd"))
    (fp_rect (start -0.499 -0.249) (end 0.499 0.249)
      (stroke (width 0.15) (type solid)) (fill none) (layer "F.Fab"))
    (pad "1" smd roundrect (at -0.484 0) (size 0.59 0.64) (layers "F.Cu" "F.Paste" "F.Mask") (roundrect_rratio 0.25)
      (net 300 "VCC1V0") (pintype "passive"))
    (pad "2" smd roundrect (at 0.484 0) (size 0.59 0.64) (layers "F.Cu" "F.Paste" "F.Mask") (roundrect_rratio 0.25)
      (net 9 "GND") (pintype "passive"))
  )

  (footprint "data-center-rdimm-ddr4-tester-footprints:C_0402_1005Metric" (layer "F.Cu")
    (at 155.324328 118.127008)
    (descr "Capacitor SMD 0402")
    (tags "capacitor SMD 0402")
    (property "Author" "Antmicro")
    (property "Dielectric" "")
    (property "License" "Apache-2.0")
    (property "MPN" "CC0402MRX5R5BB106")
    (property "Manufacturer" "Yaego")
    (property "Sheetfile" "supply.kicad_sch")
    (property "Sheetname" "Supply")
    (property "Val" "10u")
    (property "Voltage" "")
    (property "ki_description" " ")
    (attr smd)
    (fp_text reference "C99" (at -1.014328 -0.547008) (layer "F.SilkS")
        (effects (font (size 0.7 0.7) (thickness 0.15)) (justify left bottom))
    )
    (fp_text value "C_10u_0402" (at 0 1.4) (layer "F.Fab") hide
        (effects (font (size 0.7 0.7) (thickness 0.15)) (justify left bottom))
    )
    (fp_text user "License: Apache-2.0" (at -0.932 5.17) (layer "F.Fab") hide
        (effects (font (size 0.7 0.7) (thickness 0.15)) (justify left bottom))
    )
    (fp_text user "${REFERENCE}" (at -0.932 3.168) (layer "F.Fab") hide
        (effects (font (size 0.7 0.7) (thickness 0.15)) (justify left bottom))
    )
    (fp_text user "Author: Antmicro" (at -0.932 4.17) (layer "F.Fab") hide
        (effects (font (size 0.7 0.7) (thickness 0.15)) (justify left bottom))
    )
    (fp_rect (start -0.94 -0.47) (end 0.94 0.47)
      (stroke (width 0.05) (type solid)) (fill none) (layer "F.CrtYd"))
    (fp_rect (start -0.499 -0.249) (end 0.499 0.249)
      (stroke (width 0.15) (type solid)) (fill none) (layer "F.Fab"))
    (pad "1" smd roundrect (at -0.484 0) (size 0.59 0.64) (layers "F.Cu" "F.Paste" "F.Mask") (roundrect_rratio 0.25)
      (net 307 "5V0_SYS") (pintype "passive"))
    (pad "2" smd roundrect (at 0.484 0) (size 0.59 0.64) (layers "F.Cu" "F.Paste" "F.Mask") (roundrect_rratio 0.25)
      (net 9 "GND") (pintype "passive"))
  )

  (footprint "data-center-rdimm-ddr4-tester-footprints:C_0402_1005Metric" (layer "F.Cu")
    (at 151.599328 114.552008 180)
    (descr "Capacitor SMD 0402")
    (tags "capacitor SMD 0402")
    (property "Author" "Antmicro")
    (property "Dielectric" "X5R")
    (property "License" "Apache-2.0")
    (property "MPN" "GRM155R61H104KE14D")
    (property "Manufacturer" "Murata")
    (property "Sheetfile" "supply.kicad_sch")
    (property "Sheetname" "Supply")
    (property "Val" "100n")
    (property "Voltage" "50V")
    (property "ki_description" " ")
    (attr smd)
    (fp_text reference "C149" (at 1.699328 0.412008 180) (layer "F.SilkS")
        (effects (font (size 0.7 0.7) (thickness 0.15)) (justify left bottom))
    )
    (fp_text value "C_100n_0402" (at 0 1.4 180) (layer "F.Fab") hide
        (effects (font (size 0.7 0.7) (thickness 0.15)) (justify left bottom))
    )
    (fp_text user "License: Apache-2.0" (at -0.932 5.17 180) (layer "F.Fab") hide
        (effects (font (size 0.7 0.7) (thickness 0.15)) (justify left bottom))
    )
    (fp_text user "${REFERENCE}" (at -0.932 3.168 180) (layer "F.Fab") hide
        (effects (font (size 0.7 0.7) (thickness 0.15)) (justify left bottom))
    )
    (fp_text user "Author: Antmicro" (at -0.932 4.17 180) (layer "F.Fab") hide
        (effects (font (size 0.7 0.7) (thickness 0.15)) (justify left bottom))
    )
    (fp_rect (start -0.94 -0.47) (end 0.94 0.47)
      (stroke (width 0.05) (type solid)) (fill none) (layer "F.CrtYd"))
    (fp_rect (start -0.499 -0.249) (end 0.499 0.249)
      (stroke (width 0.15) (type solid)) (fill none) (layer "F.Fab"))
    (pad "1" smd roundrect (at -0.484 0 180) (size 0.59 0.64) (layers "F.Cu" "F.Paste" "F.Mask") (roundrect_rratio 0.25)
      (net 7 "Net-(U5-BST)") (pintype "passive"))
    (pad "2" smd roundrect (at 0.484 0 180) (size 0.59 0.64) (layers "F.Cu" "F.Paste" "F.Mask") (roundrect_rratio 0.25)
      (net 8 "Net-(U5-SW)") (pintype "passive"))
  )

  (footprint "data-center-rdimm-ddr4-tester-footprints:C_0402_1005Metric" (layer "F.Cu")
    (at 124.326328 107.320008 -90)
    (descr "Capacitor SMD 0402")
    (tags "capacitor SMD 0402")
    (property "Author" "Antmicro")
    (property "Dielectric" "")
    (property "License" "Apache-2.0")
    (property "MPN" "CC0402MRX5R5BB106")
    (property "Manufacturer" "Yaego")
    (property "Sheetfile" "supply.kicad_sch")
    (property "Sheetname" "Supply")
    (property "Val" "10u")
    (property "Voltage" "")
    (property "ki_description" " ")
    (attr smd)
    (fp_text reference "C150" (at 1.259992 -2.213672 -90) (layer "F.SilkS")
        (effects (font (size 0.7 0.7) (thickness 0.15)) (justify left bottom))
    )
    (fp_text value "C_10u_0402" (at 0 1.4 -90) (layer "F.Fab") hide
        (effects (font (size 0.7 0.7) (thickness 0.15)) (justify left bottom))
    )
    (fp_text user "Author: Antmicro" (at -0.932 4.17 -90) (layer "F.Fab") hide
        (effects (font (size 0.7 0.7) (thickness 0.15)) (justify left bottom))
    )
    (fp_text user "License: Apache-2.0" (at -0.932 5.17 -90) (layer "F.Fab") hide
        (effects (font (size 0.7 0.7) (thickness 0.15)) (justify left bottom))
    )
    (fp_text user "${REFERENCE}" (at -0.932 3.168 -90) (layer "F.Fab") hide
        (effects (font (size 0.7 0.7) (thickness 0.15)) (justify left bottom))
    )
    (fp_rect (start -0.94 -0.47) (end 0.94 0.47)
      (stroke (width 0.05) (type solid)) (fill none) (layer "F.CrtYd"))
    (fp_rect (start -0.499 -0.249) (end 0.499 0.249)
      (stroke (width 0.15) (type solid)) (fill none) (layer "F.Fab"))
    (pad "1" smd roundrect (at -0.484 0 270) (size 0.59 0.64) (layers "F.Cu" "F.Paste" "F.Mask") (roundrect_rratio 0.25)
      (net 307 "5V0_SYS") (pintype "passive"))
    (pad "2" smd roundrect (at 0.484 0 270) (size 0.59 0.64) (layers "F.Cu" "F.Paste" "F.Mask") (roundrect_rratio 0.25)
      (net 9 "GND") (pintype "passive"))
  )

  (footprint "data-center-rdimm-ddr4-tester-footprints:C_0402_1005Metric" (layer "F.Cu")
    (at 130.336328 95.085008 180)
    (descr "Capacitor SMD 0402")
    (tags "capacitor SMD 0402")
    (property "Author" "Antmicro")
    (property "Dielectric" "")
    (property "License" "Apache-2.0")
    (property "MPN" "CC0402MRX5R5BB106")
    (property "Manufacturer" "Yaego")
    (property "Sheetfile" "supply.kicad_sch")
    (property "Sheetname" "Supply")
    (property "Val" "10u")
    (property "Voltage" "")
    (property "ki_description" " ")
    (attr smd)
    (fp_text reference "C151" (at 1.456328 -1.264992 180) (layer "F.SilkS")
        (effects (font (size 0.7 0.7) (thickness 0.15)) (justify left bottom))
    )
    (fp_text value "C_10u_0402" (at 0 1.4 180) (layer "F.Fab") hide
        (effects (font (size 0.7 0.7) (thickness 0.15)) (justify left bottom))
    )
    (fp_text user "${REFERENCE}" (at -0.932 3.168 180) (layer "F.Fab") hide
        (effects (font (size 0.7 0.7) (thickness 0.15)) (justify left bottom))
    )
    (fp_text user "Author: Antmicro" (at -0.932 4.17 180) (layer "F.Fab") hide
        (effects (font (size 0.7 0.7) (thickness 0.15)) (justify left bottom))
    )
    (fp_text user "License: Apache-2.0" (at -0.932 5.17 180) (layer "F.Fab") hide
        (effects (font (size 0.7 0.7) (thickness 0.15)) (justify left bottom))
    )
    (fp_rect (start -0.94 -0.47) (end 0.94 0.47)
      (stroke (width 0.05) (type solid)) (fill none) (layer "F.CrtYd"))
    (fp_rect (start -0.499 -0.249) (end 0.499 0.249)
      (stroke (width 0.15) (type solid)) (fill none) (layer "F.Fab"))
    (pad "1" smd roundrect (at -0.484 0 180) (size 0.59 0.64) (layers "F.Cu" "F.Paste" "F.Mask") (roundrect_rratio 0.25)
      (net 307 "5V0_SYS") (pintype "passive"))
    (pad "2" smd roundrect (at 0.484 0 180) (size 0.59 0.64) (layers "F.Cu" "F.Paste" "F.Mask") (roundrect_rratio 0.25)
      (net 9 "GND") (pintype "passive"))
  )

  (footprint "data-center-rdimm-ddr4-tester-footprints:C_0402_1005Metric" (layer "F.Cu")
    (at 146.474328 121.852008 -90)
    (descr "Capacitor SMD 0402")
    (tags "capacitor SMD 0402")
    (property "Author" "Antmicro")
    (property "Dielectric" "")
    (property "License" "Apache-2.0")
    (property "MPN" "04024W226MAT2A")
    (property "Manufacturer" "AVX")
    (property "Sheetfile" "supply.kicad_sch")
    (property "Sheetname" "Supply")
    (property "Val" "22u")
    (property "Voltage" "")
    (property "ki_description" " ")
    (attr smd)
    (fp_text reference "C152" (at 1.477992 2.539328 -90) (layer "F.SilkS")
        (effects (font (size 0.7 0.7) (thickness 0.15)) (justify left bottom))
    )
    (fp_text value "C_22u_0402" (at 0 1.4 -90) (layer "F.Fab") hide
        (effects (font (size 0.7 0.7) (thickness 0.15)) (justify left bottom))
    )
    (fp_text user "${REFERENCE}" (at -0.932 3.168 -90) (layer "F.Fab") hide
        (effects (font (size 0.7 0.7) (thickness 0.15)) (justify left bottom))
    )
    (fp_text user "Author: Antmicro" (at -0.932 4.17 -90) (layer "F.Fab") hide
        (effects (font (size 0.7 0.7) (thickness 0.15)) (justify left bottom))
    )
    (fp_text user "License: Apache-2.0" (at -0.932 5.17 -90) (layer "F.Fab") hide
        (effects (font (size 0.7 0.7) (thickness 0.15)) (justify left bottom))
    )
    (fp_rect (start -0.94 -0.47) (end 0.94 0.47)
      (stroke (width 0.05) (type solid)) (fill none) (layer "F.CrtYd"))
    (fp_rect (start -0.499 -0.249) (end 0.499 0.249)
      (stroke (width 0.15) (type solid)) (fill none) (layer "F.Fab"))
    (pad "1" smd roundrect (at -0.484 0 270) (size 0.59 0.64) (layers "F.Cu" "F.Paste" "F.Mask") (roundrect_rratio 0.25)
      (net 176 "VCC1V2") (pintype "passive"))
    (pad "2" smd roundrect (at 0.484 0 270) (size 0.59 0.64) (layers "F.Cu" "F.Paste" "F.Mask") (roundrect_rratio 0.25)
      (net 9 "GND") (pintype "passive"))
  )

  (footprint "data-center-rdimm-ddr4-tester-footprints:C_0402_1005Metric" (layer "F.Cu")
    (at 147.484328 121.852008 -90)
    (descr "Capacitor SMD 0402")
    (tags "capacitor SMD 0402")
    (property "Author" "Antmicro")
    (property "Dielectric" "")
    (property "License" "Apache-2.0")
    (property "MPN" "04024W226MAT2A")
    (property "Manufacturer" "AVX")
    (property "Sheetfile" "supply.kicad_sch")
    (property "Sheetname" "Supply")
    (property "Val" "22u")
    (property "Voltage" "")
    (property "ki_description" " ")
    (attr smd)
    (fp_text reference "C155" (at 1.477992 2.539328 -90) (layer "F.SilkS")
        (effects (font (size 0.7 0.7) (thickness 0.15)) (justify left bottom))
    )
    (fp_text value "C_22u_0402" (at 0 1.4 -90) (layer "F.Fab") hide
        (effects (font (size 0.7 0.7) (thickness 0.15)) (justify left bottom))
    )
    (fp_text user "License: Apache-2.0" (at -0.932 5.17 -90) (layer "F.Fab") hide
        (effects (font (size 0.7 0.7) (thickness 0.15)) (justify left bottom))
    )
    (fp_text user "Author: Antmicro" (at -0.932 4.17 -90) (layer "F.Fab") hide
        (effects (font (size 0.7 0.7) (thickness 0.15)) (justify left bottom))
    )
    (fp_text user "${REFERENCE}" (at -0.932 3.168 -90) (layer "F.Fab") hide
        (effects (font (size 0.7 0.7) (thickness 0.15)) (justify left bottom))
    )
    (fp_rect (start -0.94 -0.47) (end 0.94 0.47)
      (stroke (width 0.05) (type solid)) (fill none) (layer "F.CrtYd"))
    (fp_rect (start -0.499 -0.249) (end 0.499 0.249)
      (stroke (width 0.15) (type solid)) (fill none) (layer "F.Fab"))
    (pad "1" smd roundrect (at -0.484 0 270) (size 0.59 0.64) (layers "F.Cu" "F.Paste" "F.Mask") (roundrect_rratio 0.25)
      (net 176 "VCC1V2") (pintype "passive"))
    (pad "2" smd roundrect (at 0.484 0 270) (size 0.59 0.64) (layers "F.Cu" "F.Paste" "F.Mask") (roundrect_rratio 0.25)
      (net 9 "GND") (pintype "passive"))
  )

  (footprint "data-center-rdimm-ddr4-tester-footprints:C_0402_1005Metric" (layer "F.Cu")
    (at 119.566328 104.990008 -90)
    (descr "Capacitor SMD 0402")
    (tags "capacitor SMD 0402")
    (property "Author" "Antmicro")
    (property "Dielectric" "X5R")
    (property "License" "Apache-2.0")
    (property "MPN" "GRM155R61H104KE14D")
    (property "Manufacturer" "Murata")
    (property "Sheetfile" "supply.kicad_sch")
    (property "Sheetname" "Supply")
    (property "Val" "100n")
    (property "Voltage" "50V")
    (property "ki_description" " ")
    (attr smd)
    (fp_text reference "C157" (at 1.219992 0.566328 -90) (layer "F.SilkS")
        (effects (font (size 0.7 0.7) (thickness 0.15)) (justify left bottom))
    )
    (fp_text value "C_100n_0402" (at 0 1.4 -90) (layer "F.Fab") hide
        (effects (font (size 0.7 0.7) (thickness 0.15)) (justify left bottom))
    )
    (fp_text user "Author: Antmicro" (at -0.932 4.17 -90) (layer "F.Fab") hide
        (effects (font (size 0.7 0.7) (thickness 0.15)) (justify left bottom))
    )
    (fp_text user "License: Apache-2.0" (at -0.932 5.17 -90) (layer "F.Fab") hide
        (effects (font (size 0.7 0.7) (thickness 0.15)) (justify left bottom))
    )
    (fp_text user "${REFERENCE}" (at -0.932 3.168 -90) (layer "F.Fab") hide
        (effects (font (size 0.7 0.7) (thickness 0.15)) (justify left bottom))
    )
    (fp_rect (start -0.94 -0.47) (end 0.94 0.47)
      (stroke (width 0.05) (type solid)) (fill none) (layer "F.CrtYd"))
    (fp_rect (start -0.499 -0.249) (end 0.499 0.249)
      (stroke (width 0.15) (type solid)) (fill none) (layer "F.Fab"))
    (pad "1" smd roundrect (at -0.484 0 270) (size 0.59 0.64) (layers "F.Cu" "F.Paste" "F.Mask") (roundrect_rratio 0.25)
      (net 49 "Net-(U9-BST)") (pintype "passive"))
    (pad "2" smd roundrect (at 0.484 0 270) (size 0.59 0.64) (layers "F.Cu" "F.Paste" "F.Mask") (roundrect_rratio 0.25)
      (net 50 "Net-(U9-SW)") (pintype "passive"))
  )

  (footprint "data-center-rdimm-ddr4-tester-footprints:C_0402_1005Metric" (layer "F.Cu")
    (at 134.536328 91.810008 90)
    (descr "Capacitor SMD 0402")
    (tags "capacitor SMD 0402")
    (property "Author" "Antmicro")
    (property "Dielectric" "X5R")
    (property "License" "Apache-2.0")
    (property "MPN" "GRM155R61H104KE14D")
    (property "Manufacturer" "Murata")
    (property "Sheetfile" "supply.kicad_sch")
    (property "Sheetname" "Supply")
    (property "Val" "100n")
    (property "Voltage" "50V")
    (property "ki_description" " ")
    (attr smd)
    (fp_text reference "C158" (at -1.659992 1.153672 90) (layer "F.SilkS")
        (effects (font (size 0.7 0.7) (thickness 0.15)) (justify left bottom))
    )
    (fp_text value "C_100n_0402" (at 0 1.4 90) (layer "F.Fab") hide
        (effects (font (size 0.7 0.7) (thickness 0.15)) (justify left bottom))
    )
    (fp_text user "Author: Antmicro" (at -0.932 4.17 90) (layer "F.Fab") hide
        (effects (font (size 0.7 0.7) (thickness 0.15)) (justify left bottom))
    )
    (fp_text user "${REFERENCE}" (at -0.932 3.168 90) (layer "F.Fab") hide
        (effects (font (size 0.7 0.7) (thickness 0.15)) (justify left bottom))
    )
    (fp_text user "License: Apache-2.0" (at -0.932 5.17 90) (layer "F.Fab") hide
        (effects (font (size 0.7 0.7) (thickness 0.15)) (justify left bottom))
    )
    (fp_rect (start -0.94 -0.47) (end 0.94 0.47)
      (stroke (width 0.05) (type solid)) (fill none) (layer "F.CrtYd"))
    (fp_rect (start -0.499 -0.249) (end 0.499 0.249)
      (stroke (width 0.15) (type solid)) (fill none) (layer "F.Fab"))
    (pad "1" smd roundrect (at -0.484 0 90) (size 0.59 0.64) (layers "F.Cu" "F.Paste" "F.Mask") (roundrect_rratio 0.25)
      (net 51 "Net-(U12-BST)") (pintype "passive"))
    (pad "2" smd roundrect (at 0.484 0 90) (size 0.59 0.64) (layers "F.Cu" "F.Paste" "F.Mask") (roundrect_rratio 0.25)
      (net 52 "Net-(U12-SW)") (pintype "passive"))
  )

  (footprint "data-center-rdimm-ddr4-tester-footprints:C_0402_1005Metric" (layer "F.Cu")
    (at 132.936328 83.610008)
    (descr "Capacitor SMD 0402")
    (tags "capacitor SMD 0402")
    (property "Author" "Antmicro")
    (property "Dielectric" "")
    (property "License" "Apache-2.0")
    (property "MPN" "04024W226MAT2A")
    (property "Manufacturer" "AVX")
    (property "Sheetfile" "supply.kicad_sch")
    (property "Sheetname" "Supply")
    (property "Val" "22u")
    (property "Voltage" "")
    (property "ki_description" " ")
    (attr smd)
    (fp_text reference "C215" (at -1.246328 -2.460008) (layer "F.SilkS")
        (effects (font (size 0.7 0.7) (thickness 0.15)) (justify left bottom))
    )
    (fp_text value "C_22u_0402" (at 0 1.4) (layer "F.Fab") hide
        (effects (font (size 0.7 0.7) (thickness 0.15)) (justify left bottom))
    )
    (fp_text user "License: Apache-2.0" (at -0.932 5.17) (layer "F.Fab") hide
        (effects (font (size 0.7 0.7) (thickness 0.15)) (justify left bottom))
    )
    (fp_text user "Author: Antmicro" (at -0.932 4.17) (layer "F.Fab") hide
        (effects (font (size 0.7 0.7) (thickness 0.15)) (justify left bottom))
    )
    (fp_text user "${REFERENCE}" (at -0.932 3.168) (layer "F.Fab") hide
        (effects (font (size 0.7 0.7) (thickness 0.15)) (justify left bottom))
    )
    (fp_rect (start -0.94 -0.47) (end 0.94 0.47)
      (stroke (width 0.05) (type solid)) (fill none) (layer "F.CrtYd"))
    (fp_rect (start -0.499 -0.249) (end 0.499 0.249)
      (stroke (width 0.15) (type solid)) (fill none) (layer "F.Fab"))
    (pad "1" smd roundrect (at -0.484 0) (size 0.59 0.64) (layers "F.Cu" "F.Paste" "F.Mask") (roundrect_rratio 0.25)
      (net 302 "VCC1V8") (pintype "passive"))
    (pad "2" smd roundrect (at 0.484 0) (size 0.59 0.64) (layers "F.Cu" "F.Paste" "F.Mask") (roundrect_rratio 0.25)
      (net 9 "GND") (pintype "passive"))
  )

  (footprint "data-center-rdimm-ddr4-tester-footprints:C_0402_1005Metric" (layer "F.Cu")
    (at 132.951328 84.610008)
    (descr "Capacitor SMD 0402")
    (tags "capacitor SMD 0402")
    (property "Author" "Antmicro")
    (property "Dielectric" "")
    (property "License" "Apache-2.0")
    (property "MPN" "04024W226MAT2A")
    (property "Manufacturer" "AVX")
    (property "Sheetfile" "supply.kicad_sch")
    (property "Sheetname" "Supply")
    (property "Val" "22u")
    (property "Voltage" "")
    (property "ki_description" " ")
    (attr smd)
    (fp_text reference "C217" (at -1.246328 -2.460008) (layer "F.SilkS")
        (effects (font (size 0.7 0.7) (thickness 0.15)) (justify left bottom))
    )
    (fp_text value "C_22u_0402" (at 0 1.4) (layer "F.Fab") hide
        (effects (font (size 0.7 0.7) (thickness 0.15)) (justify left bottom))
    )
    (fp_text user "License: Apache-2.0" (at -0.932 5.17) (layer "F.Fab") hide
        (effects (font (size 0.7 0.7) (thickness 0.15)) (justify left bottom))
    )
    (fp_text user "${REFERENCE}" (at -0.932 3.168) (layer "F.Fab") hide
        (effects (font (size 0.7 0.7) (thickness 0.15)) (justify left bottom))
    )
    (fp_text user "Author: Antmicro" (at -0.932 4.17) (layer "F.Fab") hide
        (effects (font (size 0.7 0.7) (thickness 0.15)) (justify left bottom))
    )
    (fp_rect (start -0.94 -0.47) (end 0.94 0.47)
      (stroke (width 0.05) (type solid)) (fill none) (layer "F.CrtYd"))
    (fp_rect (start -0.499 -0.249) (end 0.499 0.249)
      (stroke (width 0.15) (type solid)) (fill none) (layer "F.Fab"))
    (pad "1" smd roundrect (at -0.484 0) (size 0.59 0.64) (layers "F.Cu" "F.Paste" "F.Mask") (roundrect_rratio 0.25)
      (net 302 "VCC1V8") (pintype "passive"))
    (pad "2" smd roundrect (at 0.484 0) (size 0.59 0.64) (layers "F.Cu" "F.Paste" "F.Mask") (roundrect_rratio 0.25)
      (net 9 "GND") (pintype "passive"))
  )

  (footprint "data-center-rdimm-ddr4-tester-footprints:C_0402_1005Metric" (layer "F.Cu")
    (at 120.65 108.95 90)
    (descr "Capacitor SMD 0402")
    (tags "capacitor SMD 0402")
    (property "Author" "Antmicro")
    (property "Dielectric" "")
    (property "License" "Apache-2.0")
    (property "MPN" "04024W226MAT2A")
    (property "Manufacturer" "AVX")
    (property "Sheetfile" "supply.kicad_sch")
    (property "Sheetname" "Supply")
    (property "Val" "22u")
    (property "Voltage" "")
    (property "ki_description" " ")
    (attr smd)
    (fp_text reference "C218" (at -3.7 -1.75 180) (layer "F.SilkS")
        (effects (font (size 0.7 0.7) (thickness 0.15)) (justify left bottom))
    )
    (fp_text value "C_22u_0402" (at 0 1.4 90) (layer "F.Fab") hide
        (effects (font (size 0.7 0.7) (thickness 0.15)) (justify left bottom))
    )
    (fp_text user "Author: Antmicro" (at -0.932 4.17 90) (layer "F.Fab") hide
        (effects (font (size 0.7 0.7) (thickness 0.15)) (justify left bottom))
    )
    (fp_text user "${REFERENCE}" (at -0.932 3.168 90) (layer "F.Fab") hide
        (effects (font (size 0.7 0.7) (thickness 0.15)) (justify left bottom))
    )
    (fp_text user "License: Apache-2.0" (at -0.932 5.17 90) (layer "F.Fab") hide
        (effects (font (size 0.7 0.7) (thickness 0.15)) (justify left bottom))
    )
    (fp_rect (start -0.94 -0.47) (end 0.94 0.47)
      (stroke (width 0.05) (type solid)) (fill none) (layer "F.CrtYd"))
    (fp_rect (start -0.499 -0.249) (end 0.499 0.249)
      (stroke (width 0.15) (type solid)) (fill none) (layer "F.Fab"))
    (pad "1" smd roundrect (at -0.484 0 90) (size 0.59 0.64) (layers "F.Cu" "F.Paste" "F.Mask") (roundrect_rratio 0.25)
      (net 304 "VCC3V3") (pintype "passive"))
    (pad "2" smd roundrect (at 0.484 0 90) (size 0.59 0.64) (layers "F.Cu" "F.Paste" "F.Mask") (roundrect_rratio 0.25)
      (net 9 "GND") (pintype "passive"))
  )

  (footprint "data-center-rdimm-ddr4-tester-footprints:C_0402_1005Metric" (layer "F.Cu")
    (at 132.936328 85.610008)
    (descr "Capacitor SMD 0402")
    (tags "capacitor SMD 0402")
    (property "Author" "Antmicro")
    (property "Dielectric" "")
    (property "License" "Apache-2.0")
    (property "MPN" "C1005X6S1A105K050BC")
    (property "Manufacturer" "TDK")
    (property "Sheetfile" "supply.kicad_sch")
    (property "Sheetname" "Supply")
    (property "Val" "1u")
    (property "Voltage" "")
    (property "ki_description" " ")
    (attr smd)
    (fp_text reference "C219" (at -1.246328 -2.460008) (layer "F.SilkS")
        (effects (font (size 0.7 0.7) (thickness 0.15)) (justify left bottom))
    )
    (fp_text value "C_1u_0402" (at 0 1.4) (layer "F.Fab") hide
        (effects (font (size 0.7 0.7) (thickness 0.15)) (justify left bottom))
    )
    (fp_text user "${REFERENCE}" (at -0.932 3.168) (layer "F.Fab") hide
        (effects (font (size 0.7 0.7) (thickness 0.15)) (justify left bottom))
    )
    (fp_text user "License: Apache-2.0" (at -0.932 5.17) (layer "F.Fab") hide
        (effects (font (size 0.7 0.7) (thickness 0.15)) (justify left bottom))
    )
    (fp_text user "Author: Antmicro" (at -0.932 4.17) (layer "F.Fab") hide
        (effects (font (size 0.7 0.7) (thickness 0.15)) (justify left bottom))
    )
    (fp_rect (start -0.94 -0.47) (end 0.94 0.47)
      (stroke (width 0.05) (type solid)) (fill none) (layer "F.CrtYd"))
    (fp_rect (start -0.499 -0.249) (end 0.499 0.249)
      (stroke (width 0.15) (type solid)) (fill none) (layer "F.Fab"))
    (pad "1" smd roundrect (at -0.484 0) (size 0.59 0.64) (layers "F.Cu" "F.Paste" "F.Mask") (roundrect_rratio 0.25)
      (net 302 "VCC1V8") (pintype "passive"))
    (pad "2" smd roundrect (at 0.484 0) (size 0.59 0.64) (layers "F.Cu" "F.Paste" "F.Mask") (roundrect_rratio 0.25)
      (net 9 "GND") (pintype "passive"))
  )

  (footprint "data-center-rdimm-ddr4-tester-footprints:L_1716_4441Metric" (layer "F.Cu")
    (at 138.636328 84.210008 90)
    (property "Author" "Antmicro")
    (property "License" "Apache-2.0")
    (property "MPN" "SRP0420-1R5K")
    (property "Manufacturer" "Bourns")
    (property "MaxCur" "6A")
    (property "Sheetfile" "supply.kicad_sch")
    (property "Sheetname" "Supply")
    (property "Size" "4.40x4.10")
    (property "Val" "1u5/6A")
    (attr smd)
    (fp_text reference "L3" (at 2.460008 -2.656328 180) (layer "F.SilkS")
        (effects (font (size 0.7 0.7) (thickness 0.15)) (justify left bottom))
    )
    (fp_text value "L_1u5_6A_1716" (at 0 3.3 90) (layer "F.Fab") hide
        (effects (font (size 0.7 0.7) (thickness 0.15)) (justify left bottom))
    )
    (fp_text user "License: Apache-2.0" (at -17.726 19.484 90) (layer "F.Fab") hide
        (effects (font (size 0.7 0.7) (thickness 0.15)) (justify left bottom))
    )
    (fp_text user "${REFERENCE}" (at -17.726 17.083 90) (layer "F.Fab") hide
        (effects (font (size 0.7 0.7) (thickness 0.15)) (justify left bottom))
    )
    (fp_text user "Author: Antmicro" (at -17.726 18.283 90) (layer "F.Fab") hide
        (effects (font (size 0.7 0.7) (thickness 0.15)) (justify left bottom))
    )
    (fp_line (start -2.202 -2.0555) (end 2.248 -2.0555)
      (stroke (width 0.15) (type solid)) (layer "F.SilkS"))
    (fp_line (start -2.202 -1.5265) (end -2.202 -2.0555)
      (stroke (width 0.15) (type solid)) (layer "F.SilkS"))
    (fp_line (start -2.202 2.0535) (end -2.202 1.5245)
      (stroke (width 0.15) (type solid)) (layer "F.SilkS"))
    (fp_line (start -2.202 2.0535) (end 2.248 2.0535)
      (stroke (width 0.15) (type solid)) (layer "F.SilkS"))
    (fp_line (start 2.248 -2.0555) (end 2.248 -1.5265)
      (stroke (width 0.15) (type solid)) (layer "F.SilkS"))
    (fp_line (start 2.248 2.0535) (end 2.248 1.5245)
      (stroke (width 0.15) (type solid)) (layer "F.SilkS"))
    (fp_rect (start -2.775 -2.35) (end 2.775 2.35)
      (stroke (width 0.05) (type solid)) (fill none) (layer "F.CrtYd"))
    (fp_line (start -2.202 -2.0555) (end 2.248 -2.0555)
      (stroke (width 0.15) (type solid)) (layer "F.Fab"))
    (fp_line (start -2.202 2.0295) (end -2.202 -2.0305)
      (stroke (width 0.15) (type solid)) (layer "F.Fab"))
    (fp_line (start 2.248 -2.0305) (end 2.248 2.0295)
      (stroke (width 0.15) (type solid)) (layer "F.Fab"))
    (fp_line (start 2.248 2.0535) (end -2.202 2.0535)
      (stroke (width 0.15) (type solid)) (layer "F.Fab"))
    (pad "1" smd roundrect (at -2 -0.0015 90) (size 1.4 1.9) (layers "F.Cu" "F.Paste" "F.Mask") (roundrect_rratio 0.05)
      (net 3 "Net-(U4-SW)") (pintype "passive"))
    (pad "2" smd roundrect (at 2 -0.0015 90) (size 1.4 1.9) (layers "F.Cu" "F.Paste" "F.Mask") (roundrect_rratio 0.05)
      (net 300 "VCC1V0") (pintype "passive"))
  )

  (footprint "data-center-rdimm-ddr4-tester-footprints:L_1716_4441Metric" (layer "F.Cu")
    (at 117.82 108.83 -90)
    (property "Author" "Antmicro")
    (property "License" "Apache-2.0")
    (property "MPN" "SRP0420-1R5K")
    (property "Manufacturer" "Bourns")
    (property "MaxCur" "6A")
    (property "Sheetfile" "supply.kicad_sch")
    (property "Sheetname" "Supply")
    (property "Size" "4.40x4.10")
    (property "Val" "1u5/6A")
    (attr smd)
    (fp_text reference "L5" (at -2.380008 2.326328) (layer "F.SilkS")
        (effects (font (size 0.7 0.7) (thickness 0.15)) (justify left bottom))
    )
    (fp_text value "L_1u5_6A_1716" (at 0 3.3 -90) (layer "F.Fab") hide
        (effects (font (size 0.7 0.7) (thickness 0.15)) (justify left bottom))
    )
    (fp_text user "${REFERENCE}" (at -17.726 17.083 -90) (layer "F.Fab") hide
        (effects (font (size 0.7 0.7) (thickness 0.15)) (justify left bottom))
    )
    (fp_text user "License: Apache-2.0" (at -17.726 19.484 -90) (layer "F.Fab") hide
        (effects (font (size 0.7 0.7) (thickness 0.15)) (justify left bottom))
    )
    (fp_text user "Author: Antmicro" (at -17.726 18.283 -90) (layer "F.Fab") hide
        (effects (font (size 0.7 0.7) (thickness 0.15)) (justify left bottom))
    )
    (fp_line (start -2.202 -2.0555) (end 2.248 -2.0555)
      (stroke (width 0.15) (type solid)) (layer "F.SilkS"))
    (fp_line (start -2.202 -1.5265) (end -2.202 -2.0555)
      (stroke (width 0.15) (type solid)) (layer "F.SilkS"))
    (fp_line (start -2.202 2.0535) (end -2.202 1.5245)
      (stroke (width 0.15) (type solid)) (layer "F.SilkS"))
    (fp_line (start -2.202 2.0535) (end 2.248 2.0535)
      (stroke (width 0.15) (type solid)) (layer "F.SilkS"))
    (fp_line (start 2.248 -2.0555) (end 2.248 -1.5265)
      (stroke (width 0.15) (type solid)) (layer "F.SilkS"))
    (fp_line (start 2.248 2.0535) (end 2.248 1.5245)
      (stroke (width 0.15) (type solid)) (layer "F.SilkS"))
    (fp_rect (start -2.775 -2.35) (end 2.775 2.35)
      (stroke (width 0.05) (type solid)) (fill none) (layer "F.CrtYd"))
    (fp_line (start -2.202 -2.0555) (end 2.248 -2.0555)
      (stroke (width 0.15) (type solid)) (layer "F.Fab"))
    (fp_line (start -2.202 2.0295) (end -2.202 -2.0305)
      (stroke (width 0.15) (type solid)) (layer "F.Fab"))
    (fp_line (start 2.248 -2.0305) (end 2.248 2.0295)
      (stroke (width 0.15) (type solid)) (layer "F.Fab"))
    (fp_line (start 2.248 2.0535) (end -2.202 2.0535)
      (stroke (width 0.15) (type solid)) (layer "F.Fab"))
    (pad "1" smd roundrect (at -2 -0.0015 270) (size 1.4 1.9) (layers "F.Cu" "F.Paste" "F.Mask") (roundrect_rratio 0.05)
      (net 50 "Net-(U9-SW)") (pintype "passive"))
    (pad "2" smd roundrect (at 2 -0.0015 270) (size 1.4 1.9) (layers "F.Cu" "F.Paste" "F.Mask") (roundrect_rratio 0.05)
      (net 304 "VCC3V3") (pintype "passive"))
  )

  (footprint "data-center-rdimm-ddr4-tester-footprints:L_1716_4441Metric" (layer "F.Cu")
    (at 132.386327 88.510008 180)
    (property "Author" "Antmicro")
    (property "License" "Apache-2.0")
    (property "MPN" "SRP0420-1R5K")
    (property "Manufacturer" "Bourns")
    (property "MaxCur" "6A")
    (property "Sheetfile" "supply.kicad_sch")
    (property "Sheetname" "Supply")
    (property "Size" "4.40x4.10")
    (property "Val" "1u5/6A")
    (attr smd)
    (fp_text reference "L7" (at 4.066327 -1.829992 180) (layer "F.SilkS")
        (effects (font (size 0.7 0.7) (thickness 0.15)) (justify left bottom))
    )
    (fp_text value "L_1u5_6A_1716" (at 0 3.3 180) (layer "F.Fab") hide
        (effects (font (size 0.7 0.7) (thickness 0.15)) (justify left bottom))
    )
    (fp_text user "Author: Antmicro" (at -17.726 18.283 180) (layer "F.Fab") hide
        (effects (font (size 0.7 0.7) (thickness 0.15)) (justify left bottom))
    )
    (fp_text user "${REFERENCE}" (at -17.726 17.083 180) (layer "F.Fab") hide
        (effects (font (size 0.7 0.7) (thickness 0.15)) (justify left bottom))
    )
    (fp_text user "License: Apache-2.0" (at -17.726 19.484 180) (layer "F.Fab") hide
        (effects (font (size 0.7 0.7) (thickness 0.15)) (justify left bottom))
    )
    (fp_line (start -2.202 -2.0555) (end 2.248 -2.0555)
      (stroke (width 0.15) (type solid)) (layer "F.SilkS"))
    (fp_line (start -2.202 -1.5265) (end -2.202 -2.0555)
      (stroke (width 0.15) (type solid)) (layer "F.SilkS"))
    (fp_line (start -2.202 2.0535) (end -2.202 1.5245)
      (stroke (width 0.15) (type solid)) (layer "F.SilkS"))
    (fp_line (start -2.202 2.0535) (end 2.248 2.0535)
      (stroke (width 0.15) (type solid)) (layer "F.SilkS"))
    (fp_line (start 2.248 -2.0555) (end 2.248 -1.5265)
      (stroke (width 0.15) (type solid)) (layer "F.SilkS"))
    (fp_line (start 2.248 2.0535) (end 2.248 1.5245)
      (stroke (width 0.15) (type solid)) (layer "F.SilkS"))
    (fp_rect (start -2.775 -2.35) (end 2.775 2.35)
      (stroke (width 0.05) (type solid)) (fill none) (layer "F.CrtYd"))
    (fp_line (start -2.202 -2.0555) (end 2.248 -2.0555)
      (stroke (width 0.15) (type solid)) (layer "F.Fab"))
    (fp_line (start -2.202 2.0295) (end -2.202 -2.0305)
      (stroke (width 0.15) (type solid)) (layer "F.Fab"))
    (fp_line (start 2.248 -2.0305) (end 2.248 2.0295)
      (stroke (width 0.15) (type solid)) (layer "F.Fab"))
    (fp_line (start 2.248 2.0535) (end -2.202 2.0535)
      (stroke (width 0.15) (type solid)) (layer "F.Fab"))
    (pad "1" smd roundrect (at -2 -0.0015 180) (size 1.4 1.9) (layers "F.Cu" "F.Paste" "F.Mask") (roundrect_rratio 0.05)
      (net 52 "Net-(U12-SW)") (pintype "passive"))
    (pad "2" smd roundrect (at 2 -0.0015 180) (size 1.4 1.9) (layers "F.Cu" "F.Paste" "F.Mask") (roundrect_rratio 0.05)
      (net 302 "VCC1V8") (pintype "passive"))
  )

  (footprint "data-center-rdimm-ddr4-tester-footprints:R_0402_1005Metric" (layer "F.Cu")
    (at 141.411328 90.635008 180)
    (descr "Resistor SMD 0402")
    (tags "resistor SMD 0402")
    (property "Author" "Antmicro")
    (property "License" "Apache-2.0")
    (property "MPN" "CR0402-FX-1501GLF")
    (property "Manufacturer" "Bourns")
    (property "Sheetfile" "supply.kicad_sch")
    (property "Sheetname" "Supply")
    (property "Tolerance" "1%")
    (property "Val" "1k5")
    (property "ki_description" "1k5 resistor in 0402 package with 1% tolerance")
    (attr smd)
    (fp_text reference "R39" (at -0.738672 -1.529992 180) (layer "F.SilkS")
        (effects (font (size 0.7 0.7) (thickness 0.15)) (justify left bottom))
    )
    (fp_text value "R_1k5_0402" (at 0 1.4 180) (layer "F.Fab") hide
        (effects (font (size 0.7 0.7) (thickness 0.15)) (justify left bottom))
    )
    (fp_text user "${REFERENCE}" (at -0.95 3.168 180) (layer "F.Fab") hide
        (effects (font (size 0.7 0.7) (thickness 0.15)) (justify left bottom))
    )
    (fp_text user "Author: Antmicro" (at -0.95 4.169 180) (layer "F.Fab") hide
        (effects (font (size 0.7 0.7) (thickness 0.15)) (justify left bottom))
    )
    (fp_text user "License: Apache-2.0" (at -0.95 5.169 180) (layer "F.Fab") hide
        (effects (font (size 0.7 0.7) (thickness 0.15)) (justify left bottom))
    )
    (fp_rect (start -0.93 -0.47) (end 0.93 0.47)
      (stroke (width 0.05) (type solid)) (fill none) (layer "F.CrtYd"))
    (fp_rect (start -0.5 -0.25) (end 0.5 0.25)
      (stroke (width 0.15) (type solid)) (fill none) (layer "F.Fab"))
    (pad "1" smd roundrect (at -0.485 0 180) (size 0.59 0.64) (layers "F.Cu" "F.Paste" "F.Mask") (roundrect_rratio 0.25)
      (net 300 "VCC1V0") (pintype "passive"))
    (pad "2" smd roundrect (at 0.485 0 180) (size 0.59 0.64) (layers "F.Cu" "F.Paste" "F.Mask") (roundrect_rratio 0.25)
      (net 370 "Net-(R39-Pad2)") (pintype "passive"))
  )

  (footprint "data-center-rdimm-ddr4-tester-footprints:R_0402_1005Metric" (layer "F.Cu")
    (at 141.411328 91.660008 180)
    (descr "Resistor SMD 0402")
    (tags "resistor SMD 0402")
    (property "Author" "Antmicro")
    (property "License" "Apache-2.0")
    (property "MPN" "CR0402-FX-1001GLF")
    (property "Manufacturer" "Bourns")
    (property "Sheetfile" "supply.kicad_sch")
    (property "Sheetname" "Supply")
    (property "Tolerance" "1%")
    (property "Val" "1k")
    (property "ki_description" "1k resistor in 0402 package with 1% tolerance")
    (attr smd)
    (fp_text reference "R41" (at -0.738672 -1.529992 180) (layer "F.SilkS")
        (effects (font (size 0.7 0.7) (thickness 0.15)) (justify left bottom))
    )
    (fp_text value "R_1k_0402" (at 0 1.4 180) (layer "F.Fab") hide
        (effects (font (size 0.7 0.7) (thickness 0.15)) (justify left bottom))
    )
    (fp_text user "License: Apache-2.0" (at -0.95 5.169 180) (layer "F.Fab") hide
        (effects (font (size 0.7 0.7) (thickness 0.15)) (justify left bottom))
    )
    (fp_text user "${REFERENCE}" (at -0.95 3.168 180) (layer "F.Fab") hide
        (effects (font (size 0.7 0.7) (thickness 0.15)) (justify left bottom))
    )
    (fp_text user "Author: Antmicro" (at -0.95 4.169 180) (layer "F.Fab") hide
        (effects (font (size 0.7 0.7) (thickness 0.15)) (justify left bottom))
    )
    (fp_rect (start -0.93 -0.47) (end 0.93 0.47)
      (stroke (width 0.05) (type solid)) (fill none) (layer "F.CrtYd"))
    (fp_rect (start -0.5 -0.25) (end 0.5 0.25)
      (stroke (width 0.15) (type solid)) (fill none) (layer "F.Fab"))
    (pad "1" smd roundrect (at -0.485 0 180) (size 0.59 0.64) (layers "F.Cu" "F.Paste" "F.Mask") (roundrect_rratio 0.25)
      (net 370 "Net-(R39-Pad2)") (pintype "passive"))
    (pad "2" smd roundrect (at 0.485 0 180) (size 0.59 0.64) (layers "F.Cu" "F.Paste" "F.Mask") (roundrect_rratio 0.25)
      (net 614 "Net-(U4-FB)") (pintype "passive"))
  )

  (footprint "data-center-rdimm-ddr4-tester-footprints:R_0402_1005Metric" (layer "F.Cu")
    (at 139.886328 91.960008 -90)
    (descr "Resistor SMD 0402")
    (tags "resistor SMD 0402")
    (property "Author" "Antmicro")
    (property "License" "Apache-2.0")
    (property "MPN" "CR0402-FX-1002GLF")
    (property "Manufacturer" "Bourns")
    (property "Sheetfile" "supply.kicad_sch")
    (property "Sheetname" "Supply")
    (property "Tolerance" "1%")
    (property "Val" "10k")
    (property "ki_description" "10k resistor in 0402 package with 1% tolerance")
    (attr smd)
    (fp_text reference "R43" (at 2.179992 -1.183672 -90) (layer "F.SilkS")
        (effects (font (size 0.7 0.7) (thickness 0.15)) (justify left bottom))
    )
    (fp_text value "R_10k_0402" (at 0 1.4 -90) (layer "F.Fab") hide
        (effects (font (size 0.7 0.7) (thickness 0.15)) (justify left bottom))
    )
    (fp_text user "Author: Antmicro" (at -0.95 4.169 -90) (layer "F.Fab") hide
        (effects (font (size 0.7 0.7) (thickness 0.15)) (justify left bottom))
    )
    (fp_text user "${REFERENCE}" (at -0.95 3.168 -90) (layer "F.Fab") hide
        (effects (font (size 0.7 0.7) (thickness 0.15)) (justify left bottom))
    )
    (fp_text user "License: Apache-2.0" (at -0.95 5.169 -90) (layer "F.Fab") hide
        (effects (font (size 0.7 0.7) (thickness 0.15)) (justify left bottom))
    )
    (fp_rect (start -0.93 -0.47) (end 0.93 0.47)
      (stroke (width 0.05) (type solid)) (fill none) (layer "F.CrtYd"))
    (fp_rect (start -0.5 -0.25) (end 0.5 0.25)
      (stroke (width 0.15) (type solid)) (fill none) (layer "F.Fab"))
    (pad "1" smd roundrect (at -0.485 0 270) (size 0.59 0.64) (layers "F.Cu" "F.Paste" "F.Mask") (roundrect_rratio 0.25)
      (net 614 "Net-(U4-FB)") (pintype "passive"))
    (pad "2" smd roundrect (at 0.485 0 270) (size 0.59 0.64) (layers "F.Cu" "F.Paste" "F.Mask") (roundrect_rratio 0.25)
      (net 9 "GND") (pintype "passive"))
  )

  (footprint "data-center-rdimm-ddr4-tester-footprints:R_0402_1005Metric" (layer "F.Cu")
    (at 153.099328 114.102008 -90)
    (descr "Resistor SMD 0402")
    (tags "resistor SMD 0402")
    (property "Author" "Antmicro")
    (property "Current" "1A")
    (property "License" "Apache-2.0")
    (property "MPN" "ERJ2GE0R00X")
    (property "Manufacturer" "Panasonic")
    (property "Sheetfile" "supply.kicad_sch")
    (property "Sheetname" "Supply")
    (property "Tolerance" "")
    (property "Val" "0R")
    (property "ki_description" "0R resistor in 0402 package with unspecified tolerance")
    (attr smd)
    (fp_text reference "R44" (at 1.067992 -3.370672 -90) (layer "F.SilkS")
        (effects (font (size 0.7 0.7) (thickness 0.15)) (justify left bottom))
    )
    (fp_text value "R_0R_0402" (at 0 1.4 -90) (layer "F.Fab") hide
        (effects (font (size 0.7 0.7) (thickness 0.15)) (justify left bottom))
    )
    (fp_text user "License: Apache-2.0" (at -0.95 5.169 -90) (layer "F.Fab") hide
        (effects (font (size 0.7 0.7) (thickness 0.15)) (justify left bottom))
    )
    (fp_text user "Author: Antmicro" (at -0.95 4.169 -90) (layer "F.Fab") hide
        (effects (font (size 0.7 0.7) (thickness 0.15)) (justify left bottom))
    )
    (fp_text user "${REFERENCE}" (at -0.95 3.168 -90) (layer "F.Fab") hide
        (effects (font (size 0.7 0.7) (thickness 0.15)) (justify left bottom))
    )
    (fp_rect (start -0.93 -0.47) (end 0.93 0.47)
      (stroke (width 0.05) (type solid)) (fill none) (layer "F.CrtYd"))
    (fp_rect (start -0.5 -0.25) (end 0.5 0.25)
      (stroke (width 0.15) (type solid)) (fill none) (layer "F.Fab"))
    (pad "1" smd roundrect (at -0.485 0 270) (size 0.59 0.64) (layers "F.Cu" "F.Paste" "F.Mask") (roundrect_rratio 0.25)
      (net 153 "/Supply/VCC_IO_EN") (pintype "passive"))
    (pad "2" smd roundrect (at 0.485 0 270) (size 0.59 0.64) (layers "F.Cu" "F.Paste" "F.Mask") (roundrect_rratio 0.25)
      (net 624 "Net-(U5-EN)") (pintype "passive"))
  )

  (footprint "data-center-rdimm-ddr4-tester-footprints:R_0402_1005Metric" (layer "F.Cu")
    (at 154.149328 114.102008 -90)
    (descr "Resistor SMD 0402")
    (tags "resistor SMD 0402")
    (property "Author" "Antmicro")
    (property "License" "Apache-2.0")
    (property "MPN" "CR0402-FX-4991GLF")
    (property "Manufacturer" "Bourns")
    (property "Sheetfile" "supply.kicad_sch")
    (property "Sheetname" "Supply")
    (property "Tolerance" "1%")
    (property "Val" "4k99")
    (property "ki_description" "4k99 resistor in 0402 package with 1% tolerance")
    (attr smd)
    (fp_text reference "R45" (at 1.067992 -4.110672 -90) (layer "F.SilkS")
        (effects (font (size 0.7 0.7) (thickness 0.15)) (justify left bottom))
    )
    (fp_text value "R_4k99_0402" (at 0 1.4 -90) (layer "F.Fab") hide
        (effects (font (size 0.7 0.7) (thickness 0.15)) (justify left bottom))
    )
    (fp_text user "Author: Antmicro" (at -0.95 4.169 -90) (layer "F.Fab") hide
        (effects (font (size 0.7 0.7) (thickness 0.15)) (justify left bottom))
    )
    (fp_text user "License: Apache-2.0" (at -0.95 5.169 -90) (layer "F.Fab") hide
        (effects (font (size 0.7 0.7) (thickness 0.15)) (justify left bottom))
    )
    (fp_text user "${REFERENCE}" (at -0.95 3.168 -90) (layer "F.Fab") hide
        (effects (font (size 0.7 0.7) (thickness 0.15)) (justify left bottom))
    )
    (fp_rect (start -0.93 -0.47) (end 0.93 0.47)
      (stroke (width 0.05) (type solid)) (fill none) (layer "F.CrtYd"))
    (fp_rect (start -0.5 -0.25) (end 0.5 0.25)
      (stroke (width 0.15) (type solid)) (fill none) (layer "F.Fab"))
    (pad "1" smd roundrect (at -0.485 0 270) (size 0.59 0.64) (layers "F.Cu" "F.Paste" "F.Mask") (roundrect_rratio 0.25)
      (net 176 "VCC1V2") (pintype "passive"))
    (pad "2" smd roundrect (at 0.485 0 270) (size 0.59 0.64) (layers "F.Cu" "F.Paste" "F.Mask") (roundrect_rratio 0.25)
      (net 625 "Net-(U5-FB)") (pintype "passive"))
  )

  (footprint "data-center-rdimm-ddr4-tester-footprints:R_0402_1005Metric" (layer "F.Cu")
    (at 132.536328 95.110008)
    (descr "Resistor SMD 0402")
    (tags "resistor SMD 0402")
    (property "Author" "Antmicro")
    (property "License" "Apache-2.0")
    (property "MPN" "CR0402-FX-1242GLF")
    (property "Manufacturer" "Bourns")
    (property "Sheetfile" "supply.kicad_sch")
    (property "Sheetname" "Supply")
    (property "Tolerance" "1%")
    (property "Val" "12k4")
    (property "ki_description" "12k4 resistor in 0402 package with 1% tolerance")
    (attr smd)
    (fp_text reference "R83" (at 0.643672 0.399992) (layer "F.SilkS")
        (effects (font (size 0.7 0.7) (thickness 0.15)) (justify left bottom))
    )
    (fp_text value "R_12k4_0402" (at 0 1.4) (layer "F.Fab") hide
        (effects (font (size 0.7 0.7) (thickness 0.15)) (justify left bottom))
    )
    (fp_text user "${REFERENCE}" (at -0.95 3.168) (layer "F.Fab") hide
        (effects (font (size 0.7 0.7) (thickness 0.15)) (justify left bottom))
    )
    (fp_text user "Author: Antmicro" (at -0.95 4.169) (layer "F.Fab") hide
        (effects (font (size 0.7 0.7) (thickness 0.15)) (justify left bottom))
    )
    (fp_text user "License: Apache-2.0" (at -0.95 5.169) (layer "F.Fab") hide
        (effects (font (size 0.7 0.7) (thickness 0.15)) (justify left bottom))
    )
    (fp_rect (start -0.93 -0.47) (end 0.93 0.47)
      (stroke (width 0.05) (type solid)) (fill none) (layer "F.CrtYd"))
    (fp_rect (start -0.5 -0.25) (end 0.5 0.25)
      (stroke (width 0.15) (type solid)) (fill none) (layer "F.Fab"))
    (pad "1" smd roundrect (at -0.485 0) (size 0.59 0.64) (layers "F.Cu" "F.Paste" "F.Mask") (roundrect_rratio 0.25)
      (net 302 "VCC1V8") (pintype "passive"))
    (pad "2" smd roundrect (at 0.485 0) (size 0.59 0.64) (layers "F.Cu" "F.Paste" "F.Mask") (roundrect_rratio 0.25)
      (net 653 "Net-(U12-FB)") (pintype "passive"))
  )

  (footprint "data-center-rdimm-ddr4-tester-footprints:R_0402_1005Metric" (layer "F.Cu")
    (at 132.536328 96.110008 180)
    (descr "Resistor SMD 0402")
    (tags "resistor SMD 0402")
    (property "Author" "Antmicro")
    (property "License" "Apache-2.0")
    (property "MPN" "CR0402-FX-1002GLF")
    (property "Manufacturer" "Bourns")
    (property "Sheetfile" "supply.kicad_sch")
    (property "Sheetname" "Supply")
    (property "Tolerance" "1%")
    (property "Val" "10k")
    (property "ki_description" "10k resistor in 0402 package with 1% tolerance")
    (attr smd)
    (fp_text reference "R84" (at -0.663672 -0.389992 180) (layer "F.SilkS")
        (effects (font (size 0.7 0.7) (thickness 0.15)) (justify left bottom))
    )
    (fp_text value "R_10k_0402" (at 0 1.4 180) (layer "F.Fab") hide
        (effects (font (size 0.7 0.7) (thickness 0.15)) (justify left bottom))
    )
    (fp_text user "${REFERENCE}" (at -0.95 3.168 180) (layer "F.Fab") hide
        (effects (font (size 0.7 0.7) (thickness 0.15)) (justify left bottom))
    )
    (fp_text user "License: Apache-2.0" (at -0.95 5.169 180) (layer "F.Fab") hide
        (effects (font (size 0.7 0.7) (thickness 0.15)) (justify left bottom))
    )
    (fp_text user "Author: Antmicro" (at -0.95 4.169 180) (layer "F.Fab") hide
        (effects (font (size 0.7 0.7) (thickness 0.15)) (justify left bottom))
    )
    (fp_rect (start -0.93 -0.47) (end 0.93 0.47)
      (stroke (width 0.05) (type solid)) (fill none) (layer "F.CrtYd"))
    (fp_rect (start -0.5 -0.25) (end 0.5 0.25)
      (stroke (width 0.15) (type solid)) (fill none) (layer "F.Fab"))
    (pad "1" smd roundrect (at -0.485 0 180) (size 0.59 0.64) (layers "F.Cu" "F.Paste" "F.Mask") (roundrect_rratio 0.25)
      (net 653 "Net-(U12-FB)") (pintype "passive"))
    (pad "2" smd roundrect (at 0.485 0 180) (size 0.59 0.64) (layers "F.Cu" "F.Paste" "F.Mask") (roundrect_rratio 0.25)
      (net 9 "GND") (pintype "passive"))
  )

  (footprint "data-center-rdimm-ddr4-tester-footprints:AP62301WU-7-TSOT23-6" (layer "F.Cu")
    (at 138.336328 89.110008 -90)
    (property "Author" "Antmicro")
    (property "License" "Apache-2.0")
    (property "MPN" "AP62301WU-7")
    (property "Manufacturer" "Diodes Incorporated")
    (property "Sheetfile" "supply.kicad_sch")
    (property "Sheetname" "Supply")
    (attr smd)
    (fp_text reference "U4" (at -1.490008 2.236328) (layer "F.SilkS")
        (effects (font (size 0.7 0.7) (thickness 0.15)) (justify left bottom))
    )
    (fp_text value "AP62301WU-7" (at -0.005 2.6 -90) (layer "F.Fab") hide
        (effects (font (size 0.7 0.7) (thickness 0.15)) (justify left bottom))
    )
    (fp_text user "Author: Antmicro" (at -1.893 7.368 -90) (layer "F.Fab") hide
        (effects (font (size 0.7 0.7) (thickness 0.15)) (justify left bottom))
    )
    (fp_text user "License: Apache-2.0" (at -1.893 4.967 -90) (layer "F.Fab") hide
        (effects (font (size 0.7 0.7) (thickness 0.15)) (justify left bottom))
    )
    (fp_text user "${REFERENCE}" (at -1.893 6.168 -90) (layer "F.Fab") hide
        (effects (font (size 0.7 0.7) (thickness 0.15)) (justify left bottom))
    )
    (fp_line (start -1.4805 0.725) (end -1.4795 -0.725)
      (stroke (width 0.15) (type solid)) (layer "F.SilkS"))
    (fp_line (start -1.4805 0.725) (end -1.3905 0.725)
      (stroke (width 0.15) (type solid)) (layer "F.SilkS"))
    (fp_line (start -1.4795 -0.725) (end -1.3905 -0.725)
      (stroke (width 0.15) (type solid)) (layer "F.SilkS"))
    (fp_line (start 1.479 0.73) (end 1.38 0.73)
      (stroke (width 0.15) (type solid)) (layer "F.SilkS"))
    (fp_line (start 1.48 -0.72) (end 1.38 -0.72)
      (stroke (width 0.15) (type solid)) (layer "F.SilkS"))
    (fp_line (start 1.48 -0.72) (end 1.479 0.73)
      (stroke (width 0.15) (type solid)) (layer "F.SilkS"))
    (fp_circle (center -1.499 1.236) (end -1.45 1.236)
      (stroke (width 0.15) (type solid)) (fill solid) (layer "F.SilkS"))
    (fp_rect (start -1.65 -1.61) (end 1.65 1.61)
      (stroke (width 0.05) (type solid)) (fill none) (layer "F.CrtYd"))
    (fp_line (start -1.527 -0.833) (end 1.523 -0.833)
      (stroke (width 0.15) (type solid)) (layer "F.Fab"))
    (fp_line (start -1.527 0.491) (end -1.527 -0.833)
      (stroke (width 0.15) (type solid)) (layer "F.Fab"))
    (fp_line (start -1.527 0.491) (end -1.102 0.916)
      (stroke (width 0.15) (type solid)) (layer "F.Fab"))
    (fp_line (start -1.102 0.916) (end 1.523 0.916)
      (stroke (width 0.15) (type solid)) (layer "F.Fab"))
    (fp_line (start 1.523 -0.833) (end 1.523 0.916)
      (stroke (width 0.15) (type solid)) (layer "F.Fab"))
    (pad "1" smd rect (at -0.952 1.18 270) (size 0.7 0.8) (layers "F.Cu" "F.Paste" "F.Mask")
      (net 9 "GND") (pinfunction "GND") (pintype "power_in"))
    (pad "2" smd rect (at -0.001 1.18 270) (size 0.7 0.8) (layers "F.Cu" "F.Paste" "F.Mask")
      (net 3 "Net-(U4-SW)") (pinfunction "SW") (pintype "power_out"))
    (pad "3" smd rect (at 0.947 1.18 270) (size 0.7 0.8) (layers "F.Cu" "F.Paste" "F.Mask")
      (net 307 "5V0_SYS") (pinfunction "VIN") (pintype "power_in"))
    (pad "4" smd rect (at 0.947 -1.18 270) (size 0.7 0.8) (layers "F.Cu" "F.Paste" "F.Mask")
      (net 614 "Net-(U4-FB)") (pinfunction "FB") (pintype "input"))
    (pad "5" smd rect (at -0.001 -1.18 270) (size 0.7 0.8) (layers "F.Cu" "F.Paste" "F.Mask")
      (net 603 "Net-(U4-EN)") (pinfunction "EN") (pintype "input"))
    (pad "6" smd rect (at -0.952 -1.18 270) (size 0.7 0.8) (layers "F.Cu" "F.Paste" "F.Mask")
      (net 2 "Net-(U4-BST)") (pinfunction "BST") (pintype "output"))
  )

  (footprint "data-center-rdimm-ddr4-tester-footprints:C_0402_1005Metric" (layer "F.Cu")
    (at 148.499328 121.852008 -90)
    (descr "Capacitor SMD 0402")
    (tags "capacitor SMD 0402")
    (property "Author" "Antmicro")
    (property "Dielectric" "")
    (property "License" "Apache-2.0")
    (property "MPN" "C1005X6S1A105K050BC")
    (property "Manufacturer" "TDK")
    (property "Sheetfile" "supply.kicad_sch")
    (property "Sheetname" "Supply")
    (property "Val" "1u")
    (property "Voltage" "")
    (property "ki_description" " ")
    (attr smd)
    (fp_text reference "C156" (at 1.477992 2.539328 -90) (layer "F.SilkS")
        (effects (font (size 0.7 0.7) (thickness 0.15)) (justify left bottom))
    )
    (fp_text value "C_1u_0402" (at 0 1.4 -90) (layer "F.Fab") hide
        (effects (font (size 0.7 0.7) (thickness 0.15)) (justify left bottom))
    )
    (fp_text user "Author: Antmicro" (at -0.932 4.17 -90) (layer "F.Fab") hide
        (effects (font (size 0.7 0.7) (thickness 0.15)) (justify left bottom))
    )
    (fp_text user "${REFERENCE}" (at -0.932 3.168 -90) (layer "F.Fab") hide
        (effects (font (size 0.7 0.7) (thickness 0.15)) (justify left bottom))
    )
    (fp_text user "License: Apache-2.0" (at -0.932 5.17 -90) (layer "F.Fab") hide
        (effects (font (size 0.7 0.7) (thickness 0.15)) (justify left bottom))
    )
    (fp_rect (start -0.94 -0.47) (end 0.94 0.47)
      (stroke (width 0.05) (type solid)) (fill none) (layer "F.CrtYd"))
    (fp_rect (start -0.499 -0.249) (end 0.499 0.249)
      (stroke (width 0.15) (type solid)) (fill none) (layer "F.Fab"))
    (pad "1" smd roundrect (at -0.484 0 270) (size 0.59 0.64) (layers "F.Cu" "F.Paste" "F.Mask") (roundrect_rratio 0.25)
      (net 176 "VCC1V2") (pintype "passive"))
    (pad "2" smd roundrect (at 0.484 0 270) (size 0.59 0.64) (layers "F.Cu" "F.Paste" "F.Mask") (roundrect_rratio 0.25)
      (net 9 "GND") (pintype "passive"))
  )

  (footprint "data-center-rdimm-ddr4-tester-footprints:C_0402_1005Metric" (layer "F.Cu")
    (at 142.036328 81.810008)
    (descr "Capacitor SMD 0402")
    (tags "capacitor SMD 0402")
    (property "Author" "Antmicro")
    (property "Dielectric" "")
    (property "License" "Apache-2.0")
    (property "MPN" "04024W226MAT2A")
    (property "Manufacturer" "AVX")
    (property "Sheetfile" "supply.kicad_sch")
    (property "Sheetname" "Supply")
    (property "Val" "22u")
    (property "Voltage" "")
    (property "ki_description" " ")
    (attr smd)
    (fp_text reference "C96" (at 0.793672 0.369992) (layer "F.SilkS")
        (effects (font (size 0.7 0.7) (thickness 0.15)) (justify left bottom))
    )
    (fp_text value "C_22u_0402" (at 0 1.4) (layer "F.Fab") hide
        (effects (font (size 0.7 0.7) (thickness 0.15)) (justify left bottom))
    )
    (fp_text user "${REFERENCE}" (at -0.932 3.168) (layer "F.Fab") hide
        (effects (font (size 0.7 0.7) (thickness 0.15)) (justify left bottom))
    )
    (fp_text user "License: Apache-2.0" (at -0.932 5.17) (layer "F.Fab") hide
        (effects (font (size 0.7 0.7) (thickness 0.15)) (justify left bottom))
    )
    (fp_text user "Author: Antmicro" (at -0.932 4.17) (layer "F.Fab") hide
        (effects (font (size 0.7 0.7) (thickness 0.15)) (justify left bottom))
    )
    (fp_rect (start -0.94 -0.47) (end 0.94 0.47)
      (stroke (width 0.05) (type solid)) (fill none) (layer "F.CrtYd"))
    (fp_rect (start -0.499 -0.249) (end 0.499 0.249)
      (stroke (width 0.15) (type solid)) (fill none) (layer "F.Fab"))
    (pad "1" smd roundrect (at -0.484 0) (size 0.59 0.64) (layers "F.Cu" "F.Paste" "F.Mask") (roundrect_rratio 0.25)
      (net 300 "VCC1V0") (pintype "passive"))
    (pad "2" smd roundrect (at 0.484 0) (size 0.59 0.64) (layers "F.Cu" "F.Paste" "F.Mask") (roundrect_rratio 0.25)
      (net 9 "GND") (pintype "passive"))
  )

  (footprint "data-center-rdimm-ddr4-tester-footprints:R_1206_3216Metric" (layer "F.Cu")
    (at 130.7 83.4 90)
    (property "Author" "Antmicro")
    (property "License" "Apache-2.0")
    (property "MPN" "RL1206FR-7W0R01L")
    (property "Manufacturer" "Yaego")
    (property "Sheetfile" "supply.kicad_sch")
    (property "Sheetname" "Supply")
    (property "Tolerance" "1%")
    (property "Val" "0R01")
    (property "ki_description" "0R01 resistor in 1206 package with unspecified tolerance")
    (attr smd)
    (fp_text reference "R203" (at -1.39 -1.12 90) (layer "F.SilkS")
        (effects (font (size 0.7 0.7) (thickness 0.15)) (justify left bottom))
    )
    (fp_text value "R_0R01_1206" (at 0 2 90) (layer "F.Fab") hide
        (effects (font (size 0.7 0.7) (thickness 0.15)) (justify left bottom))
    )
    (fp_text user "Author: Antmicro" (at -2.401 4.899 90) (layer "F.Fab") hide
        (effects (font (size 0.7 0.7) (thickness 0.15)) (justify left bottom))
    )
    (fp_text user "License: Apache-2.0" (at -2.401 6.3 90) (layer "F.Fab") hide
        (effects (font (size 0.7 0.7) (thickness 0.15)) (justify left bottom))
    )
    (fp_text user "${REFERENCE}" (at -2.401 3.5 90) (layer "F.Fab") hide
        (effects (font (size 0.7 0.7) (thickness 0.15)) (justify left bottom))
    )
    (fp_line (start 0 -0.902) (end -0.5 -0.902)
      (stroke (width 0.15) (type solid)) (layer "F.SilkS"))
    (fp_line (start 0 -0.902) (end 0.498 -0.902)
      (stroke (width 0.15) (type solid)) (layer "F.SilkS"))
    (fp_line (start 0 0.9) (end -0.5 0.9)
      (stroke (width 0.15) (type solid)) (layer "F.SilkS"))
    (fp_line (start 0 0.9) (end 0.498 0.9)
      (stroke (width 0.15) (type solid)) (layer "F.SilkS"))
    (fp_rect (start -2.25 -1.05) (end 2.25 1.05)
      (stroke (width 0.05) (type solid)) (fill none) (layer "F.CrtYd"))
    (fp_line (start -1.601 -0.802) (end -1.601 0.8)
      (stroke (width 0.15) (type solid)) (layer "F.Fab"))
    (fp_line (start -1.601 -0.802) (end 1.6 -0.802)
      (stroke (width 0.15) (type solid)) (layer "F.Fab"))
    (fp_line (start -1.601 0.8) (end 1.6 0.8)
      (stroke (width 0.15) (type solid)) (layer "F.Fab"))
    (fp_line (start 1.6 -0.802) (end 1.6 0.8)
      (stroke (width 0.15) (type solid)) (layer "F.Fab"))
    (pad "1" smd roundrect (at -1.5 0 90) (size 1.2 1.8) (layers "F.Cu" "F.Paste" "F.Mask") (roundrect_rratio 0.15)
      (net 302 "VCC1V8") (pintype "passive"))
    (pad "2" smd roundrect (at 1.499 0 90) (size 1.2 1.8) (layers "F.Cu" "F.Paste" "F.Mask") (roundrect_rratio 0.15)
      (net 144 "1V8_SYS") (pintype "passive"))
  )

  (footprint "data-center-rdimm-ddr4-tester-footprints:R_0402_1005Metric" (layer "F.Cu")
    (at 223.8 122.8 90)
    (descr "Resistor SMD 0402")
    (tags "resistor SMD 0402")
    (property "Author" "Antmicro")
    (property "License" "Apache-2.0")
    (property "MPN" "CR0402-FX-1003GLF")
    (property "Manufacturer" "Bourns")
    (property "Sheetfile" "supply.kicad_sch")
    (property "Sheetname" "Supply")
    (property "Tolerance" "1%")
    (property "Val" "100k")
    (property "ki_description" "100k resistor in 0402 package with 1% tolerance")
    (attr smd)
    (fp_text reference "R121" (at -3.55 0.35 270) (layer "F.SilkS")
        (effects (font (size 0.7 0.7) (thickness 0.15)) (justify left bottom))
    )
    (fp_text value "R_100k_0402" (at 0 1.4 90) (layer "F.Fab") hide
        (effects (font (size 0.7 0.7) (thickness 0.15)) (justify left bottom))
    )
    (fp_text user "License: Apache-2.0" (at -0.95 5.169 90) (layer "F.Fab") hide
        (effects (font (size 0.7 0.7) (thickness 0.15)) (justify left bottom))
    )
    (fp_text user "Author: Antmicro" (at -0.95 4.169 90) (layer "F.Fab") hide
        (effects (font (size 0.7 0.7) (thickness 0.15)) (justify left bottom))
    )
    (fp_text user "${REFERENCE}" (at -0.95 3.168 90) (layer "F.Fab") hide
        (effects (font (size 0.7 0.7) (thickness 0.15)) (justify left bottom))
    )
    (fp_rect (start -0.93 -0.47) (end 0.93 0.47)
      (stroke (width 0.05) (type solid)) (fill none) (layer "F.CrtYd"))
    (fp_rect (start -0.5 -0.25) (end 0.5 0.25)
      (stroke (width 0.15) (type solid)) (fill none) (layer "F.Fab"))
    (pad "1" smd roundrect (at -0.485 0 90) (size 0.59 0.64) (layers "F.Cu" "F.Paste" "F.Mask") (roundrect_rratio 0.25)
      (net 584 "Net-(Q12-G)") (pintype "passive"))
    (pad "2" smd roundrect (at 0.485 0 90) (size 0.59 0.64) (layers "F.Cu" "F.Paste" "F.Mask") (roundrect_rratio 0.25)
      (net 9 "GND") (pintype "passive"))
  )

  (footprint "data-center-rdimm-ddr4-tester-footprints:C_0402_1005Metric" (layer "F.Cu")
    (at 123.275 99.525 -90)
    (descr "Capacitor SMD 0402")
    (tags "capacitor SMD 0402")
    (property "Author" "Antmicro")
    (property "Dielectric" "")
    (property "License" "Apache-2.0")
    (property "MPN" "CC0402MRX5R5BB106")
    (property "Manufacturer" "Yaego")
    (property "Sheetfile" "supply.kicad_sch")
    (property "Sheetname" "Supply")
    (property "Val" "10u")
    (property "Voltage" "")
    (property "ki_description" " ")
    (attr smd)
    (fp_text reference "C1" (at 2.265 -0.395 -90) (layer "F.SilkS")
        (effects (font (size 0.7 0.7) (thickness 0.15)) (justify left bottom))
    )
    (fp_text value "C_10u_0402" (at 0 1.4 -90) (layer "F.Fab") hide
        (effects (font (size 0.7 0.7) (thickness 0.15)) (justify left bottom))
    )
    (fp_text user "License: Apache-2.0" (at -0.932 5.17 -90) (layer "F.Fab") hide
        (effects (font (size 0.7 0.7) (thickness 0.15)) (justify left bottom))
    )
    (fp_text user "Author: Antmicro" (at -0.932 4.17 -90) (layer "F.Fab") hide
        (effects (font (size 0.7 0.7) (thickness 0.15)) (justify left bottom))
    )
    (fp_text user "${REFERENCE}" (at -0.932 3.168 -90) (layer "F.Fab") hide
        (effects (font (size 0.7 0.7) (thickness 0.15)) (justify left bottom))
    )
    (fp_rect (start -0.94 -0.47) (end 0.94 0.47)
      (stroke (width 0.05) (type solid)) (fill none) (layer "F.CrtYd"))
    (fp_rect (start -0.499 -0.249) (end 0.499 0.249)
      (stroke (width 0.15) (type solid)) (fill none) (layer "F.Fab"))
    (pad "1" smd roundrect (at -0.484 0 270) (size 0.59 0.64) (layers "F.Cu" "F.Paste" "F.Mask") (roundrect_rratio 0.25)
      (net 307 "5V0_SYS") (pintype "passive"))
    (pad "2" smd roundrect (at 0.484 0 270) (size 0.59 0.64) (layers "F.Cu" "F.Paste" "F.Mask") (roundrect_rratio 0.25)
      (net 9 "GND") (pintype "passive"))
  )

  (footprint "data-center-rdimm-ddr4-tester-footprints:R_0201" (layer "F.Cu")
    (at 163.28 109.02 -90)
    (descr "Resistor SMD 0201")
    (tags "resistor SMD 0201")
    (property "Author" "Antmicro")
    (property "License" "Apache-2.0")
    (property "MPN" "CR0201-FX-0R00GLF")
    (property "Manufacturer" "Bourns")
    (property "Sheetfile" "ethernet.kicad_sch")
    (property "Sheetname" "Ethernet")
    (property "Tolerance" "1%")
    (property "Val" "0R")
    (property "ki_description" "0R resistor in 0201 package with 1% tolerance")
    (attr smd)
    (fp_text reference "R111" (at 3.43 -0.31 -90) (layer "F.SilkS")
        (effects (font (size 0.7 0.7) (thickness 0.15)) (justify left bottom))
    )
    (fp_text value "R_0R_0201" (at 0 1.25 -90) (layer "F.Fab") hide
        (effects (font (size 0.7 0.7) (thickness 0.15)) (justify left bottom))
    )
    (fp_text user "${REFERENCE}" (at -0.71 3.25 -90) (layer "F.Fab") hide
        (effects (font (size 0.7 0.7) (thickness 0.15)) (justify left bottom))
    )
    (fp_text user "Author: Antmicro" (at -0.71 5.25 -90) (layer "F.Fab") hide
        (effects (font (size 0.7 0.7) (thickness 0.15)) (justify left bottom))
    )
    (fp_text user "License: Apache-2.0" (at -0.71 4.25 -90) (layer "F.Fab") hide
        (effects (font (size 0.7 0.7) (thickness 0.15)) (justify left bottom))
    )
    (fp_rect (start -0.71 -0.36) (end 0.71 0.36)
      (stroke (width 0.05) (type solid)) (fill none) (layer "F.CrtYd"))
    (fp_rect (start -0.3 -0.15) (end 0.298 0.148)
      (stroke (width 0.15) (type solid)) (fill none) (layer "F.Fab"))
    (pad "" smd roundrect (at -0.346 0 270) (size 0.318 0.36) (layers "F.Paste") (roundrect_rratio 0.25))
    (pad "" smd roundrect (at 0.344 0 270) (size 0.318 0.36) (layers "F.Paste") (roundrect_rratio 0.25))
    (pad "1" smd roundrect (at -0.32 0 270) (size 0.46 0.4) (layers "F.Cu" "F.Mask") (roundrect_rratio 0.25)
      (net 830 "/Ethernet/ETH4_BP_P") (pintype "passive"))
    (pad "2" smd roundrect (at 0.32 0 270) (size 0.46 0.4) (layers "F.Cu" "F.Mask") (roundrect_rratio 0.25)
      (net 548 "/Ethernet/INT_ETH4_P") (pintype "passive"))
  )

  (footprint "data-center-rdimm-ddr4-tester-footprints:C_0402_1005Metric" (layer "F.Cu")
    (at 248.555 120.81 180)
    (descr "Capacitor SMD 0402")
    (tags "capacitor SMD 0402")
    (property "Author" "Antmicro")
    (property "Dielectric" "X5R")
    (property "License" "Apache-2.0")
    (property "MPN" "GRM155R61H104KE14D")
    (property "Manufacturer" "Murata")
    (property "Sheetfile" "pcie.kicad_sch")
    (property "Sheetname" "FPGA banks 115-116")
    (property "Val" "100n")
    (property "Voltage" "50V")
    (property "ki_description" " ")
    (attr smd)
    (fp_text reference "C246" (at 1.485 1.56 180) (layer "F.SilkS")
        (effects (font (size 0.7 0.7) (thickness 0.15)) (justify left bottom))
    )
    (fp_text value "C_100n_0402" (at 0 1.4 180) (layer "F.Fab") hide
        (effects (font (size 0.7 0.7) (thickness 0.15)) (justify left bottom))
    )
    (fp_text user "${REFERENCE}" (at -0.932 3.168 180) (layer "F.Fab") hide
        (effects (font (size 0.7 0.7) (thickness 0.15)) (justify left bottom))
    )
    (fp_text user "License: Apache-2.0" (at -0.932 5.17 180) (layer "F.Fab") hide
        (effects (font (size 0.7 0.7) (thickness 0.15)) (justify left bottom))
    )
    (fp_text user "Author: Antmicro" (at -0.932 4.17 180) (layer "F.Fab") hide
        (effects (font (size 0.7 0.7) (thickness 0.15)) (justify left bottom))
    )
    (fp_rect (start -0.94 -0.47) (end 0.94 0.47)
      (stroke (width 0.05) (type solid)) (fill none) (layer "F.CrtYd"))
    (fp_rect (start -0.499 -0.249) (end 0.499 0.249)
      (stroke (width 0.15) (type solid)) (fill none) (layer "F.Fab"))
    (pad "1" smd roundrect (at -0.484 0 180) (size 0.59 0.64) (layers "F.Cu" "F.Paste" "F.Mask") (roundrect_rratio 0.25)
      (net 403 "GTR_REFCLK0_C_P") (pintype "passive"))
    (pad "2" smd roundrect (at 0.484 0 180) (size 0.59 0.64) (layers "F.Cu" "F.Paste" "F.Mask") (roundrect_rratio 0.25)
      (net 404 "/FPGA banks 115-116/GTR_REFCLK0_P") (pintype "passive"))
  )

  (footprint "data-center-rdimm-ddr4-tester-footprints:mounting-hole-3mm-NPTH" (layer "F.Cu")
    (at 256.75 133)
    (property "Author" "Antmicro")
    (property "License" "Apache-2.0")
    (property "MPN" "")
    (property "Manufacturer" "")
    (property "Sheetfile" "data-center-rdimm-ddr4-tester.kicad_sch")
    (property "Sheetname" "")
    (attr through_hole)
    (fp_text reference "MP2" (at 0 -1.8) (layer "F.SilkS") hide
        (effects (font (size 0.7 0.7) (thickness 0.15)) (justify left bottom))
    )
    (fp_text value "PCB_Mount_Hole_3mm_NPTH" (at 0 2.3) (layer "F.Fab") hide
        (effects (font (size 0.7 0.7) (thickness 0.15)) (justify left bottom))
    )
    (fp_text user "Author: Antmicro" (at 0 5.95) (layer "F.Fab") hide
        (effects (font (size 0.7 0.7) (thickness 0.15)) (justify left bottom))
    )
    (fp_text user "${REFERENCE}" (at 0 4.749) (layer "F.Fab") hide
        (effects (font (size 0.7 0.7) (thickness 0.15)) (justify left bottom))
    )
    (fp_text user "License: Apache-2.0" (at 0 7.15) (layer "F.Fab") hide
        (effects (font (size 0.7 0.7) (thickness 0.15)) (justify left bottom))
    )
    (pad "" np_thru_hole circle (at 0 0) (size 3 3) (drill 3) (layers "*.Cu" "*.Mask"))
  )

  (footprint "data-center-rdimm-ddr4-tester-footprints:R_0402_1005Metric" (layer "F.Cu")
    (at 224.295 86.75 180)
    (descr "Resistor SMD 0402")
    (tags "resistor SMD 0402")
    (property "Author" "Antmicro")
    (property "License" "Apache-2.0")
    (property "MPN" "CR0402-FX-1002GLF")
    (property "Manufacturer" "Bourns")
    (property "Sheetfile" "config-spi.kicad_sch")
    (property "Sheetname" "Config SPI flash")
    (property "Tolerance" "1%")
    (property "Val" "10k")
    (property "ki_description" "10k resistor in 0402 package with 1% tolerance")
    (attr smd)
    (fp_text reference "R193" (at 1.095 -2.52 180) (layer "F.SilkS")
        (effects (font (size 0.7 0.7) (thickness 0.15)) (justify left bottom))
    )
    (fp_text value "R_10k_0402" (at 0 1.4) (layer "F.Fab") hide
        (effects (font (size 0.7 0.7) (thickness 0.15)) (justify right bottom))
    )
    (fp_text user "License: Apache-2.0" (at -0.95 5.169) (layer "F.Fab") hide
        (effects (font (size 0.7 0.7) (thickness 0.15)) (justify right bottom))
    )
    (fp_text user "Author: Antmicro" (at -0.95 4.169) (layer "F.Fab") hide
        (effects (font (size 0.7 0.7) (thickness 0.15)) (justify right bottom))
    )
    (fp_text user "${REFERENCE}" (at -0.95 3.168) (layer "F.Fab") hide
        (effects (font (size 0.7 0.7) (thickness 0.15)) (justify right bottom))
    )
    (fp_rect (start -0.93 -0.47) (end 0.93 0.47)
      (stroke (width 0.05) (type solid)) (fill none) (layer "F.CrtYd"))
    (fp_rect (start -0.5 -0.25) (end 0.5 0.25)
      (stroke (width 0.15) (type solid)) (fill none) (layer "F.Fab"))
    (pad "1" smd roundrect (at -0.485 0 180) (size 0.59 0.64) (layers "F.Cu" "F.Paste" "F.Mask") (roundrect_rratio 0.25)
      (net 18 "MODE2") (pintype "passive"))
    (pad "2" smd roundrect (at 0.485 0 180) (size 0.59 0.64) (layers "F.Cu" "F.Paste" "F.Mask") (roundrect_rratio 0.25)
      (net 143 "3V3_SYS") (pintype "passive"))
  )

  (footprint "data-center-rdimm-ddr4-tester-footprints:R_0402_1005Metric" (layer "F.Cu")
    (at 219.85 122.35 90)
    (descr "Resistor SMD 0402")
    (tags "resistor SMD 0402")
    (property "Author" "Antmicro")
    (property "License" "Apache-2.0")
    (property "MPN" "CR0402-FX-1002GLF")
    (property "Manufacturer" "Bourns")
    (property "Sheetfile" "supply.kicad_sch")
    (property "Sheetname" "Supply")
    (property "Tolerance" "1%")
    (property "Val" "10k")
    (property "ki_description" "10k resistor in 0402 package with 1% tolerance")
    (attr smd)
    (fp_text reference "R123" (at -3.72 0.32 90) (layer "F.SilkS")
        (effects (font (size 0.7 0.7) (thickness 0.15)) (justify left bottom))
    )
    (fp_text value "R_10k_0402" (at 0 1.4 90) (layer "F.Fab") hide
        (effects (font (size 0.7 0.7) (thickness 0.15)) (justify left bottom))
    )
    (fp_text user "Author: Antmicro" (at -0.95 4.169 90) (layer "F.Fab") hide
        (effects (font (size 0.7 0.7) (thickness 0.15)) (justify left bottom))
    )
    (fp_text user "License: Apache-2.0" (at -0.95 5.169 90) (layer "F.Fab") hide
        (effects (font (size 0.7 0.7) (thickness 0.15)) (justify left bottom))
    )
    (fp_text user "${REFERENCE}" (at -0.95 3.168 90) (layer "F.Fab") hide
        (effects (font (size 0.7 0.7) (thickness 0.15)) (justify left bottom))
    )
    (fp_rect (start -0.93 -0.47) (end 0.93 0.47)
      (stroke (width 0.05) (type solid)) (fill none) (layer "F.CrtYd"))
    (fp_rect (start -0.5 -0.25) (end 0.5 0.25)
      (stroke (width 0.15) (type solid)) (fill none) (layer "F.Fab"))
    (pad "1" smd roundrect (at -0.485 0 90) (size 0.59 0.64) (layers "F.Cu" "F.Paste" "F.Mask") (roundrect_rratio 0.25)
      (net 167 "/Supply/SYS_EN") (pintype "passive"))
    (pad "2" smd roundrect (at 0.485 0 90) (size 0.59 0.64) (layers "F.Cu" "F.Paste" "F.Mask") (roundrect_rratio 0.25)
      (net 103 "VIN") (pintype "passive"))
  )

  (footprint "data-center-rdimm-ddr4-tester-footprints:C_0402_1005Metric" (layer "F.Cu")
    (at 156.175 104.425 -90)
    (descr "Capacitor SMD 0402")
    (tags "capacitor SMD 0402")
    (property "Author" "Antmicro")
    (property "DNP" "DNP")
    (property "Dielectric" "X5R")
    (property "License" "Apache-2.0")
    (property "MPN" "GRM155R61H104KE14D")
    (property "Manufacturer" "Murata")
    (property "Sheetfile" "ethernet.kicad_sch")
    (property "Sheetname" "Ethernet")
    (property "Val" "100n")
    (property "Voltage" "50V")
    (property "dnp" "")
    (property "exclude_from_bom" "")
    (property "ki_description" " ")
    (attr exclude_from_pos_files exclude_from_bom)
    (fp_text reference "C289" (at 3.685 -0.325 -90) (layer "F.SilkS")
        (effects (font (size 0.7 0.7) (thickness 0.15)) (justify left bottom))
    )
    (fp_text value "C_100n_0402" (at 0 1.4 -90) (layer "F.Fab") hide
        (effects (font (size 0.7 0.7) (thickness 0.15)) (justify left bottom))
    )
    (fp_text user "${REFERENCE}" (at -0.932 3.168 -90) (layer "F.Fab") hide
        (effects (font (size 0.7 0.7) (thickness 0.15)) (justify left bottom))
    )
    (fp_text user "License: Apache-2.0" (at -0.932 5.17 -90) (layer "F.Fab") hide
        (effects (font (size 0.7 0.7) (thickness 0.15)) (justify left bottom))
    )
    (fp_text user "Author: Antmicro" (at -0.932 4.17 -90) (layer "F.Fab") hide
        (effects (font (size 0.7 0.7) (thickness 0.15)) (justify left bottom))
    )
    (fp_rect (start -0.94 -0.47) (end 0.94 0.47)
      (stroke (width 0.05) (type solid)) (fill none) (layer "F.CrtYd"))
    (fp_rect (start -0.499 -0.249) (end 0.499 0.249)
      (stroke (width 0.15) (type solid)) (fill none) (layer "F.Fab"))
    (pad "1" smd roundrect (at -0.484 0 270) (size 0.59 0.64) (layers "F.Cu" "F.Paste" "F.Mask") (roundrect_rratio 0.25)
      (net 143 "3V3_SYS") (pintype "passive"))
    (pad "2" smd roundrect (at 0.484 0 270) (size 0.59 0.64) (layers "F.Cu" "F.Paste" "F.Mask") (roundrect_rratio 0.25)
      (net 9 "GND") (pintype "passive"))
  )

  (footprint "data-center-rdimm-ddr4-tester-footprints:RJ45_5-2337992-8_Horizontal" (layer "F.Cu")
    (at 159.785 118.116397)
    (property "Author" "Antmicro")
    (property "License" "Apache-2.0")
    (property "MPN" "5-2337992-8")
    (property "Manufacturer" "TE Connectivity")
    (property "Sheetfile" "ethernet.kicad_sch")
    (property "Sheetname" "Ethernet")
    (property "ki_description" "RJ45 Gigabit Ethernet Jack w/ Magnetics and PoE, Single Port, 802.3at Power over Ethernet")
    (property "ki_keywords" "RJ45 PoE Ethernet te connectivity magnetics gigabit power")
    (attr through_hole)
    (fp_text reference "J2" (at 5.165 -2.036397) (layer "F.SilkS")
        (effects (font (size 0.7 0.7) (thickness 0.15)) (justify left bottom))
    )
    (fp_text value "Bus_RJ45_5-2337992-8" (at -2.6 22) (layer "F.Fab") hide
        (effects (font (size 0.7 0.7) (thickness 0.15)) (justify left bottom))
    )
    (fp_text user "License: Apache-2.0" (at -2.644 26.2) (layer "F.Fab") hide
        (effects (font (size 0.7 0.7) (thickness 0.15)) (justify left bottom))
    )
    (fp_text user "${REFERENCE}" (at -2.644 23.4) (layer "F.Fab") hide
        (effects (font (size 0.7 0.7) (thickness 0.15)) (justify left bottom))
    )
    (fp_text user "Author: Antmicro" (at -2.644 24.8) (layer "F.Fab") hide
        (effects (font (size 0.7 0.7) (thickness 0.15)) (justify left bottom))
    )
    (fp_line (start -2.363 -1.845) (end -2.363 4.48)
      (stroke (width 0.15) (type solid)) (layer "F.SilkS"))
    (fp_line (start -2.363 7.217) (end -2.363 19.771)
      (stroke (width 0.15) (type solid)) (layer "F.SilkS"))
    (fp_line (start -2.363 19.771) (end 13.791 19.771)
      (stroke (width 0.15) (type solid)) (layer "F.SilkS"))
    (fp_line (start 13.791 -1.845) (end -2.363 -1.845)
      (stroke (width 0.15) (type solid)) (layer "F.SilkS"))
    (fp_line (start 13.791 4.48) (end 13.791 -1.845)
      (stroke (width 0.15) (type solid)) (layer "F.SilkS"))
    (fp_line (start 13.791 19.771) (end 13.791 7.217)
      (stroke (width 0.15) (type solid)) (layer "F.SilkS"))
    (fp_rect (start -2.4 -1.8) (end 13.9 19.999)
      (stroke (width 0.05) (type solid)) (fill none) (layer "F.CrtYd"))
    (fp_line (start -2.237 -1.718) (end -2.237 19.644)
      (stroke (width 0.15) (type solid)) (layer "F.Fab"))
    (fp_line (start -2.237 19.644) (end 13.665 19.644)
      (stroke (width 0.15) (type solid)) (layer "F.Fab"))
    (fp_line (start 13.665 -1.718) (end -2.237 -1.718)
      (stroke (width 0.15) (type solid)) (layer "F.Fab"))
    (fp_line (start 13.665 19.644) (end 13.665 -1.718)
      (stroke (width 0.15) (type solid)) (layer "F.Fab"))
    (pad "" np_thru_hole circle (at 0 8.9) (size 3.25 3.25) (drill 3.25) (layers "*.Cu" "*.Mask"))
    (pad "" np_thru_hole circle (at 11.429 8.9) (size 3.25 3.25) (drill 3.25) (layers "*.Cu" "*.Mask"))
    (pad "1" thru_hole circle (at 0 0) (size 1.397 1.397) (drill 0.889) (layers "*.Cu" "*.Mask")
      (net 631 "/Ethernet/INT_ETH1_P") (pinfunction "P1") (pintype "bidirectional"))
    (pad "2" thru_hole circle (at 1.269 2.539) (size 1.397 1.397) (drill 0.889) (layers "*.Cu" "*.Mask")
      (net 630 "/Ethernet/INT_ETH1_N") (pinfunction "P2") (pintype "bidirectional"))
    (pad "3" thru_hole circle (at 2.539 0) (size 1.397 1.397) (drill 0.889) (layers "*.Cu" "*.Mask")
      (net 568 "/Ethernet/INT_ETH2_P") (pinfunction "P3") (pintype "bidirectional"))
    (pad "4" thru_hole circle (at 3.809 2.539) (size 1.397 1.397) (drill 0.889) (layers "*.Cu" "*.Mask")
      (net 92 "Net-(J2-P4)") (pinfunction "P4") (pintype "bidirectional"))
    (pad "5" thru_hole circle (at 5.078 0) (size 1.397 1.397) (drill 0.889) (layers "*.Cu" "*.Mask")
      (net 94 "Net-(J2-P5)") (pinfunction "P5") (pintype "bidirectional"))
    (pad "6" thru_hole circle (at 6.349 2.539) (size 1.397 1.397) (drill 0.889) (layers "*.Cu" "*.Mask")
      (net 567 "/Ethernet/INT_ETH2_N") (pinfunction "P6") (pintype "bidirectional"))
    (pad "7" thru_hole circle (at 7.618 0) (size 1.397 1.397) (drill 0.889) (layers "*.Cu" "*.Mask")
      (net 559 "/Ethernet/INT_ETH3_P") (pinfunction "P7") (pintype "bidirectional"))
    (pad "8" thru_hole circle (at 8.89 2.539) (size 1.397 1.397) (drill 0.889) (layers "*.Cu" "*.Mask")
      (net 558 "/Ethernet/INT_ETH3_N") (pinfunction "P8") (pintype "bidirectional"))
    (pad "9" thru_hole circle (at 10.159 0) (size 1.397 1.397) (drill 0.889) (layers "*.Cu" "*.Mask")
      (net 548 "/Ethernet/INT_ETH4_P") (pinfunction "P9") (pintype "bidirectional"))
    (pad "10" thru_hole circle (at 11.429 2.539) (size 1.397 1.397) (drill 0.889) (layers "*.Cu" "*.Mask")
      (net 547 "/Ethernet/INT_ETH4_N") (pinfunction "P10") (pintype "bidirectional"))
    (pad "11" thru_hole circle (at 0 5.078) (size 1.397 1.397) (drill 0.889) (layers "*.Cu" "*.Mask")
      (net 605 "/Ethernet/PAIR_12") (pinfunction "VC1") (pintype "bidirectional"))
    (pad "12" thru_hole circle (at 2.539 6.339) (size 1.397 1.397) (drill 0.889) (layers "*.Cu" "*.Mask")
      (net 606 "/Ethernet/PAIR_36") (pinfunction "VC2") (pintype "bidirectional"))
    (pad "13" thru_hole circle (at 8.89 6.339) (size 1.397 1.397) (drill 0.889) (layers "*.Cu" "*.Mask")
      (net 607 "/Ethernet/PAIR_78") (pinfunction "VC3") (pintype "bidirectional"))
    (pad "14" thru_hole circle (at 11.429 5.07) (size 1.397 1.397) (drill 0.889) (layers "*.Cu" "*.Mask")
      (net 608 "/Ethernet/PAIR_910") (pinfunction "VC4") (pintype "bidirectional"))
    (pad "15" thru_hole circle (at -0.927 12.958) (size 1.524 1.524) (drill 1.016) (layers "*.Cu" "*.Mask")
      (net 112 "Net-(J2-LED_GRN+)") (pinfunction "LED_GRN+") (pintype "passive"))
    (pad "16" thru_hole circle (at 1.614 12.958) (size 1.524 1.524) (drill 1.016) (layers "*.Cu" "*.Mask")
      (net 546 "INT_LED_SPD") (pinfunction "LED_GRN-") (pintype "passive"))
    (pad "17" thru_hole circle (at 9.814 12.958) (size 1.524 1.524) (drill 1.016) (layers "*.Cu" "*.Mask")
      (net 113 "Net-(J2-LED_YEL+)") (pinfunction "LED_YEL+") (pintype "passive"))
    (pad "18" thru_hole circle (at 12.355 12.958) (size 1.524 1.524) (drill 1.016) (layers "*.Cu" "*.Mask")
      (net 537 "INT_LED_LINK") (pinfunction "LED_YEL-") (pintype "passive"))
    (pad "19" thru_hole circle (at -2.136 5.85) (size 2.1 2.1) (drill 1.6) (layers "*.Cu" "*.Mask")
      (net 862 "GNDS") (pinfunction "SHIELD") (pintype "passive"))
    (pad "20" thru_hole circle (at 13.563 5.85) (size 2.1082 2.1082) (drill 1.6002) (layers "*.Cu" "*.Mask")
      (net 862 "GNDS") (pinfunction "SHIELD") (pintype "passive"))
  )

  (footprint "data-center-rdimm-ddr4-tester-footprints:C_1206_3216Metric" (layer "F.Cu")
    (at 247.9 125.6 180)
    (descr "Capacitor SMD 1206")
    (tags "capacitor SMD 1206")
    (property "Author" "Antmicro")
    (property "Dielectric" "")
    (property "License" "Apache-2.0")
    (property "MPN" "C3216X5R1C476M160AB")
    (property "Manufacturer" "TDK")
    (property "Sheetfile" "fmc_hpc.kicad_sch")
    (property "Sheetname" "FMC HPC")
    (property "Val" "47u/16V")
    (property "Voltage" "")
    (property "ki_description" " ")
    (attr smd)
    (fp_text reference "C258" (at 1.47 -1.8 180) (layer "F.SilkS")
        (effects (font (size 0.7 0.7) (thickness 0.15)) (justify left bottom))
    )
    (fp_text value "C_47u_16V_1206" (at 0 2.1 180) (layer "F.Fab") hide
        (effects (font (size 0.7 0.7) (thickness 0.15)) (justify left bottom))
    )
    (fp_text user "License: Apache-2.0" (at -2.8 6.6 180) (layer "F.Fab") hide
        (effects (font (size 0.7 0.7) (thickness 0.15)) (justify left bottom))
    )
    (fp_text user "Author: Antmicro" (at -2.8 5.6 180) (layer "F.Fab") hide
        (effects (font (size 0.7 0.7) (thickness 0.15)) (justify left bottom))
    )
    (fp_text user "${REFERENCE}" (at -2.8 4.6 180) (layer "F.Fab") hide
        (effects (font (size 0.7 0.7) (thickness 0.15)) (justify left bottom))
    )
    (fp_line (start -2.625 -0.3) (end -2.625 0.3)
      (stroke (width 0.15) (type solid)) (layer "F.SilkS"))
    (fp_line (start 0.5 -0.9) (end -0.5 -0.9)
      (stroke (width 0.15) (type solid)) (layer "F.SilkS"))
    (fp_line (start 0.5 0.9) (end -0.5 0.9)
      (stroke (width 0.15) (type solid)) (layer "F.SilkS"))
    (fp_line (start 2.625 -0.3) (end 2.625 0.3)
      (stroke (width 0.15) (type solid)) (layer "F.SilkS"))
    (fp_rect (start -2.8 -1.15) (end 2.8 1.15)
      (stroke (width 0.05) (type solid)) (fill none) (layer "F.CrtYd"))
    (fp_rect (start -1.6 -0.8) (end 1.6 0.8)
      (stroke (width 0.15) (type solid)) (fill none) (layer "F.Fab"))
    (pad "1" smd rect (at -1.8 0 180) (size 1.5 1.8) (layers "F.Cu" "F.Paste" "F.Mask")
      (net 535 "12P0V") (pintype "passive"))
    (pad "2" smd rect (at 1.8 0 180) (size 1.5 1.8) (layers "F.Cu" "F.Paste" "F.Mask")
      (net 9 "GND") (pintype "passive"))
  )

  (footprint "data-center-rdimm-ddr4-tester-footprints:mounting-hole-3mm-NPTH" (layer "F.Cu")
    (at 110 49)
    (property "Author" "Antmicro")
    (property "License" "Apache-2.0")
    (property "MPN" "")
    (property "Manufacturer" "")
    (property "Sheetfile" "data-center-rdimm-ddr4-tester.kicad_sch")
    (property "Sheetname" "")
    (attr through_hole)
    (fp_text reference "MP4" (at 0 -1.8) (layer "F.SilkS") hide
        (effects (font (size 0.7 0.7) (thickness 0.15)) (justify left bottom))
    )
    (fp_text value "PCB_Mount_Hole_3mm_NPTH" (at 0 2.3) (layer "F.Fab") hide
        (effects (font (size 0.7 0.7) (thickness 0.15)) (justify left bottom))
    )
    (fp_text user "Author: Antmicro" (at 0 5.95) (layer "F.Fab") hide
        (effects (font (size 0.7 0.7) (thickness 0.15)) (justify left bottom))
    )
    (fp_text user "License: Apache-2.0" (at 0 7.15) (layer "F.Fab") hide
        (effects (font (size 0.7 0.7) (thickness 0.15)) (justify left bottom))
    )
    (fp_text user "${REFERENCE}" (at 0 4.749) (layer "F.Fab") hide
        (effects (font (size 0.7 0.7) (thickness 0.15)) (justify left bottom))
    )
    (pad "" np_thru_hole circle (at 0 0) (size 3 3) (drill 3) (layers "*.Cu" "*.Mask"))
  )

  (footprint "data-center-rdimm-ddr4-tester-footprints:TP_SMD_0.75mm" (layer "F.Cu")
    (at 250.7 122.5)
    (property "Author" "Antmicro")
    (property "License" "Apache-2.0")
    (property "MPN" "")
    (property "Manufacturer" "")
    (property "Sheetfile" "fmc_hpc.kicad_sch")
    (property "Sheetname" "FMC HPC")
    (property "ki_description" "Test Point 0.75mm")
    (attr exclude_from_pos_files)
    (fp_text reference "TP16" (at 0.51 0.35) (layer "F.SilkS")
        (effects (font (size 0.7 0.7) (thickness 0.15)) (justify left bottom))
    )
    (fp_text value "TP_0.75mm_SMD" (at 0 1.2) (layer "F.Fab") hide
        (effects (font (size 0.7 0.7) (thickness 0.15)) (justify left bottom))
    )
    (fp_text user "Author: Antmicro" (at -0.4 3.901) (layer "F.Fab") hide
        (effects (font (size 0.7 0.7) (thickness 0.15)) (justify left bottom))
    )
    (fp_text user "${REFERENCE}" (at -0.4 2.7) (layer "F.Fab") hide
        (effects (font (size 0.7 0.7) (thickness 0.15)) (justify left bottom))
    )
    (fp_text user "License: Apache-2.0" (at -0.4 5.101) (layer "F.Fab") hide
        (effects (font (size 0.7 0.7) (thickness 0.15)) (justify left bottom))
    )
    (pad "1" smd circle (at 0 0) (size 0.75 0.75) (layers "F.Cu" "F.Mask")
      (net 496 "Net-(J5B-VREF_{A_M2C})") (pinfunction "1") (pintype "passive"))
  )

  (footprint "data-center-rdimm-ddr4-tester-footprints:C_0402_1005Metric" (layer "F.Cu")
    (at 254.175 119.86)
    (descr "Capacitor SMD 0402")
    (tags "capacitor SMD 0402")
    (property "Author" "Antmicro")
    (property "Dielectric" "X5R")
    (property "License" "Apache-2.0")
    (property "MPN" "GRM155R61H104KE14D")
    (property "Manufacturer" "Murata")
    (property "Sheetfile" "fmc_hpc.kicad_sch")
    (property "Sheetname" "FMC HPC")
    (property "Val" "100n")
    (property "Voltage" "50V")
    (property "ki_description" " ")
    (attr smd)
    (fp_text reference "C259" (at -1.315 -1.58) (layer "F.SilkS")
        (effects (font (size 0.7 0.7) (thickness 0.15)) (justify left bottom))
    )
    (fp_text value "C_100n_0402" (at 0 1.4) (layer "F.Fab") hide
        (effects (font (size 0.7 0.7) (thickness 0.15)) (justify left bottom))
    )
    (fp_text user "Author: Antmicro" (at -0.932 4.17) (layer "F.Fab") hide
        (effects (font (size 0.7 0.7) (thickness 0.15)) (justify left bottom))
    )
    (fp_text user "License: Apache-2.0" (at -0.932 5.17) (layer "F.Fab") hide
        (effects (font (size 0.7 0.7) (thickness 0.15)) (justify left bottom))
    )
    (fp_text user "${REFERENCE}" (at -0.932 3.168) (layer "F.Fab") hide
        (effects (font (size 0.7 0.7) (thickness 0.15)) (justify left bottom))
    )
    (fp_rect (start -0.94 -0.47) (end 0.94 0.47)
      (stroke (width 0.05) (type solid)) (fill none) (layer "F.CrtYd"))
    (fp_rect (start -0.499 -0.249) (end 0.499 0.249)
      (stroke (width 0.15) (type solid)) (fill none) (layer "F.Fab"))
    (pad "1" smd roundrect (at -0.484 0) (size 0.59 0.64) (layers "F.Cu" "F.Paste" "F.Mask") (roundrect_rratio 0.25)
      (net 410 "/FMC HPC/GTX_TX0_C_P") (pintype "passive"))
    (pad "2" smd roundrect (at 0.484 0) (size 0.59 0.64) (layers "F.Cu" "F.Paste" "F.Mask") (roundrect_rratio 0.25)
      (net 411 "GTX_TX0_P") (pintype "passive"))
  )

  (footprint "data-center-rdimm-ddr4-tester-footprints:Mech_Lightpipe_Mentor_1296.2013" (layer "F.Cu")
    (at 243.15 128.84 180)
    (property "Author" "Antmicro")
    (property "License" "Apache-2.0")
    (property "MPN" "1296.2013")
    (property "Manufacturer" "MENTOR")
    (property "Sheetfile" "data-center-rdimm-ddr4-tester.kicad_sch")
    (property "Sheetname" "")
    (property "ki_description" "PCB Mounted 3-Way Right Angle LED Light Pipe, Tri-Level-Row Clear Dome Lens")
    (attr through_hole)
    (fp_text reference "M1" (at -1.53 -6.22 unlocked) (layer "F.SilkS")
        (effects (font (size 0.7 0.7) (thickness 0.15)) (justify left bottom))
    )
    (fp_text value "Mech_Lightpipe_Mentor_1296.2013" (at -1.75 6.25 180 unlocked) (layer "F.Fab") hide
        (effects (font (size 0.7 0.7) (thickness 0.15)) (justify left bottom))
    )
    (fp_text user "${REFERENCE}" (at -1.75 7.5 180) (layer "F.Fab") hide
        (effects (font (size 0.7 0.7) (thickness 0.15)) (justify left bottom))
    )
    (fp_text user "License: Apache-2.0" (at -1.75 10.25 180) (layer "F.Fab") hide
        (effects (font (size 0.7 0.7) (thickness 0.15)) (justify left bottom))
    )
    (fp_text user "Author: Antmicro" (at -1.75 8.75 180) (layer "F.Fab") hide
        (effects (font (size 0.7 0.7) (thickness 0.15)) (justify left bottom))
    )
    (fp_rect (start -1.508 -6.335) (end 1.507 5.289)
      (stroke (width 0.15) (type solid)) (fill none) (layer "F.SilkS"))
    (pad "" np_thru_hole circle (at 0 -4.96 180) (size 1.2 1.2) (drill 1.2) (layers "F&B.Cu" "*.Mask"))
    (pad "" np_thru_hole circle (at 0 4.24 180) (size 1.2 1.2) (drill 1.2) (layers "F&B.Cu" "*.Mask"))
  )

  (footprint "data-center-rdimm-ddr4-tester-footprints:R_0201" (layer "F.Cu")
    (at 157.06 104.29 -90)
    (descr "Resistor SMD 0201")
    (tags "resistor SMD 0201")
    (property "Author" "Antmicro")
    (property "License" "Apache-2.0")
    (property "MPN" "CR0201-FX-0R00GLF")
    (property "Manufacturer" "Bourns")
    (property "Sheetfile" "ethernet.kicad_sch")
    (property "Sheetname" "Ethernet")
    (property "Tolerance" "1%")
    (property "Val" "0R")
    (property "ki_description" "0R resistor in 0201 package with 1% tolerance")
    (attr smd)
    (fp_text reference "R99" (at -0.65 -0.31 -90) (layer "F.SilkS")
        (effects (font (size 0.7 0.7) (thickness 0.15)) (justify left bottom))
    )
    (fp_text value "R_0R_0201" (at 0 1.25 -90) (layer "F.Fab") hide
        (effects (font (size 0.7 0.7) (thickness 0.15)) (justify left bottom))
    )
    (fp_text user "Author: Antmicro" (at -0.71 5.25 -90) (layer "F.Fab") hide
        (effects (font (size 0.7 0.7) (thickness 0.15)) (justify left bottom))
    )
    (fp_text user "License: Apache-2.0" (at -0.71 4.25 -90) (layer "F.Fab") hide
        (effects (font (size 0.7 0.7) (thickness 0.15)) (justify left bottom))
    )
    (fp_text user "${REFERENCE}" (at -0.71 3.25 -90) (layer "F.Fab") hide
        (effects (font (size 0.7 0.7) (thickness 0.15)) (justify left bottom))
    )
    (fp_rect (start -0.71 -0.36) (end 0.71 0.36)
      (stroke (width 0.05) (type solid)) (fill none) (layer "F.CrtYd"))
    (fp_rect (start -0.3 -0.15) (end 0.298 0.148)
      (stroke (width 0.15) (type solid)) (fill none) (layer "F.Fab"))
    (pad "" smd roundrect (at -0.346 0 270) (size 0.318 0.36) (layers "F.Paste") (roundrect_rratio 0.25))
    (pad "" smd roundrect (at 0.344 0 270) (size 0.318 0.36) (layers "F.Paste") (roundrect_rratio 0.25))
    (pad "1" smd roundrect (at -0.32 0 270) (size 0.46 0.4) (layers "F.Cu" "F.Mask") (roundrect_rratio 0.25)
      (net 169 "/Ethernet/ETH2_P") (pintype "passive"))
    (pad "2" smd roundrect (at 0.32 0 270) (size 0.46 0.4) (layers "F.Cu" "F.Mask") (roundrect_rratio 0.25)
      (net 826 "/Ethernet/ETH2_BP_P") (pintype "passive"))
  )

  (footprint "data-center-rdimm-ddr4-tester-footprints:C_0402_1005Metric" (layer "F.Cu")
    (at 242.3 118.4 -90)
    (descr "Capacitor SMD 0402")
    (tags "capacitor SMD 0402")
    (property "Author" "Antmicro")
    (property "Dielectric" "X5R")
    (property "License" "Apache-2.0")
    (property "MPN" "GRM155R61H104KE14D")
    (property "Manufacturer" "Murata")
    (property "Sheetfile" "pcie.kicad_sch")
    (property "Sheetname" "FPGA banks 115-116")
    (property "Val" "100n")
    (property "Voltage" "50V")
    (property "ki_description" " ")
    (attr smd)
    (fp_text reference "C315" (at -0.84 -0.43 -90) (layer "F.SilkS")
        (effects (font (size 0.7 0.7) (thickness 0.15)) (justify left bottom))
    )
    (fp_text value "C_100n_0402" (at 0 1.4 -90) (layer "F.Fab") hide
        (effects (font (size 0.7 0.7) (thickness 0.15)) (justify left bottom))
    )
    (fp_text user "Author: Antmicro" (at -0.932 4.17 -90) (layer "F.Fab") hide
        (effects (font (size 0.7 0.7) (thickness 0.15)) (justify left bottom))
    )
    (fp_text user "License: Apache-2.0" (at -0.932 5.17 -90) (layer "F.Fab") hide
        (effects (font (size 0.7 0.7) (thickness 0.15)) (justify left bottom))
    )
    (fp_text user "${REFERENCE}" (at -0.932 3.168 -90) (layer "F.Fab") hide
        (effects (font (size 0.7 0.7) (thickness 0.15)) (justify left bottom))
    )
    (fp_rect (start -0.94 -0.47) (end 0.94 0.47)
      (stroke (width 0.05) (type solid)) (fill none) (layer "F.CrtYd"))
    (fp_rect (start -0.499 -0.249) (end 0.499 0.249)
      (stroke (width 0.15) (type solid)) (fill none) (layer "F.Fab"))
    (pad "1" smd roundrect (at -0.484 0 270) (size 0.59 0.64) (layers "F.Cu" "F.Paste" "F.Mask") (roundrect_rratio 0.25)
      (net 885 "/FPGA banks 115-116/GTR_REFCLK2_P") (pintype "passive"))
    (pad "2" smd roundrect (at 0.484 0 270) (size 0.59 0.64) (layers "F.Cu" "F.Paste" "F.Mask") (roundrect_rratio 0.25)
      (net 893 "GTR_REFCLK2_C_P") (pintype "passive"))
  )

  (footprint "data-center-rdimm-ddr4-tester-footprints:C_0402_1005Metric" (layer "F.Cu")
    (at 243.3 118.4 -90)
    (descr "Capacitor SMD 0402")
    (tags "capacitor SMD 0402")
    (property "Author" "Antmicro")
    (property "Dielectric" "X5R")
    (property "License" "Apache-2.0")
    (property "MPN" "GRM155R61H104KE14D")
    (property "Manufacturer" "Murata")
    (property "Sheetfile" "pcie.kicad_sch")
    (property "Sheetname" "FPGA banks 115-116")
    (property "Val" "100n")
    (property "Voltage" "50V")
    (property "ki_description" " ")
    (attr smd)
    (fp_text reference "C316" (at -0.84 -0.4 -90) (layer "F.SilkS")
        (effects (font (size 0.7 0.7) (thickness 0.15)) (justify left bottom))
    )
    (fp_text value "C_100n_0402" (at 0 1.4 -90) (layer "F.Fab") hide
        (effects (font (size 0.7 0.7) (thickness 0.15)) (justify left bottom))
    )
    (fp_text user "${REFERENCE}" (at -0.932 3.168 -90) (layer "F.Fab") hide
        (effects (font (size 0.7 0.7) (thickness 0.15)) (justify left bottom))
    )
    (fp_text user "License: Apache-2.0" (at -0.932 5.17 -90) (layer "F.Fab") hide
        (effects (font (size 0.7 0.7) (thickness 0.15)) (justify left bottom))
    )
    (fp_text user "Author: Antmicro" (at -0.932 4.17 -90) (layer "F.Fab") hide
        (effects (font (size 0.7 0.7) (thickness 0.15)) (justify left bottom))
    )
    (fp_rect (start -0.94 -0.47) (end 0.94 0.47)
      (stroke (width 0.05) (type solid)) (fill none) (layer "F.CrtYd"))
    (fp_rect (start -0.499 -0.249) (end 0.499 0.249)
      (stroke (width 0.15) (type solid)) (fill none) (layer "F.Fab"))
    (pad "1" smd roundrect (at -0.484 0 270) (size 0.59 0.64) (layers "F.Cu" "F.Paste" "F.Mask") (roundrect_rratio 0.25)
      (net 886 "/FPGA banks 115-116/GTR_REFCLK2_N") (pintype "passive"))
    (pad "2" smd roundrect (at 0.484 0 270) (size 0.59 0.64) (layers "F.Cu" "F.Paste" "F.Mask") (roundrect_rratio 0.25)
      (net 894 "GTR_REFCLK2_C_N") (pintype "passive"))
  )

  (footprint "data-center-rdimm-ddr4-tester-footprints:C_0402_1005Metric" (layer "F.Cu")
    (at 153.1 110.615 -90)
    (descr "Capacitor SMD 0402")
    (tags "capacitor SMD 0402")
    (property "Author" "Antmicro")
    (property "DNP" "DNP")
    (property "Dielectric" "")
    (property "License" "Apache-2.0")
    (property "MPN" "GRM155R61A475MEAAD")
    (property "Manufacturer" "Murata")
    (property "Sheetfile" "ethernet.kicad_sch")
    (property "Sheetname" "Ethernet")
    (property "Val" "4u7")
    (property "Voltage" "")
    (property "dnp" "")
    (property "exclude_from_bom" "")
    (property "ki_description" " ")
    (attr exclude_from_pos_files exclude_from_bom)
    (fp_text reference "C230" (at 1.425 0.53 -90) (layer "F.SilkS")
        (effects (font (size 0.7 0.7) (thickness 0.15)) (justify left bottom))
    )
    (fp_text value "C_4u7_0402" (at 0 1.4 -90) (layer "F.Fab") hide
        (effects (font (size 0.7 0.7) (thickness 0.15)) (justify left bottom))
    )
    (fp_text user "License: Apache-2.0" (at -0.932 5.17 -90) (layer "F.Fab") hide
        (effects (font (size 0.7 0.7) (thickness 0.15)) (justify left bottom))
    )
    (fp_text user "Author: Antmicro" (at -0.932 4.17 -90) (layer "F.Fab") hide
        (effects (font (size 0.7 0.7) (thickness 0.15)) (justify left bottom))
    )
    (fp_text user "${REFERENCE}" (at -0.932 3.168 -90) (layer "F.Fab") hide
        (effects (font (size 0.7 0.7) (thickness 0.15)) (justify left bottom))
    )
    (fp_rect (start -0.94 -0.47) (end 0.94 0.47)
      (stroke (width 0.05) (type solid)) (fill none) (layer "F.CrtYd"))
    (fp_rect (start -0.499 -0.249) (end 0.499 0.249)
      (stroke (width 0.15) (type solid)) (fill none) (layer "F.Fab"))
    (pad "1" smd roundrect (at -0.484 0 270) (size 0.59 0.64) (layers "F.Cu" "F.Paste" "F.Mask") (roundrect_rratio 0.25)
      (net 143 "3V3_SYS") (pintype "passive"))
    (pad "2" smd roundrect (at 0.484 0 270) (size 0.59 0.64) (layers "F.Cu" "F.Paste" "F.Mask") (roundrect_rratio 0.25)
      (net 9 "GND") (pintype "passive"))
  )

  (footprint "data-center-rdimm-ddr4-tester-footprints:R_0402_1005Metric" (layer "F.Cu")
    (at 244.772901 119.82 180)
    (descr "Resistor SMD 0402")
    (tags "resistor SMD 0402")
    (property "Author" "Antmicro")
    (property "License" "Apache-2.0")
    (property "MPN" "CR0402-FX-33R0GLF")
    (property "Manufacturer" "Bourns")
    (property "Sheetfile" "fmc_hpc.kicad_sch")
    (property "Sheetname" "FMC HPC")
    (property "Tolerance" "1%")
    (property "Val" "33R")
    (property "ki_description" "33R resistor in 0402 package with 1% tolerance")
    (attr smd)
    (fp_text reference "R151" (at 0.57 1.46 180) (layer "F.SilkS")
        (effects (font (size 0.7 0.7) (thickness 0.15)) (justify left bottom))
    )
    (fp_text value "R_33R_0402" (at 0 1.4 180) (layer "F.Fab") hide
        (effects (font (size 0.7 0.7) (thickness 0.15)) (justify left bottom))
    )
    (fp_text user "${REFERENCE}" (at -0.95 3.168 180) (layer "F.Fab") hide
        (effects (font (size 0.7 0.7) (thickness 0.15)) (justify left bottom))
    )
    (fp_text user "License: Apache-2.0" (at -0.95 5.169 180) (layer "F.Fab") hide
        (effects (font (size 0.7 0.7) (thickness 0.15)) (justify left bottom))
    )
    (fp_text user "Author: Antmicro" (at -0.95 4.169 180) (layer "F.Fab") hide
        (effects (font (size 0.7 0.7) (thickness 0.15)) (justify left bottom))
    )
    (fp_rect (start -0.93 -0.47) (end 0.93 0.47)
      (stroke (width 0.05) (type solid)) (fill none) (layer "F.CrtYd"))
    (fp_rect (start -0.5 -0.25) (end 0.5 0.25)
      (stroke (width 0.15) (type solid)) (fill none) (layer "F.Fab"))
    (pad "1" smd roundrect (at -0.485 0 180) (size 0.59 0.64) (layers "F.Cu" "F.Paste" "F.Mask") (roundrect_rratio 0.25)
      (net 904 "/FMC HPC/GTR_REFCLK2_R_N") (pintype "passive"))
    (pad "2" smd roundrect (at 0.485 0 180) (size 0.59 0.64) (layers "F.Cu" "F.Paste" "F.Mask") (roundrect_rratio 0.25)
      (net 894 "GTR_REFCLK2_C_N") (pintype "passive"))
  )

  (footprint "data-center-rdimm-ddr4-tester-footprints:R_1206_3216Metric" (layer "F.Cu")
    (at 119.65 83.5 90)
    (property "Author" "Antmicro")
    (property "License" "Apache-2.0")
    (property "MPN" "CR1206-J/-000ELF")
    (property "Manufacturer" "Bourns")
    (property "Sheetfile" "supply.kicad_sch")
    (property "Sheetname" "Supply")
    (property "Tolerance" "1%")
    (property "Val" "0R005")
    (property "ki_description" "0R005 resistor in 1206 package with 1% tolerance")
    (attr smd)
    (fp_text reference "R199" (at -1.26 -1.14 90) (layer "F.SilkS")
        (effects (font (size 0.7 0.7) (thickness 0.15)) (justify left bottom))
    )
    (fp_text value "R_0R005_1206" (at 0 2 90) (layer "F.Fab") hide
        (effects (font (size 0.7 0.7) (thickness 0.15)) (justify left bottom))
    )
    (fp_text user "${REFERENCE}" (at -2.401 3.5 90) (layer "F.Fab") hide
        (effects (font (size 0.7 0.7) (thickness 0.15)) (justify left bottom))
    )
    (fp_text user "License: Apache-2.0" (at -2.401 6.3 90) (layer "F.Fab") hide
        (effects (font (size 0.7 0.7) (thickness 0.15)) (justify left bottom))
    )
    (fp_text user "Author: Antmicro" (at -2.401 4.899 90) (layer "F.Fab") hide
        (effects (font (size 0.7 0.7) (thickness 0.15)) (justify left bottom))
    )
    (fp_line (start 0 -0.902) (end -0.5 -0.902)
      (stroke (width 0.15) (type solid)) (layer "F.SilkS"))
    (fp_line (start 0 -0.902) (end 0.498 -0.902)
      (stroke (width 0.15) (type solid)) (layer "F.SilkS"))
    (fp_line (start 0 0.9) (end -0.5 0.9)
      (stroke (width 0.15) (type solid)) (layer "F.SilkS"))
    (fp_line (start 0 0.9) (end 0.498 0.9)
      (stroke (width 0.15) (type solid)) (layer "F.SilkS"))
    (fp_rect (start -2.25 -1.05) (end 2.25 1.05)
      (stroke (width 0.05) (type solid)) (fill none) (layer "F.CrtYd"))
    (fp_line (start -1.601 -0.802) (end -1.601 0.8)
      (stroke (width 0.15) (type solid)) (layer "F.Fab"))
    (fp_line (start -1.601 -0.802) (end 1.6 -0.802)
      (stroke (width 0.15) (type solid)) (layer "F.Fab"))
    (fp_line (start -1.601 0.8) (end 1.6 0.8)
      (stroke (width 0.15) (type solid)) (layer "F.Fab"))
    (fp_line (start 1.6 -0.802) (end 1.6 0.8)
      (stroke (width 0.15) (type solid)) (layer "F.Fab"))
    (pad "1" smd roundrect (at -1.5 0 90) (size 1.2 1.8) (layers "F.Cu" "F.Paste" "F.Mask") (roundrect_rratio 0.15)
      (net 301 "VDD1V2") (pintype "passive"))
    (pad "2" smd roundrect (at 1.499 0 90) (size 1.2 1.8) (layers "F.Cu" "F.Paste" "F.Mask") (roundrect_rratio 0.15)
      (net 77 "VDDQ") (pintype "passive"))
  )

  (footprint "data-center-rdimm-ddr4-tester-footprints:LED_0603_1608Metric_G" (layer "F.Cu")
    (at 202.8 111.9)
    (descr "LED SMD 0603 Green")
    (tags "LED SMD 0603 Green")
    (property "Author" "Antmicro")
    (property "License" "Apache-2.0")
    (property "MPN" "KP-1608CGCK")
    (property "Manufacturer" "Kingbright")
    (property "Sheetfile" "ethernet.kicad_sch")
    (property "Sheetname" "Ethernet")
    (attr smd)
    (fp_text reference "D15" (at -1 -0.72) (layer "F.SilkS")
        (effects (font (size 0.7 0.7) (thickness 0.15)) (justify left bottom))
    )
    (fp_text value "LED_G_0603_KP-1608CGCK" (at 0 1.6) (layer "F.Fab") hide
        (effects (font (size 0.7 0.7) (thickness 0.15)) (justify left bottom))
    )
    (fp_text user "Author: Antmicro" (at -1.31 4.769) (layer "F.Fab") hide
        (effects (font (size 0.7 0.7) (thickness 0.15)) (justify left bottom))
    )
    (fp_text user "${REFERENCE}" (at -1.31 3.769) (layer "F.Fab") hide
        (effects (font (size 0.7 0.7) (thickness 0.15)) (justify left bottom))
    )
    (fp_text user "License: Apache-2.0" (at -1.31 5.769) (layer "F.Fab") hide
        (effects (font (size 0.7 0.7) (thickness 0.15)) (justify left bottom))
    )
    (fp_line (start -0.27 -0.35) (end 0.27 -0.35)
      (stroke (width 0.15) (type solid)) (layer "F.SilkS"))
    (fp_line (start -0.27 0.351) (end 0.27 0.351)
      (stroke (width 0.15) (type solid)) (layer "F.SilkS"))
    (fp_line (start -0.106328 -0.200008) (end -0.106328 0.199992)
      (stroke (width 0.1) (type solid)) (layer "F.SilkS"))
    (fp_line (start -0.106328 -0.200008) (end 0.093672 -0.000008)
      (stroke (width 0.1) (type solid)) (layer "F.SilkS"))
    (fp_line (start -0.106328 -0.000008) (end -0.29 0)
      (stroke (width 0.1) (type solid)) (layer "F.SilkS"))
    (fp_line (start 0.093672 -0.200008) (end 0.093672 0.199992)
      (stroke (width 0.1) (type solid)) (layer "F.SilkS"))
    (fp_line (start 0.093672 -0.000008) (end -0.106328 0.199992)
      (stroke (width 0.1) (type solid)) (layer "F.SilkS"))
    (fp_line (start 0.093672 -0.000008) (end 0.293672 -0.000008)
      (stroke (width 0.1) (type solid)) (layer "F.SilkS"))
    (fp_line (start 1.25 0.32) (end 1.25 -0.32)
      (stroke (width 0.15) (type solid)) (layer "F.SilkS"))
    (fp_rect (start 1.26 0.65) (end -1.26 -0.65)
      (stroke (width 0.05) (type solid)) (fill none) (layer "F.CrtYd"))
    (fp_line (start -0.599 0) (end -0.201 0)
      (stroke (width 0.15) (type solid)) (layer "F.Fab"))
    (fp_line (start -0.201 -0.2) (end -0.201 0)
      (stroke (width 0.15) (type solid)) (layer "F.Fab"))
    (fp_line (start -0.201 0) (end -0.201 0.202)
      (stroke (width 0.15) (type solid)) (layer "F.Fab"))
    (fp_line (start -0.201 0.202) (end 0.101 0)
      (stroke (width 0.15) (type solid)) (layer "F.Fab"))
    (fp_line (start 0.101 0) (end -0.201 -0.2)
      (stroke (width 0.15) (type solid)) (layer "F.Fab"))
    (fp_line (start 0.199 -0.2) (end 0.199 -0.1)
      (stroke (width 0.15) (type solid)) (layer "F.Fab"))
    (fp_line (start 0.199 0) (end 0.597 0)
      (stroke (width 0.15) (type solid)) (layer "F.Fab"))
    (fp_line (start 0.199 0.202) (end 0.199 -0.1)
      (stroke (width 0.15) (type solid)) (layer "F.Fab"))
    (fp_rect (start -0.848 -0.4) (end 0.85 0.402)
      (stroke (width 0.15) (type solid)) (fill none) (layer "F.Fab"))
    (pad "1" smd rect (at -0.75 0 180) (size 0.8 0.8) (layers "F.Cu" "F.Paste" "F.Mask")
      (net 609 "Net-(D15-Pad1)") (pinfunction "1") (pintype "passive"))
    (pad "2" smd rect (at 0.75 0 180) (size 0.8 0.8) (layers "F.Cu" "F.Paste" "F.Mask")
      (net 604 "GNDD") (pinfunction "2") (pintype "passive"))
  )

  (footprint "data-center-rdimm-ddr4-tester-footprints:R_0402_1005Metric" (layer "F.Cu")
    (at 256.2 90.3)
    (descr "Resistor SMD 0402")
    (tags "resistor SMD 0402")
    (property "Author" "Antmicro")
    (property "License" "Apache-2.0")
    (property "MPN" "CR0402-FX-4701GLF")
    (property "Manufacturer" "Bourns")
    (property "Sheetfile" "fmc_hpc.kicad_sch")
    (property "Sheetname" "FMC HPC")
    (property "Tolerance" "1%")
    (property "Val" "4k7")
    (property "ki_description" "4k7 resistor in 0402 package with 1% tolerance")
    (attr smd)
    (fp_text reference "R155" (at 0.66 0.35) (layer "F.SilkS")
        (effects (font (size 0.7 0.7) (thickness 0.15)) (justify left bottom))
    )
    (fp_text value "R_4k7_0402" (at 0 1.4) (layer "F.Fab") hide
        (effects (font (size 0.7 0.7) (thickness 0.15)) (justify left bottom))
    )
    (fp_text user "${REFERENCE}" (at -0.95 3.168) (layer "F.Fab") hide
        (effects (font (size 0.7 0.7) (thickness 0.15)) (justify left bottom))
    )
    (fp_text user "License: Apache-2.0" (at -0.95 5.169) (layer "F.Fab") hide
        (effects (font (size 0.7 0.7) (thickness 0.15)) (justify left bottom))
    )
    (fp_text user "Author: Antmicro" (at -0.95 4.169) (layer "F.Fab") hide
        (effects (font (size 0.7 0.7) (thickness 0.15)) (justify left bottom))
    )
    (fp_rect (start -0.93 -0.47) (end 0.93 0.47)
      (stroke (width 0.05) (type solid)) (fill none) (layer "F.CrtYd"))
    (fp_rect (start -0.5 -0.25) (end 0.5 0.25)
      (stroke (width 0.15) (type solid)) (fill none) (layer "F.Fab"))
    (pad "1" smd roundrect (at -0.485 0) (size 0.59 0.64) (layers "F.Cu" "F.Paste" "F.Mask") (roundrect_rratio 0.25)
      (net 143 "3V3_SYS") (pintype "passive"))
    (pad "2" smd roundrect (at 0.485 0) (size 0.59 0.64) (layers "F.Cu" "F.Paste" "F.Mask") (roundrect_rratio 0.25)
      (net 907 "FMC_SCL_3V3") (pintype "passive"))
  )

  (footprint "data-center-rdimm-ddr4-tester-footprints:R_0402_1005Metric" (layer "F.Cu")
    (at 154.2 127.515 -90)
    (descr "Resistor SMD 0402")
    (tags "resistor SMD 0402")
    (property "Author" "Antmicro")
    (property "License" "Apache-2.0")
    (property "MPN" "CR0402-FX-3300GLF")
    (property "Manufacturer" "Bourns")
    (property "Sheetfile" "interfaces.kicad_sch")
    (property "Sheetname" "Interfaces")
    (property "Tolerance" "1%")
    (property "Val" "330R")
    (property "ki_description" "330R resistor in 0402 package with 1% tolerance")
    (attr smd)
    (fp_text reference "R125" (at 1.035 -1.24 -90) (layer "F.SilkS")
        (effects (font (size 0.7 0.7) (thickness 0.15)) (justify left bottom))
    )
    (fp_text value "R_330R_0402" (at 0 1.4 -90) (layer "F.Fab") hide
        (effects (font (size 0.7 0.7) (thickness 0.15)) (justify left bottom))
    )
    (fp_text user "${REFERENCE}" (at -0.95 3.168 -90) (layer "F.Fab") hide
        (effects (font (size 0.7 0.7) (thickness 0.15)) (justify left bottom))
    )
    (fp_text user "Author: Antmicro" (at -0.95 4.169 -90) (layer "F.Fab") hide
        (effects (font (size 0.7 0.7) (thickness 0.15)) (justify left bottom))
    )
    (fp_text user "License: Apache-2.0" (at -0.95 5.169 -90) (layer "F.Fab") hide
        (effects (font (size 0.7 0.7) (thickness 0.15)) (justify left bottom))
    )
    (fp_rect (start -0.93 -0.47) (end 0.93 0.47)
      (stroke (width 0.05) (type solid)) (fill none) (layer "F.CrtYd"))
    (fp_rect (start -0.5 -0.25) (end 0.5 0.25)
      (stroke (width 0.15) (type solid)) (fill none) (layer "F.Fab"))
    (pad "1" smd roundrect (at -0.485 0 270) (size 0.59 0.64) (layers "F.Cu" "F.Paste" "F.Mask") (roundrect_rratio 0.25)
      (net 9 "GND") (pintype "passive"))
    (pad "2" smd roundrect (at 0.485 0 270) (size 0.59 0.64) (layers "F.Cu" "F.Paste" "F.Mask") (roundrect_rratio 0.25)
      (net 862 "GNDS") (pintype "passive"))
  )

  (footprint "data-center-rdimm-ddr4-tester-footprints:C_0402_1005Metric" (layer "F.Cu")
    (at 256.18 84.261)
    (descr "Capacitor SMD 0402")
    (tags "capacitor SMD 0402")
    (property "Author" "Antmicro")
    (property "Dielectric" "X5R")
    (property "License" "Apache-2.0")
    (property "MPN" "GRM155R61H104KE14D")
    (property "Manufacturer" "Murata")
    (property "Sheetfile" "fmc_hpc.kicad_sch")
    (property "Sheetname" "FMC HPC")
    (property "Val" "100n")
    (property "Voltage" "50V")
    (property "ki_description" " ")
    (attr smd)
    (fp_text reference "C274" (at 0.69 0.409) (layer "F.SilkS")
        (effects (font (size 0.7 0.7) (thickness 0.15)) (justify left bottom))
    )
    (fp_text value "C_100n_0402" (at 0 1.4) (layer "F.Fab") hide
        (effects (font (size 0.7 0.7) (thickness 0.15)) (justify left bottom))
    )
    (fp_text user "License: Apache-2.0" (at -0.932 5.17) (layer "F.Fab") hide
        (effects (font (size 0.7 0.7) (thickness 0.15)) (justify left bottom))
    )
    (fp_text user "Author: Antmicro" (at -0.932 4.17) (layer "F.Fab") hide
        (effects (font (size 0.7 0.7) (thickness 0.15)) (justify left bottom))
    )
    (fp_text user "${REFERENCE}" (at -0.932 3.168) (layer "F.Fab") hide
        (effects (font (size 0.7 0.7) (thickness 0.15)) (justify left bottom))
    )
    (fp_rect (start -0.94 -0.47) (end 0.94 0.47)
      (stroke (width 0.05) (type solid)) (fill none) (layer "F.CrtYd"))
    (fp_rect (start -0.499 -0.249) (end 0.499 0.249)
      (stroke (width 0.15) (type solid)) (fill none) (layer "F.Fab"))
    (pad "1" smd roundrect (at -0.484 0) (size 0.59 0.64) (layers "F.Cu" "F.Paste" "F.Mask") (roundrect_rratio 0.25)
      (net 525 "/FMC HPC/GTX_TX7_C_N") (pintype "passive"))
    (pad "2" smd roundrect (at 0.484 0) (size 0.59 0.64) (layers "F.Cu" "F.Paste" "F.Mask") (roundrect_rratio 0.25)
      (net 526 "GTX_TX7_N") (pintype "passive"))
  )

  (footprint "data-center-rdimm-ddr4-tester-footprints:PinHeader_2x7_P2mm_SMD_Shrouded_no-locator" (layer "F.Cu")
    (at 235.68 79.45 90)
    (descr "Pin Header 2x7 SMD Shrouded no-locator")
    (property "Author" "Antmicro")
    (property "DNP" "DNP")
    (property "License" "Apache-2.0")
    (property "MPN" "878321412")
    (property "Manufacturer" "Molex")
    (property "Sheetfile" "config-spi.kicad_sch")
    (property "Sheetname" "Config SPI flash")
    (property "dnp" "")
    (property "exclude_from_bom" "")
    (property "ki_description" "Pin Header, Signal, Wire-to-Board, 2 mm, 2 Rows, 14 Contacts, Surface Mount Straight")
    (property "ki_keywords" "PINSTRIP, HEADER ")
    (attr exclude_from_pos_files exclude_from_bom)
    (fp_text reference "J1" (at 8.86 -3.48) (layer "F.SilkS")
        (effects (font (size 0.7 0.7) (thickness 0.15)) (justify left bottom))
    )
    (fp_text value "PinHeader_2x7_P2mm_SMD_Shrouded_no-locator" (at 0 5.038 90) (layer "F.Fab")
        (effects (font (size 0.7 0.7) (thickness 0.15)) (justify left bottom))
    )
    (fp_text user "License: Apache-2.0" (at -8.933 7.038 90) (layer "F.Fab") hide
        (effects (font (size 0.7 0.7) (thickness 0.15)) (justify left bottom))
    )
    (fp_text user "Author: Antmicro" (at -8.933 8.237 90) (layer "F.Fab") hide
        (effects (font (size 0.7 0.7) (thickness 0.15)) (justify left bottom))
    )
    (fp_text user "${REFERENCE}" (at -8.933 9.438 90) (layer "F.Fab") hide
        (effects (font (size 0.7 0.7) (thickness 0.15)) (justify left bottom))
    )
    (fp_line (start -8.5 -3.301) (end -8.5 -2.801)
      (stroke (width 0.15) (type solid)) (layer "F.SilkS"))
    (fp_line (start -8.5 -3.301) (end -8 -3.301)
      (stroke (width 0.15) (type solid)) (layer "F.SilkS"))
    (fp_line (start -8.5 3.297) (end -8.5 2.797)
      (stroke (width 0.15) (type solid)) (layer "F.SilkS"))
    (fp_line (start -8.5 3.297) (end -8 3.297)
      (stroke (width 0.15) (type solid)) (layer "F.SilkS"))
    (fp_line (start -1.397 2.41) (end -1.397 2.91)
      (stroke (width 0.15) (type solid)) (layer "F.SilkS"))
    (fp_line (start -1.397 2.41) (end -0.9 2.41)
      (stroke (width 0.15) (type solid)) (layer "F.SilkS"))
    (fp_line (start 1.394 2.418) (end 0.897 2.418)
      (stroke (width 0.15) (type solid)) (layer "F.SilkS"))
    (fp_line (start 1.394 2.418) (end 1.394 2.918)
      (stroke (width 0.15) (type solid)) (layer "F.SilkS"))
    (fp_line (start 8.499 -3.301) (end 7.998 -3.301)
      (stroke (width 0.15) (type solid)) (layer "F.SilkS"))
    (fp_line (start 8.499 -3.301) (end 8.499 -2.801)
      (stroke (width 0.15) (type solid)) (layer "F.SilkS"))
    (fp_line (start 8.499 3.297) (end 7.998 3.297)
      (stroke (width 0.15) (type solid)) (layer "F.SilkS"))
    (fp_line (start 8.499 3.297) (end 8.499 2.797)
      (stroke (width 0.15) (type solid)) (layer "F.SilkS"))
    (fp_circle (center -6.8 3.4) (end -6.748 3.4)
      (stroke (width 0.15) (type solid)) (fill solid) (layer "F.SilkS"))
    (fp_rect (start -8.7 -3.7) (end 8.7 3.7)
      (stroke (width 0.05) (type solid)) (fill none) (layer "F.CrtYd"))
    (fp_line (start -8.325 -3.15) (end 8.323 -3.15)
      (stroke (width 0.15) (type solid)) (layer "F.Fab"))
    (fp_line (start -8.325 3.148) (end -8.325 -3.15)
      (stroke (width 0.15) (type solid)) (layer "F.Fab"))
    (fp_line (start -8.325 3.148) (end -1.397 3.148)
      (stroke (width 0.15) (type solid)) (layer "F.Fab"))
    (fp_line (start -1.397 2.41) (end -1.397 3.14)
      (stroke (width 0.15) (type solid)) (layer "F.Fab"))
    (fp_line (start -1.397 2.41) (end 1.394 2.41)
      (stroke (width 0.15) (type solid)) (layer "F.Fab"))
    (fp_line (start 1.394 2.41) (end 1.394 3.14)
      (stroke (width 0.15) (type solid)) (layer "F.Fab"))
    (fp_line (start 1.394 3.148) (end 8.323 3.148)
      (stroke (width 0.15) (type solid)) (layer "F.Fab"))
    (fp_line (start 8.323 3.148) (end 8.323 -3.15)
      (stroke (width 0.15) (type solid)) (layer "F.Fab"))
    (pad "1" smd rect (at -6 2.128 90) (size 1 2.75) (layers "F.Cu" "F.Paste" "F.Mask")
      (net 9 "GND") (pintype "passive"))
    (pad "2" smd rect (at -6 -2.13 90) (size 1 2.75) (layers "F.Cu" "F.Paste" "F.Mask")
      (net 143 "3V3_SYS") (pintype "passive"))
    (pad "3" smd rect (at -4 2.128 90) (size 1 2.75) (layers "F.Cu" "F.Paste" "F.Mask")
      (net 9 "GND") (pintype "passive"))
    (pad "4" smd rect (at -4 -2.13 90) (size 1 2.75) (layers "F.Cu" "F.Paste" "F.Mask")
      (net 13 "TMS_JTAG") (pintype "passive"))
    (pad "5" smd rect (at -2 2.128 90) (size 1 2.75) (layers "F.Cu" "F.Paste" "F.Mask")
      (net 9 "GND") (pintype "passive"))
    (pad "6" smd rect (at -2 -2.13 90) (size 1 2.75) (layers "F.Cu" "F.Paste" "F.Mask")
      (net 12 "TCK_JTAG") (pintype "passive"))
    (pad "7" smd rect (at 0 2.128 90) (size 1 2.75) (layers "F.Cu" "F.Paste" "F.Mask")
      (net 9 "GND") (pintype "passive"))
    (pad "8" smd rect (at 0 -2.13 90) (size 1 2.75) (layers "F.Cu" "F.Paste" "F.Mask")
      (net 15 "TDO_JTAG") (pintype "passive"))
    (pad "9" smd rect (at 1.999 2.128 90) (size 1 2.75) (layers "F.Cu" "F.Paste" "F.Mask")
      (net 9 "GND") (pintype "passive"))
    (pad "10" smd rect (at 1.999 -2.13 90) (size 1 2.75) (layers "F.Cu" "F.Paste" "F.Mask")
      (net 14 "TDI_JTAG") (pintype "passive"))
    (pad "11" smd rect (at 3.999 2.128 90) (size 1 2.75) (layers "F.Cu" "F.Paste" "F.Mask")
      (net 9 "GND") (pintype "passive"))
    (pad "12" smd rect (at 3.999 -2.13 90) (size 1 2.75) (layers "F.Cu" "F.Paste" "F.Mask")
      (net 380 "unconnected-(J1-Pad12)") (pintype "passive+no_connect"))
    (pad "13" smd rect (at 5.998 2.128 90) (size 1 2.75) (layers "F.Cu" "F.Paste" "F.Mask")
      (net 9 "GND") (pintype "passive"))
    (pad "14" smd rect (at 5.998 -2.13 90) (size 1 2.75) (layers "F.Cu" "F.Paste" "F.Mask")
      (net 379 "unconnected-(J1-Pad14)") (pintype "passive+no_connect"))
  )

  (footprint "data-center-rdimm-ddr4-tester-footprints:NetTie-2_SMD_Pad0.127mm" (layer "F.Cu")
    (at 144.77 83.7)
    (descr "Net tie, 2 pin, 0.127mm  SMD pads")
    (tags "net tie")
    (property "Author" "Antmicro")
    (property "License" "Apache-2.0")
    (property "MPN" "")
    (property "Manufacturer" "")
    (property "Sheetfile" "supply.kicad_sch")
    (property "Sheetname" "Supply")
    (property "ki_description" "Net tie, 2 pins")
    (property "ki_keywords" "net tie short")
    (attr through_hole exclude_from_pos_files)
    (net_tie_pad_groups "1, 2")
    (fp_text reference "NT14" (at -0.128 -1.345) (layer "F.SilkS") hide
        (effects (font (size 0.7 0.7) (thickness 0.15)) (justify left bottom))
    )
    (fp_text value "Net-Tie_2" (at 0 1.199) (layer "F.Fab") hide
        (effects (font (size 0.7 0.7) (thickness 0.15)) (justify left bottom))
    )
    (fp_text user "${REFERENCE}" (at -0.128 3.2) (layer "F.Fab") hide
        (effects (font (size 0.7 0.7) (thickness 0.15)) (justify left bottom))
    )
    (fp_text user "License: Apache-2.0" (at -0.128 5.6) (layer "F.Fab") hide
        (effects (font (size 0.7 0.7) (thickness 0.15)) (justify left bottom))
    )
    (fp_text user "Author: Antmicro" (at -0.128 4.4) (layer "F.Fab") hide
        (effects (font (size 0.7 0.7) (thickness 0.15)) (justify left bottom))
    )
    (fp_poly
      (pts
        (xy -0.0635 -0.0635)
        (xy 0.0625 -0.0635)
        (xy 0.0625 0.0635)
        (xy -0.0635 0.0635)
      )

      (stroke (width 0) (type solid)) (fill solid) (layer "F.Cu"))
    (pad "1" smd roundrect (at -0.127 0 180) (size 0.127 0.127) (layers "F.Cu") (roundrect_rratio 0.5)
      (chamfer_ratio 0) (chamfer top_left bottom_left)
      (net 845 "/Supply/1V0_SEN_-") (pinfunction "1") (pintype "passive"))
    (pad "2" smd roundrect (at 0.126 0) (size 0.127 0.127) (layers "F.Cu") (roundrect_rratio 0.5)
      (chamfer_ratio 0) (chamfer top_left bottom_left)
      (net 147 "1V0_SYS") (pinfunction "2") (pintype "passive"))
  )

  (footprint "data-center-rdimm-ddr4-tester-footprints:C_0402_1005Metric" (layer "F.Cu")
    (at 254.71 92.875 180)
    (descr "Capacitor SMD 0402")
    (tags "capacitor SMD 0402")
    (property "Author" "Antmicro")
    (property "Dielectric" "X5R")
    (property "License" "Apache-2.0")
    (property "MPN" "GRM155R61H104KE14D")
    (property "Manufacturer" "Murata")
    (property "Sheetfile" "fmc_hpc.kicad_sch")
    (property "Sheetname" "FMC HPC")
    (property "Val" "100n")
    (property "Voltage" "50V")
    (property "ki_description" " ")
    (attr smd)
    (fp_text reference "C263" (at -0.8 -0.385 180) (layer "F.SilkS")
        (effects (font (size 0.7 0.7) (thickness 0.15)) (justify left bottom))
    )
    (fp_text value "C_100n_0402" (at 0 1.4 180) (layer "F.Fab") hide
        (effects (font (size 0.7 0.7) (thickness 0.15)) (justify left bottom))
    )
    (fp_text user "Author: Antmicro" (at -0.932 4.17 180) (layer "F.Fab") hide
        (effects (font (size 0.7 0.7) (thickness 0.15)) (justify left bottom))
    )
    (fp_text user "${REFERENCE}" (at -0.932 3.168 180) (layer "F.Fab") hide
        (effects (font (size 0.7 0.7) (thickness 0.15)) (justify left bottom))
    )
    (fp_text user "License: Apache-2.0" (at -0.932 5.17 180) (layer "F.Fab") hide
        (effects (font (size 0.7 0.7) (thickness 0.15)) (justify left bottom))
    )
    (fp_rect (start -0.94 -0.47) (end 0.94 0.47)
      (stroke (width 0.05) (type solid)) (fill none) (layer "F.CrtYd"))
    (fp_rect (start -0.499 -0.249) (end 0.499 0.249)
      (stroke (width 0.15) (type solid)) (fill none) (layer "F.Fab"))
    (pad "1" smd roundrect (at -0.484 0 180) (size 0.59 0.64) (layers "F.Cu" "F.Paste" "F.Mask") (roundrect_rratio 0.25)
      (net 430 "/FMC HPC/GTX_TX2_C_P") (pintype "passive"))
    (pad "2" smd roundrect (at 0.484 0 180) (size 0.59 0.64) (layers "F.Cu" "F.Paste" "F.Mask") (roundrect_rratio 0.25)
      (net 431 "GTX_TX2_P") (pintype "passive"))
  )

  (footprint "data-center-rdimm-ddr4-tester-footprints:R_0201" (layer "F.Cu")
    (at 163.9 104.29 -90)
    (descr "Resistor SMD 0201")
    (tags "resistor SMD 0201")
    (property "Author" "Antmicro")
    (property "License" "Apache-2.0")
    (property "MPN" "CR0201-FX-0R00GLF")
    (property "Manufacturer" "Bourns")
    (property "Sheetfile" "ethernet.kicad_sch")
    (property "Sheetname" "Ethernet")
    (property "Tolerance" "1%")
    (property "Val" "0R")
    (property "ki_description" "0R resistor in 0201 package with 1% tolerance")
    (attr smd)
    (fp_text reference "R221" (at -0.63 -0.375 -90) (layer "F.SilkS")
        (effects (font (size 0.7 0.7) (thickness 0.15)) (justify left bottom))
    )
    (fp_text value "R_0R_0201" (at 0 1.25 -90) (layer "F.Fab") hide
        (effects (font (size 0.7 0.7) (thickness 0.15)) (justify left bottom))
    )
    (fp_text user "License: Apache-2.0" (at -0.71 4.25 -90) (layer "F.Fab") hide
        (effects (font (size 0.7 0.7) (thickness 0.15)) (justify left bottom))
    )
    (fp_text user "Author: Antmicro" (at -0.71 5.25 -90) (layer "F.Fab") hide
        (effects (font (size 0.7 0.7) (thickness 0.15)) (justify left bottom))
    )
    (fp_text user "${REFERENCE}" (at -0.71 3.25 -90) (layer "F.Fab") hide
        (effects (font (size 0.7 0.7) (thickness 0.15)) (justify left bottom))
    )
    (fp_rect (start -0.71 -0.36) (end 0.71 0.36)
      (stroke (width 0.05) (type solid)) (fill none) (layer "F.CrtYd"))
    (fp_rect (start -0.3 -0.15) (end 0.298 0.148)
      (stroke (width 0.15) (type solid)) (fill none) (layer "F.Fab"))
    (pad "" smd roundrect (at -0.346 0 270) (size 0.318 0.36) (layers "F.Paste") (roundrect_rratio 0.25))
    (pad "" smd roundrect (at 0.344 0 270) (size 0.318 0.36) (layers "F.Paste") (roundrect_rratio 0.25))
    (pad "1" smd roundrect (at -0.32 0 270) (size 0.46 0.4) (layers "F.Cu" "F.Mask") (roundrect_rratio 0.25)
      (net 16 "LED_LINK") (pintype "passive"))
    (pad "2" smd roundrect (at 0.32 0 270) (size 0.46 0.4) (layers "F.Cu" "F.Mask") (roundrect_rratio 0.25)
      (net 537 "INT_LED_LINK") (pintype "passive"))
  )

  (footprint "data-center-rdimm-ddr4-tester-footprints:SOT-353" (layer "F.Cu")
    (at 225.8 122.8 90)
    (descr "5-lead Small Outline SMT package (aka SC-70-5, SC-88A or TSSOP5): reflow soldering footprint")
    (tags "SOT-353 sot353 SC-70-5 sc70 SC-88A sc88a TSSOP5")
    (property "Author" "Antmicro")
    (property "License" "Apache-2.0")
    (property "MPN" "SN74LVC1G240DCKR")
    (property "Manufacturer" "Texas Instruments")
    (property "Sheetfile" "supply.kicad_sch")
    (property "Sheetname" "Supply")
    (property "ki_description" "Single Inverting Buffer/Driver With 3-State Output")
    (attr smd)
    (fp_text reference "U27" (at 1.42 -1.93) (layer "F.SilkS")
        (effects (font (size 0.7 0.7) (thickness 0.15)) (justify left bottom))
    )
    (fp_text value "SN74LVC1G240_SC70" (at 0 2.4 90) (layer "F.Fab") hide
        (effects (font (size 0.7 0.7) (thickness 0.15)) (justify left bottom))
    )
    (fp_text user "License: Apache-2.0" (at -1.206 6.427 90) (layer "F.Fab") hide
        (effects (font (size 0.7 0.7) (thickness 0.15)) (justify left bottom))
    )
    (fp_text user "${REFERENCE}" (at -1.206 4.027 90) (layer "F.Fab") hide
        (effects (font (size 0.7 0.7) (thickness 0.15)) (justify left bottom))
    )
    (fp_text user "Author: Antmicro" (at -1.206 5.227 90) (layer "F.Fab") hide
        (effects (font (size 0.7 0.7) (thickness 0.15)) (justify left bottom))
    )
    (fp_line (start -1.15 0.7) (end -1.15 -0.65)
      (stroke (width 0.15) (type solid)) (layer "F.SilkS"))
    (fp_line (start 1.15 0.7) (end 1.144 -0.65)
      (stroke (width 0.15) (type solid)) (layer "F.SilkS"))
    (fp_circle (center -0.762 1.6256) (end -0.712 1.6256)
      (stroke (width 0.15) (type solid)) (fill solid) (layer "F.SilkS"))
    (fp_rect (start 1.25 -1.46) (end -1.25 1.45)
      (stroke (width 0.05) (type solid)) (fill none) (layer "F.CrtYd"))
    (fp_line (start -1.006 -0.657) (end 0.993 -0.657)
      (stroke (width 0.15) (type solid)) (layer "F.Fab"))
    (fp_line (start -1.006 0.293) (end -1.006 -0.657)
      (stroke (width 0.15) (type solid)) (layer "F.Fab"))
    (fp_line (start -1.006 0.293) (end -0.706 0.593)
      (stroke (width 0.15) (type solid)) (layer "F.Fab"))
    (fp_line (start 0.993 -0.657) (end 0.993 0.593)
      (stroke (width 0.15) (type solid)) (layer "F.Fab"))
    (fp_line (start 0.993 0.593) (end -0.706 0.593)
      (stroke (width 0.15) (type solid)) (layer "F.Fab"))
    (pad "1" smd roundrect (at -0.756 0.893 180) (size 0.6 0.6) (layers "F.Cu" "F.Paste" "F.Mask") (roundrect_rratio 0.25)
      (net 108 "Net-(U27-~{OE})") (pinfunction "~{OE}") (pintype "input"))
    (pad "2" smd roundrect (at -0.006 0.893 180) (size 0.6 0.4) (layers "F.Cu" "F.Paste" "F.Mask") (roundrect_rratio 0.25)
      (net 859 "/Supply/OUT") (pinfunction "A") (pintype "input"))
    (pad "3" smd roundrect (at 0.743 0.893 180) (size 0.6 0.6) (layers "F.Cu" "F.Paste" "F.Mask") (roundrect_rratio 0.25)
      (net 9 "GND") (pinfunction "GND") (pintype "power_in"))
    (pad "4" smd roundrect (at 0.743 -0.907 180) (size 0.6 0.6) (layers "F.Cu" "F.Paste" "F.Mask") (roundrect_rratio 0.25)
      (net 584 "Net-(Q12-G)") (pinfunction "Y") (pintype "output"))
    (pad "5" smd roundrect (at -0.756 -0.907 180) (size 0.6 0.6) (layers "F.Cu" "F.Paste" "F.Mask") (roundrect_rratio 0.25)
      (net 846 "5V_ON_OFF") (pinfunction "V_{CC}") (pintype "power_in"))
  )

  (footprint "data-center-rdimm-ddr4-tester-footprints:R_0402_1005Metric" (layer "F.Cu")
    (at 122.525 62.95)
    (descr "Resistor SMD 0402")
    (tags "resistor SMD 0402")
    (property "Author" "Antmicro")
    (property "Current" "1A")
    (property "License" "Apache-2.0")
    (property "MPN" "ERJ2GE0R00X")
    (property "Manufacturer" "Panasonic")
    (property "Sheetfile" "DDR4.kicad_sch")
    (property "Sheetname" "DDR4")
    (property "Tolerance" "")
    (property "Val" "0R")
    (property "ki_description" "0R resistor in 0402 package with unspecified tolerance")
    (attr smd)
    (fp_text reference "R158" (at 0 -0.7) (layer "F.SilkS")
        (effects (font (size 0.7 0.7) (thickness 0.15)) (justify left bottom))
    )
    (fp_text value "R_0R_0402" (at 0 1.4) (layer "F.Fab") hide
        (effects (font (size 0.7 0.7) (thickness 0.15)) (justify left bottom))
    )
    (fp_text user "Author: Antmicro" (at -0.95 4.169) (layer "F.Fab") hide
        (effects (font (size 0.7 0.7) (thickness 0.15)) (justify left bottom))
    )
    (fp_text user "${REFERENCE}" (at -0.95 3.168) (layer "F.Fab") hide
        (effects (font (size 0.7 0.7) (thickness 0.15)) (justify left bottom))
    )
    (fp_text user "License: Apache-2.0" (at -0.95 5.169) (layer "F.Fab") hide
        (effects (font (size 0.7 0.7) (thickness 0.15)) (justify left bottom))
    )
    (fp_rect (start -0.93 -0.47) (end 0.93 0.47)
      (stroke (width 0.05) (type solid)) (fill none) (layer "F.CrtYd"))
    (fp_rect (start -0.5 -0.25) (end 0.5 0.25)
      (stroke (width 0.15) (type solid)) (fill none) (layer "F.Fab"))
    (pad "1" smd roundrect (at -0.485 0) (size 0.59 0.64) (layers "F.Cu" "F.Paste" "F.Mask") (roundrect_rratio 0.25)
      (net 184 "VPP") (pintype "passive"))
    (pad "2" smd roundrect (at 0.485 0) (size 0.59 0.64) (layers "F.Cu" "F.Paste" "F.Mask") (roundrect_rratio 0.25)
      (net 185 "VDDSPD") (pintype "passive"))
  )

  (footprint "data-center-rdimm-ddr4-tester-footprints:R_0402_1005Metric" (layer "F.Cu")
    (at 246.042902 123.36 180)
    (descr "Resistor SMD 0402")
    (tags "resistor SMD 0402")
    (property "Author" "Antmicro")
    (property "License" "Apache-2.0")
    (property "MPN" "CR0402-FX-33R0GLF")
    (property "Manufacturer" "Bourns")
    (property "Sheetfile" "fmc_hpc.kicad_sch")
    (property "Sheetname" "FMC HPC")
    (property "Tolerance" "1%")
    (property "Val" "33R")
    (property "ki_description" "33R resistor in 0402 package with 1% tolerance")
    (attr smd)
    (fp_text reference "R152" (at -0.697098 -0.37 180) (layer "F.SilkS")
        (effects (font (size 0.7 0.7) (thickness 0.15)) (justify left bottom))
    )
    (fp_text value "R_33R_0402" (at 0 1.4 180) (layer "F.Fab") hide
        (effects (font (size 0.7 0.7) (thickness 0.15)) (justify left bottom))
    )
    (fp_text user "${REFERENCE}" (at -0.95 3.168 180) (layer "F.Fab") hide
        (effects (font (size 0.7 0.7) (thickness 0.15)) (justify left bottom))
    )
    (fp_text user "License: Apache-2.0" (at -0.95 5.169 180) (layer "F.Fab") hide
        (effects (font (size 0.7 0.7) (thickness 0.15)) (justify left bottom))
    )
    (fp_text user "Author: Antmicro" (at -0.95 4.169 180) (layer "F.Fab") hide
        (effects (font (size 0.7 0.7) (thickness 0.15)) (justify left bottom))
    )
    (fp_rect (start -0.93 -0.47) (end 0.93 0.47)
      (stroke (width 0.05) (type solid)) (fill none) (layer "F.CrtYd"))
    (fp_rect (start -0.5 -0.25) (end 0.5 0.25)
      (stroke (width 0.15) (type solid)) (fill none) (layer "F.Fab"))
    (pad "1" smd roundrect (at -0.485 0 180) (size 0.59 0.64) (layers "F.Cu" "F.Paste" "F.Mask") (roundrect_rratio 0.25)
      (net 899 "/FMC HPC/GTR_REFCLK3_R_P") (pintype "passive"))
    (pad "2" smd roundrect (at 0.485 0 180) (size 0.59 0.64) (layers "F.Cu" "F.Paste" "F.Mask") (roundrect_rratio 0.25)
      (net 895 "GTR_REFCLK3_C_P") (pintype "passive"))
  )

  (footprint "data-center-rdimm-ddr4-tester-footprints:C_0402_1005Metric" (layer "F.Cu")
    (at 225.4 124.6)
    (descr "Capacitor SMD 0402")
    (tags "capacitor SMD 0402")
    (property "Author" "Antmicro")
    (property "Dielectric" "X5R")
    (property "License" "Apache-2.0")
    (property "MPN" "GRM155R61H104KE14D")
    (property "Manufacturer" "Murata")
    (property "Sheetfile" "supply.kicad_sch")
    (property "Sheetname" "Supply")
    (property "Val" "100n")
    (property "Voltage" "50V")
    (property "ki_description" " ")
    (attr smd)
    (fp_text reference "C282" (at -1.11 1.33) (layer "F.SilkS")
        (effects (font (size 0.7 0.7) (thickness 0.15)) (justify left bottom))
    )
    (fp_text value "C_100n_0402" (at 0 1.4) (layer "F.Fab") hide
        (effects (font (size 0.7 0.7) (thickness 0.15)) (justify left bottom))
    )
    (fp_text user "${REFERENCE}" (at -0.932 3.168) (layer "F.Fab") hide
        (effects (font (size 0.7 0.7) (thickness 0.15)) (justify left bottom))
    )
    (fp_text user "License: Apache-2.0" (at -0.932 5.17) (layer "F.Fab") hide
        (effects (font (size 0.7 0.7) (thickness 0.15)) (justify left bottom))
    )
    (fp_text user "Author: Antmicro" (at -0.932 4.17) (layer "F.Fab") hide
        (effects (font (size 0.7 0.7) (thickness 0.15)) (justify left bottom))
    )
    (fp_rect (start -0.94 -0.47) (end 0.94 0.47)
      (stroke (width 0.05) (type solid)) (fill none) (layer "F.CrtYd"))
    (fp_rect (start -0.499 -0.249) (end 0.499 0.249)
      (stroke (width 0.15) (type solid)) (fill none) (layer "F.Fab"))
    (pad "1" smd roundrect (at -0.484 0) (size 0.59 0.64) (layers "F.Cu" "F.Paste" "F.Mask") (roundrect_rratio 0.25)
      (net 846 "5V_ON_OFF") (pintype "passive"))
    (pad "2" smd roundrect (at 0.484 0) (size 0.59 0.64) (layers "F.Cu" "F.Paste" "F.Mask") (roundrect_rratio 0.25)
      (net 9 "GND") (pintype "passive"))
  )

  (footprint "data-center-rdimm-ddr4-tester-footprints:NetTie-2_SMD_Pad0.127mm" (layer "F.Cu")
    (at 153.17 121.7)
    (descr "Net tie, 2 pin, 0.127mm  SMD pads")
    (tags "net tie")
    (property "Author" "Antmicro")
    (property "License" "Apache-2.0")
    (property "MPN" "")
    (property "Manufacturer" "")
    (property "Sheetfile" "supply.kicad_sch")
    (property "Sheetname" "Supply")
    (property "ki_description" "Net tie, 2 pins")
    (property "ki_keywords" "net tie short")
    (attr through_hole exclude_from_pos_files)
    (net_tie_pad_groups "1, 2")
    (fp_text reference "NT16" (at -0.128 -1.345) (layer "F.SilkS") hide
        (effects (font (size 0.7 0.7) (thickness 0.15)) (justify left bottom))
    )
    (fp_text value "Net-Tie_2" (at 0 1.199) (layer "F.Fab") hide
        (effects (font (size 0.7 0.7) (thickness 0.15)) (justify left bottom))
    )
    (fp_text user "${REFERENCE}" (at -0.128 3.2) (layer "F.Fab") hide
        (effects (font (size 0.7 0.7) (thickness 0.15)) (justify left bottom))
    )
    (fp_text user "Author: Antmicro" (at -0.128 4.4) (layer "F.Fab") hide
        (effects (font (size 0.7 0.7) (thickness 0.15)) (justify left bottom))
    )
    (fp_text user "License: Apache-2.0" (at -0.128 5.6) (layer "F.Fab") hide
        (effects (font (size 0.7 0.7) (thickness 0.15)) (justify left bottom))
    )
    (fp_poly
      (pts
        (xy -0.0635 -0.0635)
        (xy 0.0625 -0.0635)
        (xy 0.0625 0.0635)
        (xy -0.0635 0.0635)
      )

      (stroke (width 0) (type solid)) (fill solid) (layer "F.Cu"))
    (pad "1" smd roundrect (at -0.127 0 180) (size 0.127 0.127) (layers "F.Cu") (roundrect_rratio 0.5)
      (chamfer_ratio 0) (chamfer top_left bottom_left)
      (net 806 "/Supply/VCC1V2_SEN_-") (pinfunction "1") (pintype "passive"))
    (pad "2" smd roundrect (at 0.126 0) (size 0.127 0.127) (layers "F.Cu") (roundrect_rratio 0.5)
      (chamfer_ratio 0) (chamfer top_left bottom_left)
      (net 306 "1V2_SYS") (pinfunction "2") (pintype "passive"))
  )

  (footprint "data-center-rdimm-ddr4-tester-footprints:C_0402_1005Metric" (layer "F.Cu")
    (at 221.85 126.4 180)
    (descr "Capacitor SMD 0402")
    (tags "capacitor SMD 0402")
    (property "Author" "Antmicro")
    (property "DNP" "DNP")
    (property "Dielectric" "")
    (property "License" "Apache-2.0")
    (property "MPN" "C1005X6S1A105K050BC")
    (property "Manufacturer" "TDK")
    (property "Sheetfile" "interfaces.kicad_sch")
    (property "Sheetname" "Interfaces")
    (property "Val" "1u")
    (property "Voltage" "")
    (property "dnp" "")
    (property "exclude_from_bom" "")
    (property "ki_description" " ")
    (attr exclude_from_pos_files exclude_from_bom)
    (fp_text reference "C226" (at -0.83 -0.73 180) (layer "F.SilkS")
        (effects (font (size 0.7 0.7) (thickness 0.15)) (justify left bottom))
    )
    (fp_text value "C_1u_0402" (at 0 1.4 180) (layer "F.Fab") hide
        (effects (font (size 0.7 0.7) (thickness 0.15)) (justify left bottom))
    )
    (fp_text user "${REFERENCE}" (at -0.932 3.168 180) (layer "F.Fab") hide
        (effects (font (size 0.7 0.7) (thickness 0.15)) (justify left bottom))
    )
    (fp_text user "Author: Antmicro" (at -0.932 4.17 180) (layer "F.Fab") hide
        (effects (font (size 0.7 0.7) (thickness 0.15)) (justify left bottom))
    )
    (fp_text user "License: Apache-2.0" (at -0.932 5.17 180) (layer "F.Fab") hide
        (effects (font (size 0.7 0.7) (thickness 0.15)) (justify left bottom))
    )
    (fp_rect (start -0.94 -0.47) (end 0.94 0.47)
      (stroke (width 0.05) (type solid)) (fill none) (layer "F.CrtYd"))
    (fp_rect (start -0.499 -0.249) (end 0.499 0.249)
      (stroke (width 0.15) (type solid)) (fill none) (layer "F.Fab"))
    (pad "1" smd roundrect (at -0.484 0 180) (size 0.59 0.64) (layers "F.Cu" "F.Paste" "F.Mask") (roundrect_rratio 0.25)
      (net 149 "HOT_SWAP_BUTTON") (pintype "passive"))
    (pad "2" smd roundrect (at 0.484 0 180) (size 0.59 0.64) (layers "F.Cu" "F.Paste" "F.Mask") (roundrect_rratio 0.25)
      (net 9 "GND") (pintype "passive"))
  )

  (footprint "data-center-rdimm-ddr4-tester-footprints:NetTie-2_SMD_Pad0.127mm" (layer "F.Cu")
    (at 151.43 121.7 180)
    (descr "Net tie, 2 pin, 0.127mm  SMD pads")
    (tags "net tie")
    (property "Author" "Antmicro")
    (property "License" "Apache-2.0")
    (property "MPN" "")
    (property "Manufacturer" "")
    (property "Sheetfile" "supply.kicad_sch")
    (property "Sheetname" "Supply")
    (property "ki_description" "Net tie, 2 pins")
    (property "ki_keywords" "net tie short")
    (attr through_hole exclude_from_pos_files)
    (net_tie_pad_groups "1, 2")
    (fp_text reference "NT15" (at -0.128 -1.345 180) (layer "F.SilkS") hide
        (effects (font (size 0.7 0.7) (thickness 0.15)) (justify left bottom))
    )
    (fp_text value "Net-Tie_2" (at 0 1.199 180) (layer "F.Fab") hide
        (effects (font (size 0.7 0.7) (thickness 0.15)) (justify left bottom))
    )
    (fp_text user "License: Apache-2.0" (at -0.128 5.6 180) (layer "F.Fab") hide
        (effects (font (size 0.7 0.7) (thickness 0.15)) (justify left bottom))
    )
    (fp_text user "${REFERENCE}" (at -0.128 3.2 180) (layer "F.Fab") hide
        (effects (font (size 0.7 0.7) (thickness 0.15)) (justify left bottom))
    )
    (fp_text user "Author: Antmicro" (at -0.128 4.4 180) (layer "F.Fab") hide
        (effects (font (size 0.7 0.7) (thickness 0.15)) (justify left bottom))
    )
    (fp_poly
      (pts
        (xy -0.0635 -0.0635)
        (xy 0.0625 -0.0635)
        (xy 0.0625 0.0635)
        (xy -0.0635 0.0635)
      )

      (stroke (width 0) (type solid)) (fill solid) (layer "F.Cu"))
    (pad "1" smd roundrect (at -0.127 0) (size 0.127 0.127) (layers "F.Cu") (roundrect_rratio 0.5)
      (chamfer_ratio 0) (chamfer top_left bottom_left)
      (net 805 "/Supply/VCC1V2_SEN_+") (pinfunction "1") (pintype "passive"))
    (pad "2" smd roundrect (at 0.126 0 180) (size 0.127 0.127) (layers "F.Cu") (roundrect_rratio 0.5)
      (chamfer_ratio 0) (chamfer top_left bottom_left)
      (net 176 "VCC1V2") (pinfunction "2") (pintype "passive"))
  )

  (footprint "data-center-rdimm-ddr4-tester-footprints:R_0402_1005Metric" (layer "F.Cu")
    (at 201.9 113.7 -90)
    (descr "Resistor SMD 0402")
    (tags "resistor SMD 0402")
    (property "Author" "Antmicro")
    (property "License" "Apache-2.0")
    (property "MPN" "CR0402-FX-3242GLF")
    (property "Manufacturer" "Bourns")
    (property "Sheetfile" "ethernet.kicad_sch")
    (property "Sheetname" "Ethernet")
    (property "Tolerance" "1%")
    (property "Val" "32k4")
    (property "ki_description" "32k4 resistor in 0402 package with 1% tolerance")
    (attr smd)
    (fp_text reference "R180" (at 1.38 0.57 -90) (layer "F.SilkS")
        (effects (font (size 0.7 0.7) (thickness 0.15)) (justify left bottom))
    )
    (fp_text value "R_32k4_0402" (at 0 1.4 -90) (layer "F.Fab") hide
        (effects (font (size 0.7 0.7) (thickness 0.15)) (justify left bottom))
    )
    (fp_text user "License: Apache-2.0" (at -0.95 5.169 -90) (layer "F.Fab") hide
        (effects (font (size 0.7 0.7) (thickness 0.15)) (justify left bottom))
    )
    (fp_text user "${REFERENCE}" (at -0.95 3.168 -90) (layer "F.Fab") hide
        (effects (font (size 0.7 0.7) (thickness 0.15)) (justify left bottom))
    )
    (fp_text user "Author: Antmicro" (at -0.95 4.169 -90) (layer "F.Fab") hide
        (effects (font (size 0.7 0.7) (thickness 0.15)) (justify left bottom))
    )
    (fp_rect (start -0.93 -0.47) (end 0.93 0.47)
      (stroke (width 0.05) (type solid)) (fill none) (layer "F.CrtYd"))
    (fp_rect (start -0.5 -0.25) (end 0.5 0.25)
      (stroke (width 0.15) (type solid)) (fill none) (layer "F.Fab"))
    (pad "1" smd roundrect (at -0.485 0 270) (size 0.59 0.64) (layers "F.Cu" "F.Paste" "F.Mask") (roundrect_rratio 0.25)
      (net 609 "Net-(D15-Pad1)") (pintype "passive"))
    (pad "2" smd roundrect (at 0.485 0 270) (size 0.59 0.64) (layers "F.Cu" "F.Paste" "F.Mask") (roundrect_rratio 0.25)
      (net 360 "/Ethernet/VDD") (pintype "passive"))
  )

  (footprint "data-center-rdimm-ddr4-tester-footprints:R_1206_3216Metric" (layer "F.Cu")
    (at 112.25 108.95 180)
    (property "Author" "Antmicro")
    (property "License" "Apache-2.0")
    (property "MPN" "RL1206FR-7W0R01L")
    (property "Manufacturer" "Yaego")
    (property "Sheetfile" "supply.kicad_sch")
    (property "Sheetname" "Supply")
    (property "Tolerance" "1%")
    (property "Val" "0R01")
    (property "ki_description" "0R01 resistor in 1206 package with unspecified tolerance")
    (attr smd)
    (fp_text reference "R202" (at 3.26 1.15 180) (layer "F.SilkS")
        (effects (font (size 0.7 0.7) (thickness 0.15)) (justify left bottom))
    )
    (fp_text value "R_0R01_1206" (at 0 2 180) (layer "F.Fab") hide
        (effects (font (size 0.7 0.7) (thickness 0.15)) (justify left bottom))
    )
    (fp_text user "License: Apache-2.0" (at -2.401 6.3 180) (layer "F.Fab") hide
        (effects (font (size 0.7 0.7) (thickness 0.15)) (justify left bottom))
    )
    (fp_text user "${REFERENCE}" (at -2.401 3.5 180) (layer "F.Fab") hide
        (effects (font (size 0.7 0.7) (thickness 0.15)) (justify left bottom))
    )
    (fp_text user "Author: Antmicro" (at -2.401 4.899 180) (layer "F.Fab") hide
        (effects (font (size 0.7 0.7) (thickness 0.15)) (justify left bottom))
    )
    (fp_line (start 0 -0.902) (end -0.5 -0.902)
      (stroke (width 0.15) (type solid)) (layer "F.SilkS"))
    (fp_line (start 0 -0.902) (end 0.498 -0.902)
      (stroke (width 0.15) (type solid)) (layer "F.SilkS"))
    (fp_line (start 0 0.9) (end -0.5 0.9)
      (stroke (width 0.15) (type solid)) (layer "F.SilkS"))
    (fp_line (start 0 0.9) (end 0.498 0.9)
      (stroke (width 0.15) (type solid)) (layer "F.SilkS"))
    (fp_rect (start -2.25 -1.05) (end 2.25 1.05)
      (stroke (width 0.05) (type solid)) (fill none) (layer "F.CrtYd"))
    (fp_line (start -1.601 -0.802) (end -1.601 0.8)
      (stroke (width 0.15) (type solid)) (layer "F.Fab"))
    (fp_line (start -1.601 -0.802) (end 1.6 -0.802)
      (stroke (width 0.15) (type solid)) (layer "F.Fab"))
    (fp_line (start -1.601 0.8) (end 1.6 0.8)
      (stroke (width 0.15) (type solid)) (layer "F.Fab"))
    (fp_line (start 1.6 -0.802) (end 1.6 0.8)
      (stroke (width 0.15) (type solid)) (layer "F.Fab"))
    (pad "1" smd roundrect (at -1.5 0 180) (size 1.2 1.8) (layers "F.Cu" "F.Paste" "F.Mask") (roundrect_rratio 0.15)
      (net 304 "VCC3V3") (pintype "passive"))
    (pad "2" smd roundrect (at 1.499 0 180) (size 1.2 1.8) (layers "F.Cu" "F.Paste" "F.Mask") (roundrect_rratio 0.15)
      (net 143 "3V3_SYS") (pintype "passive"))
  )

  (footprint "data-center-rdimm-ddr4-tester-footprints:R_0201" (layer "F.Cu")
    (at 160.8 109.03 -90)
    (descr "Resistor SMD 0201")
    (tags "resistor SMD 0201")
    (property "Author" "Antmicro")
    (property "License" "Apache-2.0")
    (property "MPN" "CR0201-FX-0R00GLF")
    (property "Manufacturer" "Bourns")
    (property "Sheetfile" "ethernet.kicad_sch")
    (property "Sheetname" "Ethernet")
    (property "Tolerance" "1%")
    (property "Val" "0R")
    (property "ki_description" "0R resistor in 0201 package with 1% tolerance")
    (attr smd)
    (fp_text reference "R109" (at 3.47 -0.37 -90) (layer "F.SilkS")
        (effects (font (size 0.7 0.7) (thickness 0.15)) (justify left bottom))
    )
    (fp_text value "R_0R_0201" (at 0 1.25 -90) (layer "F.Fab") hide
        (effects (font (size 0.7 0.7) (thickness 0.15)) (justify left bottom))
    )
    (fp_text user "License: Apache-2.0" (at -0.71 4.25 -90) (layer "F.Fab") hide
        (effects (font (size 0.7 0.7) (thickness 0.15)) (justify left bottom))
    )
    (fp_text user "Author: Antmicro" (at -0.71 5.25 -90) (layer "F.Fab") hide
        (effects (font (size 0.7 0.7) (thickness 0.15)) (justify left bottom))
    )
    (fp_text user "${REFERENCE}" (at -0.71 3.25 -90) (layer "F.Fab") hide
        (effects (font (size 0.7 0.7) (thickness 0.15)) (justify left bottom))
    )
    (fp_rect (start -0.71 -0.36) (end 0.71 0.36)
      (stroke (width 0.05) (type solid)) (fill none) (layer "F.CrtYd"))
    (fp_rect (start -0.3 -0.15) (end 0.298 0.148)
      (stroke (width 0.15) (type solid)) (fill none) (layer "F.Fab"))
    (pad "" smd roundrect (at -0.346 0 270) (size 0.318 0.36) (layers "F.Paste") (roundrect_rratio 0.25))
    (pad "" smd roundrect (at 0.344 0 270) (size 0.318 0.36) (layers "F.Paste") (roundrect_rratio 0.25))
    (pad "1" smd roundrect (at -0.32 0 270) (size 0.46 0.4) (layers "F.Cu" "F.Mask") (roundrect_rratio 0.25)
      (net 828 "/Ethernet/ETH3_BP_P") (pintype "passive"))
    (pad "2" smd roundrect (at 0.32 0 270) (size 0.46 0.4) (layers "F.Cu" "F.Mask") (roundrect_rratio 0.25)
      (net 559 "/Ethernet/INT_ETH3_P") (pintype "passive"))
  )

  (footprint "data-center-rdimm-ddr4-tester-footprints:C_0402_1005Metric" (layer "F.Cu")
    (at 232.1 122.4 -90)
    (descr "Capacitor SMD 0402")
    (tags "capacitor SMD 0402")
    (property "Author" "Antmicro")
    (property "Dielectric" "X5R")
    (property "License" "Apache-2.0")
    (property "MPN" "GRM155R61H104KE14D")
    (property "Manufacturer" "Murata")
    (property "Sheetfile" "supply.kicad_sch")
    (property "Sheetname" "Supply")
    (property "Val" "100n")
    (property "Voltage" "50V")
    (property "ki_description" " ")
    (attr smd)
    (fp_text reference "C283" (at 1.54 -1.25 -90) (layer "F.SilkS")
        (effects (font (size 0.7 0.7) (thickness 0.15)) (justify left bottom))
    )
    (fp_text value "C_100n_0402" (at 0 1.4 -90) (layer "F.Fab") hide
        (effects (font (size 0.7 0.7) (thickness 0.15)) (justify left bottom))
    )
    (fp_text user "Author: Antmicro" (at -0.932 4.17 -90) (layer "F.Fab") hide
        (effects (font (size 0.7 0.7) (thickness 0.15)) (justify left bottom))
    )
    (fp_text user "${REFERENCE}" (at -0.932 3.168 -90) (layer "F.Fab") hide
        (effects (font (size 0.7 0.7) (thickness 0.15)) (justify left bottom))
    )
    (fp_text user "License: Apache-2.0" (at -0.932 5.17 -90) (layer "F.Fab") hide
        (effects (font (size 0.7 0.7) (thickness 0.15)) (justify left bottom))
    )
    (fp_rect (start -0.94 -0.47) (end 0.94 0.47)
      (stroke (width 0.05) (type solid)) (fill none) (layer "F.CrtYd"))
    (fp_rect (start -0.499 -0.249) (end 0.499 0.249)
      (stroke (width 0.15) (type solid)) (fill none) (layer "F.Fab"))
    (pad "1" smd roundrect (at -0.484 0 270) (size 0.59 0.64) (layers "F.Cu" "F.Paste" "F.Mask") (roundrect_rratio 0.25)
      (net 846 "5V_ON_OFF") (pintype "passive"))
    (pad "2" smd roundrect (at 0.484 0 270) (size 0.59 0.64) (layers "F.Cu" "F.Paste" "F.Mask") (roundrect_rratio 0.25)
      (net 9 "GND") (pintype "passive"))
  )

  (footprint "data-center-rdimm-ddr4-tester-footprints:R_0201" (layer "F.Cu")
    (at 161.075 104.29 -90)
    (descr "Resistor SMD 0201")
    (tags "resistor SMD 0201")
    (property "Author" "Antmicro")
    (property "License" "Apache-2.0")
    (property "MPN" "CR0201-FX-0R00GLF")
    (property "Manufacturer" "Bourns")
    (property "Sheetfile" "ethernet.kicad_sch")
    (property "Sheetname" "Ethernet")
    (property "Tolerance" "1%")
    (property "Val" "0R")
    (property "ki_description" "0R resistor in 0201 package with 1% tolerance")
    (attr smd)
    (fp_text reference "R103" (at -0.61 -0.435 -90) (layer "F.SilkS")
        (effects (font (size 0.7 0.7) (thickness 0.15)) (justify left bottom))
    )
    (fp_text value "R_0R_0201" (at 0 1.25 -90) (layer "F.Fab") hide
        (effects (font (size 0.7 0.7) (thickness 0.15)) (justify left bottom))
    )
    (fp_text user "Author: Antmicro" (at -0.71 5.25 -90) (layer "F.Fab") hide
        (effects (font (size 0.7 0.7) (thickness 0.15)) (justify left bottom))
    )
    (fp_text user "License: Apache-2.0" (at -0.71 4.25 -90) (layer "F.Fab") hide
        (effects (font (size 0.7 0.7) (thickness 0.15)) (justify left bottom))
    )
    (fp_text user "${REFERENCE}" (at -0.71 3.25 -90) (layer "F.Fab") hide
        (effects (font (size 0.7 0.7) (thickness 0.15)) (justify left bottom))
    )
    (fp_rect (start -0.71 -0.36) (end 0.71 0.36)
      (stroke (width 0.05) (type solid)) (fill none) (layer "F.CrtYd"))
    (fp_rect (start -0.3 -0.15) (end 0.298 0.148)
      (stroke (width 0.15) (type solid)) (fill none) (layer "F.Fab"))
    (pad "" smd roundrect (at -0.346 0 270) (size 0.318 0.36) (layers "F.Paste") (roundrect_rratio 0.25))
    (pad "" smd roundrect (at 0.344 0 270) (size 0.318 0.36) (layers "F.Paste") (roundrect_rratio 0.25))
    (pad "1" smd roundrect (at -0.32 0 270) (size 0.46 0.4) (layers "F.Cu" "F.Mask") (roundrect_rratio 0.25)
      (net 171 "/Ethernet/ETH4_P") (pintype "passive"))
    (pad "2" smd roundrect (at 0.32 0 270) (size 0.46 0.4) (layers "F.Cu" "F.Mask") (roundrect_rratio 0.25)
      (net 830 "/Ethernet/ETH4_BP_P") (pintype "passive"))
  )

  (footprint "data-center-rdimm-ddr4-tester-footprints:R_0402_1005Metric" (layer "F.Cu")
    (at 238.3 123.8 90)
    (descr "Resistor SMD 0402")
    (tags "resistor SMD 0402")
    (property "Author" "Antmicro")
    (property "DNP" "DNP")
    (property "License" "Apache-2.0")
    (property "MPN" "CR0402-FX-4702GLF")
    (property "Manufacturer" "Bourns")
    (property "Sheetfile" "supply.kicad_sch")
    (property "Sheetname" "Supply")
    (property "Tolerance" "1%")
    (property "Val" "47k")
    (property "dnp" "")
    (property "exclude_from_bom" "")
    (property "ki_description" "47k resistor in 0402 package with 1% tolerance")
    (attr exclude_from_pos_files exclude_from_bom)
    (fp_text reference "R117" (at -2.99 1.34 90) (layer "F.SilkS")
        (effects (font (size 0.7 0.7) (thickness 0.15)) (justify left bottom))
    )
    (fp_text value "R_47k_0402" (at 0 1.4 90) (layer "F.Fab") hide
        (effects (font (size 0.7 0.7) (thickness 0.15)) (justify left bottom))
    )
    (fp_text user "${REFERENCE}" (at -0.95 3.168 90) (layer "F.Fab") hide
        (effects (font (size 0.7 0.7) (thickness 0.15)) (justify left bottom))
    )
    (fp_text user "License: Apache-2.0" (at -0.95 5.169 90) (layer "F.Fab") hide
        (effects (font (size 0.7 0.7) (thickness 0.15)) (justify left bottom))
    )
    (fp_text user "Author: Antmicro" (at -0.95 4.169 90) (layer "F.Fab") hide
        (effects (font (size 0.7 0.7) (thickness 0.15)) (justify left bottom))
    )
    (fp_rect (start -0.93 -0.47) (end 0.93 0.47)
      (stroke (width 0.05) (type solid)) (fill none) (layer "F.CrtYd"))
    (fp_rect (start -0.5 -0.25) (end 0.5 0.25)
      (stroke (width 0.15) (type solid)) (fill none) (layer "F.Fab"))
    (pad "1" smd roundrect (at -0.485 0 90) (size 0.59 0.64) (layers "F.Cu" "F.Paste" "F.Mask") (roundrect_rratio 0.25)
      (net 626 "VIN_RAW") (pintype "passive"))
    (pad "2" smd roundrect (at 0.485 0 90) (size 0.59 0.64) (layers "F.Cu" "F.Paste" "F.Mask") (roundrect_rratio 0.25)
      (net 108 "Net-(U27-~{OE})") (pintype "passive"))
  )

  (footprint "data-center-rdimm-ddr4-tester-footprints:NetTie-2_SMD_Pad0.127mm" (layer "F.Cu")
    (at 111.38 108.95 180)
    (descr "Net tie, 2 pin, 0.127mm  SMD pads")
    (tags "net tie")
    (property "Author" "Antmicro")
    (property "License" "Apache-2.0")
    (property "MPN" "")
    (property "Manufacturer" "")
    (property "Sheetfile" "supply.kicad_sch")
    (property "Sheetname" "Supply")
    (property "ki_description" "Net tie, 2 pins")
    (property "ki_keywords" "net tie short")
    (attr through_hole exclude_from_pos_files)
    (net_tie_pad_groups "1, 2")
    (fp_text reference "NT12" (at -0.128 -1.345 180) (layer "F.SilkS") hide
        (effects (font (size 0.7 0.7) (thickness 0.15)) (justify left bottom))
    )
    (fp_text value "Net-Tie_2" (at 0 1.199 180) (layer "F.Fab") hide
        (effects (font (size 0.7 0.7) (thickness 0.15)) (justify left bottom))
    )
    (fp_text user "Author: Antmicro" (at -0.128 4.4 180) (layer "F.Fab") hide
        (effects (font (size 0.7 0.7) (thickness 0.15)) (justify left bottom))
    )
    (fp_text user "${REFERENCE}" (at -0.128 3.2 180) (layer "F.Fab") hide
        (effects (font (size 0.7 0.7) (thickness 0.15)) (justify left bottom))
    )
    (fp_text user "License: Apache-2.0" (at -0.128 5.6 180) (layer "F.Fab") hide
        (effects (font (size 0.7 0.7) (thickness 0.15)) (justify left bottom))
    )
    (fp_poly
      (pts
        (xy -0.0635 -0.0635)
        (xy 0.0625 -0.0635)
        (xy 0.0625 0.0635)
        (xy -0.0635 0.0635)
      )

      (stroke (width 0) (type solid)) (fill solid) (layer "F.Cu"))
    (pad "1" smd roundrect (at -0.127 0) (size 0.127 0.127) (layers "F.Cu") (roundrect_rratio 0.5)
      (chamfer_ratio 0) (chamfer top_left bottom_left)
      (net 843 "/Supply/3V3_SEN_-") (pinfunction "1") (pintype "passive"))
    (pad "2" smd roundrect (at 0.126 0 180) (size 0.127 0.127) (layers "F.Cu") (roundrect_rratio 0.5)
      (chamfer_ratio 0) (chamfer top_left bottom_left)
      (net 143 "3V3_SYS") (pinfunction "2") (pintype "passive"))
  )

  (footprint "data-center-rdimm-ddr4-tester-footprints:R_0402_1005Metric" (layer "F.Cu")
    (at 150.6 127.5 90)
    (descr "Resistor SMD 0402")
    (tags "resistor SMD 0402")
    (property "Author" "Antmicro")
    (property "License" "Apache-2.0")
    (property "MPN" "CR0402-FX-5111GLF")
    (property "Manufacturer" "Bourns")
    (property "Sheetfile" "interfaces.kicad_sch")
    (property "Sheetname" "Interfaces")
    (property "Tolerance" "1%")
    (property "Val" "5k11")
    (property "ki_description" "5k11 resistor in 0402 package with 1% tolerance")
    (attr smd)
    (fp_text reference "R16" (at -0.94 1.17 90) (layer "F.SilkS")
        (effects (font (size 0.7 0.7) (thickness 0.15)) (justify left bottom))
    )
    (fp_text value "R_5k11_0402" (at 0 1.4 90) (layer "F.Fab") hide
        (effects (font (size 0.7 0.7) (thickness 0.15)) (justify left bottom))
    )
    (fp_text user "Author: Antmicro" (at -0.95 4.169 90) (layer "F.Fab") hide
        (effects (font (size 0.7 0.7) (thickness 0.15)) (justify left bottom))
    )
    (fp_text user "License: Apache-2.0" (at -0.95 5.169 90) (layer "F.Fab") hide
        (effects (font (size 0.7 0.7) (thickness 0.15)) (justify left bottom))
    )
    (fp_text user "${REFERENCE}" (at -0.95 3.168 90) (layer "F.Fab") hide
        (effects (font (size 0.7 0.7) (thickness 0.15)) (justify left bottom))
    )
    (fp_rect (start -0.93 -0.47) (end 0.93 0.47)
      (stroke (width 0.05) (type solid)) (fill none) (layer "F.CrtYd"))
    (fp_rect (start -0.5 -0.25) (end 0.5 0.25)
      (stroke (width 0.15) (type solid)) (fill none) (layer "F.Fab"))
    (pad "1" smd roundrect (at -0.485 0 90) (size 0.59 0.64) (layers "F.Cu" "F.Paste" "F.Mask") (roundrect_rratio 0.25)
      (net 569 "Net-(J9-CC2)") (pintype "passive"))
    (pad "2" smd roundrect (at 0.485 0 90) (size 0.59 0.64) (layers "F.Cu" "F.Paste" "F.Mask") (roundrect_rratio 0.25)
      (net 9 "GND") (pintype "passive"))
  )

  (footprint "data-center-rdimm-ddr4-tester-footprints:C_0402_1005Metric" (layer "F.Cu")
    (at 256.18 85.261)
    (descr "Capacitor SMD 0402")
    (tags "capacitor SMD 0402")
    (property "Author" "Antmicro")
    (property "Dielectric" "X5R")
    (property "License" "Apache-2.0")
    (property "MPN" "GRM155R61H104KE14D")
    (property "Manufacturer" "Murata")
    (property "Sheetfile" "fmc_hpc.kicad_sch")
    (property "Sheetname" "FMC HPC")
    (property "Val" "100n")
    (property "Voltage" "50V")
    (property "ki_description" " ")
    (attr smd)
    (fp_text reference "C273" (at 0.69 0.409) (layer "F.SilkS")
        (effects (font (size 0.7 0.7) (thickness 0.15)) (justify left bottom))
    )
    (fp_text value "C_100n_0402" (at 0 1.4) (layer "F.Fab") hide
        (effects (font (size 0.7 0.7) (thickness 0.15)) (justify left bottom))
    )
    (fp_text user "${REFERENCE}" (at -0.932 3.168) (layer "F.Fab") hide
        (effects (font (size 0.7 0.7) (thickness 0.15)) (justify left bottom))
    )
    (fp_text user "License: Apache-2.0" (at -0.932 5.17) (layer "F.Fab") hide
        (effects (font (size 0.7 0.7) (thickness 0.15)) (justify left bottom))
    )
    (fp_text user "Author: Antmicro" (at -0.932 4.17) (layer "F.Fab") hide
        (effects (font (size 0.7 0.7) (thickness 0.15)) (justify left bottom))
    )
    (fp_rect (start -0.94 -0.47) (end 0.94 0.47)
      (stroke (width 0.05) (type solid)) (fill none) (layer "F.CrtYd"))
    (fp_rect (start -0.499 -0.249) (end 0.499 0.249)
      (stroke (width 0.15) (type solid)) (fill none) (layer "F.Fab"))
    (pad "1" smd roundrect (at -0.484 0) (size 0.59 0.64) (layers "F.Cu" "F.Paste" "F.Mask") (roundrect_rratio 0.25)
      (net 513 "/FMC HPC/GTX_TX7_C_P") (pintype "passive"))
    (pad "2" smd roundrect (at 0.484 0) (size 0.59 0.64) (layers "F.Cu" "F.Paste" "F.Mask") (roundrect_rratio 0.25)
      (net 524 "GTX_TX7_P") (pintype "passive"))
  )

  (footprint "data-center-rdimm-ddr4-tester-footprints:SW_DS04-254-1-01BK-SMT" (layer "F.Cu")
    (at 222.225 79.13 180)
    (property "Author" "Antmicro")
    (property "License" "Apache-2.0")
    (property "MPN" "DS04-254-1-01BK-SMT")
    (property "Manufacturer" "CUI Inc")
    (property "Sheetfile" "config-spi.kicad_sch")
    (property "Sheetname" "Config SPI flash")
    (property "ki_description" "Slide switch")
    (property "ki_keywords" "HORIZONTAL, SMT, SWITCH, MECHANICAL, SLIDE")
    (attr smd)
    (fp_text reference "S2" (at 3.485 2.25) (layer "F.SilkS")
        (effects (font (size 0.7 0.7) (thickness 0.15)) (justify left bottom))
    )
    (fp_text value "SW_DS04-254-1-01BK-SMT" (at 0 3) (layer "F.Fab")
        (effects (font (size 0.7 0.7) (thickness 0.15)) (justify right bottom))
    )
    (fp_text user "Author: Antmicro" (at -5.25 5.6) (layer "F.Fab") hide
        (effects (font (size 0.7 0.7) (thickness 0.15)) (justify right bottom))
    )
    (fp_text user "License: Apache-2.0" (at -5.25 6.799) (layer "F.Fab") hide
        (effects (font (size 0.7 0.7) (thickness 0.15)) (justify right bottom))
    )
    (fp_text user "${REFERENCE}" (at -5.25 4.4) (layer "F.Fab") hide
        (effects (font (size 0.7 0.7) (thickness 0.15)) (justify right bottom))
    )
    (fp_rect (start -3.3 -2) (end 3.3 2)
      (stroke (width 0.15) (type solid)) (fill none) (layer "F.SilkS"))
    (fp_rect (start -5.25 -2.025) (end 5.25 2.025)
      (stroke (width 0.05) (type solid)) (fill none) (layer "F.CrtYd"))
    (fp_rect (start -3.1 -1.8) (end 3.1 1.8)
      (stroke (width 0.15) (type solid)) (fill none) (layer "F.Fab"))
    (pad "1" smd rect (at -4.472 0.038 180) (size 1.5 1.1) (layers "F.Cu" "F.Paste" "F.Mask")
      (net 18 "MODE2") (pintype "passive"))
    (pad "2" smd rect (at 4.428 0.038) (size 1.5 1.1) (layers "F.Cu" "F.Paste" "F.Mask")
      (net 9 "GND") (pintype "passive"))
  )

  (footprint "data-center-rdimm-ddr4-tester-footprints:R_0201" (layer "F.Cu")
    (at 156.05 109.03 90)
    (descr "Resistor SMD 0201")
    (tags "resistor SMD 0201")
    (property "Author" "Antmicro")
    (property "License" "Apache-2.0")
    (property "MPN" "CR0201-FX-0R00GLF")
    (property "Manufacturer" "Bourns")
    (property "Sheetfile" "ethernet.kicad_sch")
    (property "Sheetname" "Ethernet")
    (property "Tolerance" "1%")
    (property "Val" "0R")
    (property "ki_description" "0R resistor in 0201 package with 1% tolerance")
    (attr smd)
    (fp_text reference "R106" (at -3.48 0.37 90) (layer "F.SilkS")
        (effects (font (size 0.7 0.7) (thickness 0.15)) (justify left bottom))
    )
    (fp_text value "R_0R_0201" (at 0 1.25 90) (layer "F.Fab") hide
        (effects (font (size 0.7 0.7) (thickness 0.15)) (justify left bottom))
    )
    (fp_text user "License: Apache-2.0" (at -0.71 4.25 90) (layer "F.Fab") hide
        (effects (font (size 0.7 0.7) (thickness 0.15)) (justify left bottom))
    )
    (fp_text user "${REFERENCE}" (at -0.71 3.25 90) (layer "F.Fab") hide
        (effects (font (size 0.7 0.7) (thickness 0.15)) (justify left bottom))
    )
    (fp_text user "Author: Antmicro" (at -0.71 5.25 90) (layer "F.Fab") hide
        (effects (font (size 0.7 0.7) (thickness 0.15)) (justify left bottom))
    )
    (fp_rect (start -0.71 -0.36) (end 0.71 0.36)
      (stroke (width 0.05) (type solid)) (fill none) (layer "F.CrtYd"))
    (fp_rect (start -0.3 -0.15) (end 0.298 0.148)
      (stroke (width 0.15) (type solid)) (fill none) (layer "F.Fab"))
    (pad "" smd roundrect (at -0.346 0 90) (size 0.318 0.36) (layers "F.Paste") (roundrect_rratio 0.25))
    (pad "" smd roundrect (at 0.344 0 90) (size 0.318 0.36) (layers "F.Paste") (roundrect_rratio 0.25))
    (pad "1" smd roundrect (at -0.32 0 90) (size 0.46 0.4) (layers "F.Cu" "F.Mask") (roundrect_rratio 0.25)
      (net 630 "/Ethernet/INT_ETH1_N") (pintype "passive"))
    (pad "2" smd roundrect (at 0.32 0 90) (size 0.46 0.4) (layers "F.Cu" "F.Mask") (roundrect_rratio 0.25)
      (net 825 "/Ethernet/ETH1_BP_N") (pintype "passive"))
  )

  (footprint "data-center-rdimm-ddr4-tester-footprints:NetTie-2_SMD_Pad0.127mm" (layer "F.Cu")
    (at 130.7 84.234 -90)
    (descr "Net tie, 2 pin, 0.127mm  SMD pads")
    (tags "net tie")
    (property "Author" "Antmicro")
    (property "License" "Apache-2.0")
    (property "MPN" "")
    (property "Manufacturer" "")
    (property "Sheetfile" "supply.kicad_sch")
    (property "Sheetname" "Supply")
    (property "ki_description" "Net tie, 2 pins")
    (property "ki_keywords" "net tie short")
    (attr through_hole exclude_from_pos_files)
    (net_tie_pad_groups "1, 2")
    (fp_text reference "NT9" (at -0.128 -1.345 -90) (layer "F.SilkS") hide
        (effects (font (size 0.7 0.7) (thickness 0.15)) (justify left bottom))
    )
    (fp_text value "Net-Tie_2" (at 0 1.199 -90) (layer "F.Fab") hide
        (effects (font (size 0.7 0.7) (thickness 0.15)) (justify left bottom))
    )
    (fp_text user "Author: Antmicro" (at -0.128 4.4 -90) (layer "F.Fab") hide
        (effects (font (size 0.7 0.7) (thickness 0.15)) (justify left bottom))
    )
    (fp_text user "${REFERENCE}" (at -0.128 3.2 -90) (layer "F.Fab") hide
        (effects (font (size 0.7 0.7) (thickness 0.15)) (justify left bottom))
    )
    (fp_text user "License: Apache-2.0" (at -0.128 5.6 -90) (layer "F.Fab") hide
        (effects (font (size 0.7 0.7) (thickness 0.15)) (justify left bottom))
    )
    (fp_poly
      (pts
        (xy -0.0635 -0.0635)
        (xy 0.0625 -0.0635)
        (xy 0.0625 0.0635)
        (xy -0.0635 0.0635)
      )

      (stroke (width 0) (type solid)) (fill solid) (layer "F.Cu"))
    (pad "1" smd roundrect (at -0.127 0 90) (size 0.127 0.127) (layers "F.Cu") (roundrect_rratio 0.5)
      (chamfer_ratio 0) (chamfer top_left bottom_left)
      (net 840 "/Supply/1V8_SEN_+") (pinfunction "1") (pintype "passive"))
    (pad "2" smd roundrect (at 0.126 0 270) (size 0.127 0.127) (layers "F.Cu") (roundrect_rratio 0.5)
      (chamfer_ratio 0) (chamfer top_left bottom_left)
      (net 302 "VCC1V8") (pinfunction "2") (pintype "passive"))
  )

  (footprint "data-center-rdimm-ddr4-tester-footprints:SOT-23-3" (layer "F.Cu")
    (at 235.7 123.3)
    (property "Author" "Antmicro")
    (property "License" "Apache-2.0")
    (property "MPN" "BZX84C5V1-TP")
    (property "Manufacturer" "Micro Commercial Co")
    (property "Sheetfile" "supply.kicad_sch")
    (property "Sheetname" "Supply")
    (property "ki_description" "DIODE ZENER 5.1V 350MW SOT23")
    (attr smd)
    (fp_text reference "D19" (at -1.55 2.51) (layer "F.SilkS")
        (effects (font (size 0.7 0.7) (thickness 0.15)) (justify left bottom))
    )
    (fp_text value "BZX84C5V1-TP" (at -1.9 2.7) (layer "F.Fab") hide
        (effects (font (size 0.7 0.7) (thickness 0.15)) (justify left bottom))
    )
    (fp_text user "Author: Antmicro" (at -1.837 5.3) (layer "F.Fab") hide
        (effects (font (size 0.7 0.7) (thickness 0.15)) (justify left bottom))
    )
    (fp_text user "${REFERENCE}" (at -1.837 4) (layer "F.Fab") hide
        (effects (font (size 0.7 0.7) (thickness 0.15)) (justify left bottom))
    )
    (fp_text user "License: Apache-2.0" (at -1.8 6.8) (layer "F.Fab") hide
        (effects (font (size 0.7 0.7) (thickness 0.15)) (justify left bottom))
    )
    (fp_line (start -1.45 -1.35) (end -0.85 -1.35)
      (stroke (width 0.15) (type solid)) (layer "F.SilkS"))
    (fp_line (start -0.85 -1.35) (end -0.7 -1.5)
      (stroke (width 0.15) (type solid)) (layer "F.SilkS"))
    (fp_line (start -0.7 1.5) (end -0.7 1.35)
      (stroke (width 0.15) (type solid)) (layer "F.SilkS"))
    (fp_line (start 0.7 -1.5) (end -0.7 -1.5)
      (stroke (width 0.15) (type solid)) (layer "F.SilkS"))
    (fp_line (start 0.7 -0.4) (end 0.7 -1.5)
      (stroke (width 0.15) (type solid)) (layer "F.SilkS"))
    (fp_line (start 0.7 0.4) (end 0.7 1.5)
      (stroke (width 0.15) (type solid)) (layer "F.SilkS"))
    (fp_line (start 0.7 1.5) (end -0.7 1.5)
      (stroke (width 0.15) (type solid)) (layer "F.SilkS"))
    (fp_line (start -1.75 -0.5) (end -1.75 -1.4)
      (stroke (width 0.05) (type solid)) (layer "F.CrtYd"))
    (fp_line (start -1.75 0.5) (end -0.85 0.5)
      (stroke (width 0.05) (type solid)) (layer "F.CrtYd"))
    (fp_line (start -1.75 1.4) (end -1.75 0.5)
      (stroke (width 0.05) (type solid)) (layer "F.CrtYd"))
    (fp_line (start -0.9 -1.6) (end -0.9 -1.4)
      (stroke (width 0.05) (type solid)) (layer "F.CrtYd"))
    (fp_line (start -0.9 -1.6) (end 0.825 -1.6)
      (stroke (width 0.05) (type solid)) (layer "F.CrtYd"))
    (fp_line (start -0.9 -1.4) (end -1.75 -1.4)
      (stroke (width 0.05) (type solid)) (layer "F.CrtYd"))
    (fp_line (start -0.85 -0.5) (end -1.75 -0.5)
      (stroke (width 0.05) (type solid)) (layer "F.CrtYd"))
    (fp_line (start -0.85 0.5) (end -0.85 -0.5)
      (stroke (width 0.05) (type solid)) (layer "F.CrtYd"))
    (fp_line (start -0.85 1.4) (end -1.75 1.4)
      (stroke (width 0.05) (type solid)) (layer "F.CrtYd"))
    (fp_line (start -0.85 1.65) (end -0.85 1.4)
      (stroke (width 0.05) (type solid)) (layer "F.CrtYd"))
    (fp_line (start 0.825 -1.6) (end 0.825 -0.45)
      (stroke (width 0.05) (type solid)) (layer "F.CrtYd"))
    (fp_line (start 0.825 -0.45) (end 1.75 -0.45)
      (stroke (width 0.05) (type solid)) (layer "F.CrtYd"))
    (fp_line (start 0.85 0.45) (end 0.85 1.65)
      (stroke (width 0.05) (type solid)) (layer "F.CrtYd"))
    (fp_line (start 0.85 1.65) (end -0.85 1.65)
      (stroke (width 0.05) (type solid)) (layer "F.CrtYd"))
    (fp_line (start 1.75 -0.45) (end 1.75 0.45)
      (stroke (width 0.05) (type solid)) (layer "F.CrtYd"))
    (fp_line (start 1.75 0.45) (end 0.85 0.45)
      (stroke (width 0.05) (type solid)) (layer "F.CrtYd"))
    (fp_line (start -0.712 -1.325) (end -0.712 1.523)
      (stroke (width 0.15) (type solid)) (layer "F.Fab"))
    (fp_line (start -0.712 1.519) (end 0.688 1.519)
      (stroke (width 0.15) (type solid)) (layer "F.Fab"))
    (fp_line (start -0.437 -1.526) (end -0.712 -1.325)
      (stroke (width 0.15) (type solid)) (layer "F.Fab"))
    (fp_line (start -0.437 -1.526) (end 0.688 -1.526)
      (stroke (width 0.15) (type solid)) (layer "F.Fab"))
    (fp_line (start 0.688 1.519) (end 0.688 -1.52)
      (stroke (width 0.15) (type solid)) (layer "F.Fab"))
    (pad "1" smd roundrect (at -1.1 -0.951) (size 1 0.6) (layers "F.Cu" "F.Paste" "F.Mask") (roundrect_rratio 0.15)
      (net 9 "GND") (pinfunction "1") (pintype "passive"))
    (pad "2" smd roundrect (at -1.1 0.949) (size 1 0.6) (layers "F.Cu" "F.Paste" "F.Mask") (roundrect_rratio 0.15)
      (net 623 "unconnected-(D19-Pad2)") (pinfunction "2") (pintype "no_connect"))
    (pad "3" smd roundrect (at 1.1 -0.0005) (size 1 0.6) (layers "F.Cu" "F.Paste" "F.Mask") (roundrect_rratio 0.15)
      (net 108 "Net-(U27-~{OE})") (pinfunction "3") (pintype "passive"))
  )

  (footprint "data-center-rdimm-ddr4-tester-footprints:C_0402_1005Metric" (layer "F.Cu")
    (at 159.4 108.8 90)
    (descr "Capacitor SMD 0402")
    (tags "capacitor SMD 0402")
    (property "Author" "Antmicro")
    (property "DNP" "DNP")
    (property "Dielectric" "X5R")
    (property "License" "Apache-2.0")
    (property "MPN" "GRM155R61H104KE14D")
    (property "Manufacturer" "Murata")
    (property "Sheetfile" "ethernet.kicad_sch")
    (property "Sheetname" "Ethernet")
    (property "Val" "100n")
    (property "Voltage" "50V")
    (property "dnp" "")
    (property "exclude_from_bom" "")
    (property "ki_description" " ")
    (attr exclude_from_pos_files exclude_from_bom)
    (fp_text reference "C287" (at -3.72 0.42 90) (layer "F.SilkS")
        (effects (font (size 0.7 0.7) (thickness 0.15)) (justify left bottom))
    )
    (fp_text value "C_100n_0402" (at 0 1.4 90) (layer "F.Fab") hide
        (effects (font (size 0.7 0.7) (thickness 0.15)) (justify left bottom))
    )
    (fp_text user "Author: Antmicro" (at -0.932 4.17 90) (layer "F.Fab") hide
        (effects (font (size 0.7 0.7) (thickness 0.15)) (justify left bottom))
    )
    (fp_text user "License: Apache-2.0" (at -0.932 5.17 90) (layer "F.Fab") hide
        (effects (font (size 0.7 0.7) (thickness 0.15)) (justify left bottom))
    )
    (fp_text user "${REFERENCE}" (at -0.932 3.168 90) (layer "F.Fab") hide
        (effects (font (size 0.7 0.7) (thickness 0.15)) (justify left bottom))
    )
    (fp_rect (start -0.94 -0.47) (end 0.94 0.47)
      (stroke (width 0.05) (type solid)) (fill none) (layer "F.CrtYd"))
    (fp_rect (start -0.499 -0.249) (end 0.499 0.249)
      (stroke (width 0.15) (type solid)) (fill none) (layer "F.Fab"))
    (pad "1" smd roundrect (at -0.484 0 90) (size 0.59 0.64) (layers "F.Cu" "F.Paste" "F.Mask") (roundrect_rratio 0.25)
      (net 143 "3V3_SYS") (pintype "passive"))
    (pad "2" smd roundrect (at 0.484 0 90) (size 0.59 0.64) (layers "F.Cu" "F.Paste" "F.Mask") (roundrect_rratio 0.25)
      (net 9 "GND") (pintype "passive"))
  )

  (footprint "data-center-rdimm-ddr4-tester-footprints:C_0402_1005Metric" (layer "F.Cu")
    (at 110.883 110.6 180)
    (descr "Capacitor SMD 0402")
    (tags "capacitor SMD 0402")
    (property "Author" "Antmicro")
    (property "Dielectric" "X5R")
    (property "License" "Apache-2.0")
    (property "MPN" "GRM155R61H104KE14D")
    (property "Manufacturer" "Murata")
    (property "Sheetfile" "supply.kicad_sch")
    (property "Sheetname" "Supply")
    (property "Val" "100n")
    (property "Voltage" "50V")
    (property "ki_description" " ")
    (attr smd)
    (fp_text reference "C30" (at 3.043 0 180) (layer "F.SilkS")
        (effects (font (size 0.7 0.7) (thickness 0.15)) (justify left bottom))
    )
    (fp_text value "C_100n_0402" (at 0 1.4 180) (layer "F.Fab") hide
        (effects (font (size 0.7 0.7) (thickness 0.15)) (justify left bottom))
    )
    (fp_text user "License: Apache-2.0" (at -0.932 5.17 180) (layer "F.Fab") hide
        (effects (font (size 0.7 0.7) (thickness 0.15)) (justify left bottom))
    )
    (fp_text user "Author: Antmicro" (at -0.932 4.17 180) (layer "F.Fab") hide
        (effects (font (size 0.7 0.7) (thickness 0.15)) (justify left bottom))
    )
    (fp_text user "${REFERENCE}" (at -0.932 3.168 180) (layer "F.Fab") hide
        (effects (font (size 0.7 0.7) (thickness 0.15)) (justify left bottom))
    )
    (fp_rect (start -0.94 -0.47) (end 0.94 0.47)
      (stroke (width 0.05) (type solid)) (fill none) (layer "F.CrtYd"))
    (fp_rect (start -0.499 -0.249) (end 0.499 0.249)
      (stroke (width 0.15) (type solid)) (fill none) (layer "F.Fab"))
    (pad "1" smd roundrect (at -0.484 0 180) (size 0.59 0.64) (layers "F.Cu" "F.Paste" "F.Mask") (roundrect_rratio 0.25)
      (net 103 "VIN") (pintype "passive"))
    (pad "2" smd roundrect (at 0.484 0 180) (size 0.59 0.64) (layers "F.Cu" "F.Paste" "F.Mask") (roundrect_rratio 0.25)
      (net 9 "GND") (pintype "passive"))
  )

  (footprint "data-center-rdimm-ddr4-tester-footprints:C_0402_1005Metric" (layer "F.Cu")
    (at 256.18 79.181 180)
    (descr "Capacitor SMD 0402")
    (tags "capacitor SMD 0402")
    (property "Author" "Antmicro")
    (property "Dielectric" "X5R")
    (property "License" "Apache-2.0")
    (property "MPN" "GRM155R61H104KE14D")
    (property "Manufacturer" "Murata")
    (property "Sheetfile" "fmc_hpc.kicad_sch")
    (property "Sheetname" "FMC HPC")
    (property "Val" "100n")
    (property "Voltage" "50V")
    (property "ki_description" " ")
    (attr smd)
    (fp_text reference "C272" (at -0.74 -0.409 180) (layer "F.SilkS")
        (effects (font (size 0.7 0.7) (thickness 0.15)) (justify left bottom))
    )
    (fp_text value "C_100n_0402" (at 0 1.4 180) (layer "F.Fab") hide
        (effects (font (size 0.7 0.7) (thickness 0.15)) (justify left bottom))
    )
    (fp_text user "Author: Antmicro" (at -0.932 4.17 180) (layer "F.Fab") hide
        (effects (font (size 0.7 0.7) (thickness 0.15)) (justify left bottom))
    )
    (fp_text user "${REFERENCE}" (at -0.932 3.168 180) (layer "F.Fab") hide
        (effects (font (size 0.7 0.7) (thickness 0.15)) (justify left bottom))
    )
    (fp_text user "License: Apache-2.0" (at -0.932 5.17 180) (layer "F.Fab") hide
        (effects (font (size 0.7 0.7) (thickness 0.15)) (justify left bottom))
    )
    (fp_rect (start -0.94 -0.47) (end 0.94 0.47)
      (stroke (width 0.05) (type solid)) (fill none) (layer "F.CrtYd"))
    (fp_rect (start -0.499 -0.249) (end 0.499 0.249)
      (stroke (width 0.15) (type solid)) (fill none) (layer "F.Fab"))
    (pad "1" smd roundrect (at -0.484 0 180) (size 0.59 0.64) (layers "F.Cu" "F.Paste" "F.Mask") (roundrect_rratio 0.25)
      (net 512 "GTX_TX6_N") (pintype "passive"))
    (pad "2" smd roundrect (at 0.484 0 180) (size 0.59 0.64) (layers "F.Cu" "F.Paste" "F.Mask") (roundrect_rratio 0.25)
      (net 499 "/FMC HPC/GTX_TX6_C_N") (pintype "passive"))
  )

  (footprint "data-center-rdimm-ddr4-tester-footprints:C_0402_1005Metric" (layer "F.Cu")
    (at 254.71 97.955 180)
    (descr "Capacitor SMD 0402")
    (tags "capacitor SMD 0402")
    (property "Author" "Antmicro")
    (property "Dielectric" "X5R")
    (property "License" "Apache-2.0")
    (property "MPN" "GRM155R61H104KE14D")
    (property "Manufacturer" "Murata")
    (property "Sheetfile" "fmc_hpc.kicad_sch")
    (property "Sheetname" "FMC HPC")
    (property "Val" "100n")
    (property "Voltage" "50V")
    (property "ki_description" " ")
    (attr smd)
    (fp_text reference "C261" (at 3.64 -0.365 180) (layer "F.SilkS")
        (effects (font (size 0.7 0.7) (thickness 0.15)) (justify left bottom))
    )
    (fp_text value "C_100n_0402" (at 0 1.4 180) (layer "F.Fab") hide
        (effects (font (size 0.7 0.7) (thickness 0.15)) (justify left bottom))
    )
    (fp_text user "License: Apache-2.0" (at -0.932 5.17 180) (layer "F.Fab") hide
        (effects (font (size 0.7 0.7) (thickness 0.15)) (justify left bottom))
    )
    (fp_text user "Author: Antmicro" (at -0.932 4.17 180) (layer "F.Fab") hide
        (effects (font (size 0.7 0.7) (thickness 0.15)) (justify left bottom))
    )
    (fp_text user "${REFERENCE}" (at -0.932 3.168 180) (layer "F.Fab") hide
        (effects (font (size 0.7 0.7) (thickness 0.15)) (justify left bottom))
    )
    (fp_rect (start -0.94 -0.47) (end 0.94 0.47)
      (stroke (width 0.05) (type solid)) (fill none) (layer "F.CrtYd"))
    (fp_rect (start -0.499 -0.249) (end 0.499 0.249)
      (stroke (width 0.15) (type solid)) (fill none) (layer "F.Fab"))
    (pad "1" smd roundrect (at -0.484 0 180) (size 0.59 0.64) (layers "F.Cu" "F.Paste" "F.Mask") (roundrect_rratio 0.25)
      (net 419 "/FMC HPC/GTX_TX1_C_P") (pintype "passive"))
    (pad "2" smd roundrect (at 0.484 0 180) (size 0.59 0.64) (layers "F.Cu" "F.Paste" "F.Mask") (roundrect_rratio 0.25)
      (net 420 "GTX_TX1_P") (pintype "passive"))
  )

  (footprint "data-center-rdimm-ddr4-tester-footprints:R_0201" (layer "F.Cu")
    (at 159.575 104.3 -90)
    (descr "Resistor SMD 0201")
    (tags "resistor SMD 0201")
    (property "Author" "Antmicro")
    (property "License" "Apache-2.0")
    (property "MPN" "CR0201-FX-0R00GLF")
    (property "Manufacturer" "Bourns")
    (property "Sheetfile" "ethernet.kicad_sch")
    (property "Sheetname" "Ethernet")
    (property "Tolerance" "1%")
    (property "Val" "0R")
    (property "ki_description" "0R resistor in 0201 package with 1% tolerance")
    (attr smd)
    (fp_text reference "R101" (at -0.65 -0.175 -90) (layer "F.SilkS")
        (effects (font (size 0.7 0.7) (thickness 0.15)) (justify left bottom))
    )
    (fp_text value "R_0R_0201" (at 0 1.25 -90) (layer "F.Fab") hide
        (effects (font (size 0.7 0.7) (thickness 0.15)) (justify left bottom))
    )
    (fp_text user "${REFERENCE}" (at -0.71 3.25 -90) (layer "F.Fab") hide
        (effects (font (size 0.7 0.7) (thickness 0.15)) (justify left bottom))
    )
    (fp_text user "License: Apache-2.0" (at -0.71 4.25 -90) (layer "F.Fab") hide
        (effects (font (size 0.7 0.7) (thickness 0.15)) (justify left bottom))
    )
    (fp_text user "Author: Antmicro" (at -0.71 5.25 -90) (layer "F.Fab") hide
        (effects (font (size 0.7 0.7) (thickness 0.15)) (justify left bottom))
    )
    (fp_rect (start -0.71 -0.36) (end 0.71 0.36)
      (stroke (width 0.05) (type solid)) (fill none) (layer "F.CrtYd"))
    (fp_rect (start -0.3 -0.15) (end 0.298 0.148)
      (stroke (width 0.15) (type solid)) (fill none) (layer "F.Fab"))
    (pad "" smd roundrect (at -0.346 0 270) (size 0.318 0.36) (layers "F.Paste") (roundrect_rratio 0.25))
    (pad "" smd roundrect (at 0.344 0 270) (size 0.318 0.36) (layers "F.Paste") (roundrect_rratio 0.25))
    (pad "1" smd roundrect (at -0.32 0 270) (size 0.46 0.4) (layers "F.Cu" "F.Mask") (roundrect_rratio 0.25)
      (net 168 "/Ethernet/ETH3_P") (pintype "passive"))
    (pad "2" smd roundrect (at 0.32 0 270) (size 0.46 0.4) (layers "F.Cu" "F.Mask") (roundrect_rratio 0.25)
      (net 828 "/Ethernet/ETH3_BP_P") (pintype "passive"))
  )

  (footprint "data-center-rdimm-ddr4-tester-footprints:Fiducial_1mm_Mask2mm" (layer "F.Cu")
    (at 110.15 128)
    (descr "Circular Fiducial, 1mm bare copper, 3mm soldermask opening")
    (tags "fiducial")
    (property "Author" "Antmicro")
    (property "License" "Apache-2.0")
    (property "MPN" "")
    (property "Manufacturer" "")
    (property "Sheetfile" "data-center-rdimm-ddr4-tester.kicad_sch")
    (property "Sheetname" "")
    (property "exclude_from_bom" "")
    (property "ki_description" "Fiducial Marker for use with single board only")
    (attr exclude_from_pos_files exclude_from_bom)
    (fp_text reference "FID2" (at 2.44 1.09 90) (layer "F.SilkS")
        (effects (font (size 0.7 0.7) (thickness 0.15)) (justify left bottom))
    )
    (fp_text value "Fiducial_1mm_Mask2mm" (at 0 2.2) (layer "F.Fab")
        (effects (font (size 0.7 0.7) (thickness 0.15)) (justify left bottom))
    )
    (fp_text user "${REFERENCE}" (at -1.25 4.603) (layer "F.Fab") hide
        (effects (font (size 0.7 0.7) (thickness 0.15)) (justify left bottom))
    )
    (fp_text user "License: Apache-2.0" (at -1.25 7.003) (layer "F.Fab") hide
        (effects (font (size 0.7 0.7) (thickness 0.15)) (justify left bottom))
    )
    (fp_text user "Author: Antmicro" (at -1.25 5.803) (layer "F.Fab") hide
        (effects (font (size 0.7 0.7) (thickness 0.15)) (justify left bottom))
    )
    (fp_circle (center 0 0) (end 1.24 0)
      (stroke (width 0.05) (type solid)) (fill none) (layer "F.CrtYd"))
    (fp_circle (center 0 0) (end 0.999 0)
      (stroke (width 0.15) (type solid)) (fill none) (layer "F.Fab"))
    (pad "" smd circle (at 0 0) (size 1 1) (layers "F.Cu" "F.Mask")
      (solder_mask_margin 0.5) (clearance 0.5))
  )

  (footprint "data-center-rdimm-ddr4-tester-footprints:R_0402_1005Metric" (layer "F.Cu")
    (at 250.9 119.815 180)
    (descr "Resistor SMD 0402")
    (tags "resistor SMD 0402")
    (property "Author" "Antmicro")
    (property "License" "Apache-2.0")
    (property "MPN" "CR0402-FX-33R0GLF")
    (property "Manufacturer" "Bourns")
    (property "Sheetfile" "fmc_hpc.kicad_sch")
    (property "Sheetname" "FMC HPC")
    (property "Tolerance" "1%")
    (property "Val" "33R")
    (property "ki_description" "33R resistor in 0402 package with 1% tolerance")
    (attr smd)
    (fp_text reference "R211" (at 1.03 1.565 180) (layer "F.SilkS")
        (effects (font (size 0.7 0.7) (thickness 0.15)) (justify left bottom))
    )
    (fp_text value "R_33R_0402" (at 0 1.4 180) (layer "F.Fab") hide
        (effects (font (size 0.7 0.7) (thickness 0.15)) (justify left bottom))
    )
    (fp_text user "License: Apache-2.0" (at -0.95 5.169 180) (layer "F.Fab") hide
        (effects (font (size 0.7 0.7) (thickness 0.15)) (justify left bottom))
    )
    (fp_text user "${REFERENCE}" (at -0.95 3.168 180) (layer "F.Fab") hide
        (effects (font (size 0.7 0.7) (thickness 0.15)) (justify left bottom))
    )
    (fp_text user "Author: Antmicro" (at -0.95 4.169 180) (layer "F.Fab") hide
        (effects (font (size 0.7 0.7) (thickness 0.15)) (justify left bottom))
    )
    (fp_rect (start -0.93 -0.47) (end 0.93 0.47)
      (stroke (width 0.05) (type solid)) (fill none) (layer "F.CrtYd"))
    (fp_rect (start -0.5 -0.25) (end 0.5 0.25)
      (stroke (width 0.15) (type solid)) (fill none) (layer "F.Fab"))
    (pad "1" smd roundrect (at -0.485 0 180) (size 0.59 0.64) (layers "F.Cu" "F.Paste" "F.Mask") (roundrect_rratio 0.25)
      (net 669 "/FMC HPC/GTR_REFCLK0_R_N") (pintype "passive"))
    (pad "2" smd roundrect (at 0.485 0 180) (size 0.59 0.64) (layers "F.Cu" "F.Paste" "F.Mask") (roundrect_rratio 0.25)
      (net 408 "GTR_REFCLK0_C_N") (pintype "passive"))
  )

  (footprint "data-center-rdimm-ddr4-tester-footprints:SC70-3" (layer "F.Cu")
    (at 221.8 122.7 180)
    (property "Author" "Antmicro")
    (property "License" "Apache-2.0")
    (property "MPN" "BSS138PW")
    (property "Manufacturer" "Nexperia")
    (property "Sheetfile" "supply.kicad_sch")
    (property "Sheetname" "Supply")
    (property "ki_description" "60 V, 320 mA N-channel enhancement mode Trench MOSFET, SC-70-3 aka SOT-323 package")
    (property "ki_keywords" "n-channel enhancement mosfet sc70 sc-70 sot-323 sot323")
    (attr smd)
    (fp_text reference "Q12" (at 1.04 1.27 180) (layer "F.SilkS")
        (effects (font (size 0.7 0.7) (thickness 0.15)) (justify left bottom))
    )
    (fp_text value "BSS138PW" (at 0 2.3 180) (layer "F.Fab") hide
        (effects (font (size 0.7 0.7) (thickness 0.15)) (justify left bottom))
    )
    (fp_text user "License: Apache-2.0" (at -1.45 6.782 180) (layer "F.Fab") hide
        (effects (font (size 0.7 0.7) (thickness 0.15)) (justify left bottom))
    )
    (fp_text user "Author: Antmicro" (at -1.45 5.782 180) (layer "F.Fab") hide
        (effects (font (size 0.7 0.7) (thickness 0.15)) (justify left bottom))
    )
    (fp_text user "${REFERENCE}" (at -1.45 4.783 180) (layer "F.Fab") hide
        (effects (font (size 0.7 0.7) (thickness 0.15)) (justify left bottom))
    )
    (fp_line (start -0.3 -1) (end 0.627 -0.999)
      (stroke (width 0.15) (type solid)) (layer "F.SilkS"))
    (fp_line (start -0.3 1) (end 0.627 1.001)
      (stroke (width 0.15) (type solid)) (layer "F.SilkS"))
    (fp_line (start 0.627 -0.6) (end 0.627 -0.999)
      (stroke (width 0.15) (type solid)) (layer "F.SilkS"))
    (fp_line (start 0.627 0.6) (end 0.627 1.001)
      (stroke (width 0.15) (type solid)) (layer "F.SilkS"))
    (fp_rect (start 1.4 1.3) (end -1.4 -1.3)
      (stroke (width 0.05) (type solid)) (fill none) (layer "F.CrtYd"))
    (fp_rect (start -0.623 -0.999) (end 0.627 1.001)
      (stroke (width 0.15) (type solid)) (fill none) (layer "F.Fab"))
    (pad "1" smd rect (at -0.95 -0.65 270) (size 0.6 0.8) (layers "F.Cu" "F.Paste" "F.Mask")
      (net 584 "Net-(Q12-G)") (pinfunction "G") (pintype "bidirectional"))
    (pad "2" smd rect (at -0.95 0.65 270) (size 0.6 0.8) (layers "F.Cu" "F.Paste" "F.Mask")
      (net 9 "GND") (pinfunction "S") (pintype "bidirectional"))
    (pad "3" smd rect (at 0.95 0 270) (size 0.6 0.8) (layers "F.Cu" "F.Paste" "F.Mask")
      (net 167 "/Supply/SYS_EN") (pinfunction "D") (pintype "bidirectional"))
  )

  (footprint "data-center-rdimm-ddr4-tester-footprints:R_0201" (layer "F.Cu")
    (at 161.825 104.29 90)
    (descr "Resistor SMD 0201")
    (tags "resistor SMD 0201")
    (property "Author" "Antmicro")
    (property "License" "Apache-2.0")
    (property "MPN" "CR0201-FX-0R00GLF")
    (property "Manufacturer" "Bourns")
    (property "Sheetfile" "ethernet.kicad_sch")
    (property "Sheetname" "Ethernet")
    (property "Tolerance" "1%")
    (property "Val" "0R")
    (property "ki_description" "0R resistor in 0201 package with 1% tolerance")
    (attr smd)
    (fp_text reference "R104" (at 0.59 0.575 90) (layer "F.SilkS")
        (effects (font (size 0.7 0.7) (thickness 0.15)) (justify left bottom))
    )
    (fp_text value "R_0R_0201" (at 0 1.25 90) (layer "F.Fab") hide
        (effects (font (size 0.7 0.7) (thickness 0.15)) (justify left bottom))
    )
    (fp_text user "${REFERENCE}" (at -0.71 3.25 90) (layer "F.Fab") hide
        (effects (font (size 0.7 0.7) (thickness 0.15)) (justify left bottom))
    )
    (fp_text user "Author: Antmicro" (at -0.71 5.25 90) (layer "F.Fab") hide
        (effects (font (size 0.7 0.7) (thickness 0.15)) (justify left bottom))
    )
    (fp_text user "License: Apache-2.0" (at -0.71 4.25 90) (layer "F.Fab") hide
        (effects (font (size 0.7 0.7) (thickness 0.15)) (justify left bottom))
    )
    (fp_rect (start -0.71 -0.36) (end 0.71 0.36)
      (stroke (width 0.05) (type solid)) (fill none) (layer "F.CrtYd"))
    (fp_rect (start -0.3 -0.15) (end 0.298 0.148)
      (stroke (width 0.15) (type solid)) (fill none) (layer "F.Fab"))
    (pad "" smd roundrect (at -0.346 0 90) (size 0.318 0.36) (layers "F.Paste") (roundrect_rratio 0.25))
    (pad "" smd roundrect (at 0.344 0 90) (size 0.318 0.36) (layers "F.Paste") (roundrect_rratio 0.25))
    (pad "1" smd roundrect (at -0.32 0 90) (size 0.46 0.4) (layers "F.Cu" "F.Mask") (roundrect_rratio 0.25)
      (net 831 "/Ethernet/ETH4_BP_N") (pintype "passive"))
    (pad "2" smd roundrect (at 0.32 0 90) (size 0.46 0.4) (layers "F.Cu" "F.Mask") (roundrect_rratio 0.25)
      (net 175 "/Ethernet/ETH4_N") (pintype "passive"))
  )

  (footprint "data-center-rdimm-ddr4-tester-footprints:C_0402_1005Metric" (layer "F.Cu")
    (at 254.71 96.955 180)
    (descr "Capacitor SMD 0402")
    (tags "capacitor SMD 0402")
    (property "Author" "Antmicro")
    (property "Dielectric" "X5R")
    (property "License" "Apache-2.0")
    (property "MPN" "GRM155R61H104KE14D")
    (property "Manufacturer" "Murata")
    (property "Sheetfile" "fmc_hpc.kicad_sch")
    (property "Sheetname" "FMC HPC")
    (property "Val" "100n")
    (property "Voltage" "50V")
    (property "ki_description" " ")
    (attr smd)
    (fp_text reference "C262" (at 3.64 -0.365 180) (layer "F.SilkS")
        (effects (font (size 0.7 0.7) (thickness 0.15)) (justify left bottom))
    )
    (fp_text value "C_100n_0402" (at 0 1.4 180) (layer "F.Fab") hide
        (effects (font (size 0.7 0.7) (thickness 0.15)) (justify left bottom))
    )
    (fp_text user "Author: Antmicro" (at -0.932 4.17 180) (layer "F.Fab") hide
        (effects (font (size 0.7 0.7) (thickness 0.15)) (justify left bottom))
    )
    (fp_text user "License: Apache-2.0" (at -0.932 5.17 180) (layer "F.Fab") hide
        (effects (font (size 0.7 0.7) (thickness 0.15)) (justify left bottom))
    )
    (fp_text user "${REFERENCE}" (at -0.932 3.168 180) (layer "F.Fab") hide
        (effects (font (size 0.7 0.7) (thickness 0.15)) (justify left bottom))
    )
    (fp_rect (start -0.94 -0.47) (end 0.94 0.47)
      (stroke (width 0.05) (type solid)) (fill none) (layer "F.CrtYd"))
    (fp_rect (start -0.499 -0.249) (end 0.499 0.249)
      (stroke (width 0.15) (type solid)) (fill none) (layer "F.Fab"))
    (pad "1" smd roundrect (at -0.484 0 180) (size 0.59 0.64) (layers "F.Cu" "F.Paste" "F.Mask") (roundrect_rratio 0.25)
      (net 421 "/FMC HPC/GTX_TX1_C_N") (pintype "passive"))
    (pad "2" smd roundrect (at 0.484 0 180) (size 0.59 0.64) (layers "F.Cu" "F.Paste" "F.Mask") (roundrect_rratio 0.25)
      (net 429 "GTX_TX1_N") (pintype "passive"))
  )

  (footprint "data-center-rdimm-ddr4-tester-footprints:R_0201" (layer "F.Cu")
    (at 151.35 106.775 -90)
    (descr "Resistor SMD 0201")
    (tags "resistor SMD 0201")
    (property "Author" "Antmicro")
    (property "License" "Apache-2.0")
    (property "MPN" "CR0201-FX-0R00GLF")
    (property "Manufacturer" "Bourns")
    (property "Sheetfile" "ethernet.kicad_sch")
    (property "Sheetname" "Ethernet")
    (property "Tolerance" "1%")
    (property "Val" "0R")
    (property "ki_description" "0R resistor in 0201 package with 1% tolerance")
    (attr smd)
    (fp_text reference "R222" (at -3.385 -0.4 90) (layer "F.SilkS")
        (effects (font (size 0.7 0.7) (thickness 0.15)) (justify right bottom))
    )
    (fp_text value "R_0R_0201" (at 0 1.25 90) (layer "F.Fab") hide
        (effects (font (size 0.7 0.7) (thickness 0.15)) (justify right bottom))
    )
    (fp_text user "${REFERENCE}" (at -0.71 3.25 90) (layer "F.Fab") hide
        (effects (font (size 0.7 0.7) (thickness 0.15)) (justify right bottom))
    )
    (fp_text user "Author: Antmicro" (at -0.71 5.25 90) (layer "F.Fab") hide
        (effects (font (size 0.7 0.7) (thickness 0.15)) (justify right bottom))
    )
    (fp_text user "License: Apache-2.0" (at -0.71 4.25 90) (layer "F.Fab") hide
        (effects (font (size 0.7 0.7) (thickness 0.15)) (justify right bottom))
    )
    (fp_rect (start -0.71 -0.36) (end 0.71 0.36)
      (stroke (width 0.05) (type solid)) (fill none) (layer "F.CrtYd"))
    (fp_rect (start -0.3 -0.15) (end 0.298 0.148)
      (stroke (width 0.15) (type solid)) (fill none) (layer "F.Fab"))
    (pad "" smd roundrect (at -0.346 0 270) (size 0.318 0.36) (layers "F.Paste") (roundrect_rratio 0.25))
    (pad "" smd roundrect (at 0.344 0 270) (size 0.318 0.36) (layers "F.Paste") (roundrect_rratio 0.25))
    (pad "1" smd roundrect (at -0.32 0 270) (size 0.46 0.4) (layers "F.Cu" "F.Mask") (roundrect_rratio 0.25)
      (net 17 "LED_SPD") (pintype "passive"))
    (pad "2" smd roundrect (at 0.32 0 270) (size 0.46 0.4) (layers "F.Cu" "F.Mask") (roundrect_rratio 0.25)
      (net 546 "INT_LED_SPD") (pintype "passive"))
  )

  (footprint "data-center-rdimm-ddr4-tester-footprints:LED_RGY_1.6x1.6mm_APTF1616" (layer "F.Cu")
    (at 251.666 76.898 180)
    (descr "1.6 x 1.6 mm Full-Color Surface Mount LED")
    (tags "LED")
    (property "Author" "Antmicro")
    (property "Description" "Standard LEDs - SMD RGY 1616 SMD")
    (property "License" "Apache-2.0")
    (property "MPN" "APTF1616SURKCGKSYKC")
    (property "Manufacturer" "Kingbright")
    (property "Sheetfile" "interfaces.kicad_sch")
    (property "Sheetname" "Interfaces")
    (property "ki_description" "Standard LEDs - SMD RGY 1616 SMD")
    (attr smd)
    (fp_text reference "D17" (at 1.8 1.2) (layer "F.SilkS")
        (effects (font (size 0.7 0.7) (thickness 0.15)) (justify left bottom))
    )
    (fp_text value "LED_RGY_0606_APTF1616SURKCGKSYKC" (at 0 2) (layer "F.Fab")
        (effects (font (size 0.7 0.7) (thickness 0.15)) (justify right bottom))
    )
    (fp_text user "License: Apache-2.0" (at -1.3 5.698) (layer "F.Fab") hide
        (effects (font (size 0.7 0.7) (thickness 0.15)) (justify right bottom))
    )
    (fp_text user "${REFERENCE}" (at -1.3 3.297) (layer "F.Fab") hide
        (effects (font (size 0.7 0.7) (thickness 0.15)) (justify right bottom))
    )
    (fp_text user "Author: Antmicro" (at -1.3 4.496) (layer "F.Fab") hide
        (effects (font (size 0.7 0.7) (thickness 0.15)) (justify right bottom))
    )
    (fp_line (start -0.8 -0.15) (end -0.801 0.15)
      (stroke (width 0.15) (type solid)) (layer "F.SilkS"))
    (fp_line (start -0.35 0.8) (end 0.35 0.8)
      (stroke (width 0.15) (type solid)) (layer "F.SilkS"))
    (fp_line (start 0.35 -0.802) (end -0.35 -0.802)
      (stroke (width 0.15) (type solid)) (layer "F.SilkS"))
    (fp_line (start 0.8 0.148) (end 0.8 -0.102)
      (stroke (width 0.15) (type solid)) (layer "F.SilkS"))
    (fp_circle (center -1.05 -0.95) (end -1.101 -0.999)
      (stroke (width 0.15) (type solid)) (fill solid) (layer "F.SilkS"))
    (fp_rect (start 1.3 1.1) (end -1.3 -1.1)
      (stroke (width 0.05) (type solid)) (fill none) (layer "F.CrtYd"))
    (fp_rect (start -0.801 -0.802) (end 0.8 0.801)
      (stroke (width 0.15) (type solid)) (fill none) (layer "F.Fab"))
    (pad "1" smd rect (at -0.874 -0.499 90) (size 0.5 0.85) (layers "F.Cu" "F.Paste" "F.Mask")
      (net 143 "3V3_SYS") (pinfunction "A") (pintype "passive"))
    (pad "2" smd rect (at 0.874 -0.499 90) (size 0.5 0.85) (layers "F.Cu" "F.Paste" "F.Mask")
      (net 101 "Net-(D17-C_{R})") (pinfunction "C_{R}") (pintype "passive"))
    (pad "3" smd rect (at 0.874 0.498 90) (size 0.5 0.85) (layers "F.Cu" "F.Paste" "F.Mask")
      (net 102 "Net-(D17-C_{G})") (pinfunction "C_{G}") (pintype "passive"))
    (pad "4" smd rect (at -0.874 0.498 90) (size 0.5 0.85) (layers "F.Cu" "F.Paste" "F.Mask")
      (net 106 "Net-(D17-C_{Y})") (pinfunction "C_{Y}") (pintype "passive"))
  )

  (footprint "data-center-rdimm-ddr4-tester-footprints:R_0201" (layer "F.Cu")
    (at 161.55 109.03 90)
    (descr "Resistor SMD 0201")
    (tags "resistor SMD 0201")
    (property "Author" "Antmicro")
    (property "License" "Apache-2.0")
    (property "MPN" "CR0201-FX-0R00GLF")
    (property "Manufacturer" "Bourns")
    (property "Sheetfile" "ethernet.kicad_sch")
    (property "Sheetname" "Ethernet")
    (property "Tolerance" "1%")
    (property "Val" "0R")
    (property "ki_description" "0R resistor in 0201 package with 1% tolerance")
    (attr smd)
    (fp_text reference "R110" (at -3.48 0.51 90) (layer "F.SilkS")
        (effects (font (size 0.7 0.7) (thickness 0.15)) (justify left bottom))
    )
    (fp_text value "R_0R_0201" (at 0 1.25 90) (layer "F.Fab") hide
        (effects (font (size 0.7 0.7) (thickness 0.15)) (justify left bottom))
    )
    (fp_text user "${REFERENCE}" (at -0.71 3.25 90) (layer "F.Fab") hide
        (effects (font (size 0.7 0.7) (thickness 0.15)) (justify left bottom))
    )
    (fp_text user "Author: Antmicro" (at -0.71 5.25 90) (layer "F.Fab") hide
        (effects (font (size 0.7 0.7) (thickness 0.15)) (justify left bottom))
    )
    (fp_text user "License: Apache-2.0" (at -0.71 4.25 90) (layer "F.Fab") hide
        (effects (font (size 0.7 0.7) (thickness 0.15)) (justify left bottom))
    )
    (fp_rect (start -0.71 -0.36) (end 0.71 0.36)
      (stroke (width 0.05) (type solid)) (fill none) (layer "F.CrtYd"))
    (fp_rect (start -0.3 -0.15) (end 0.298 0.148)
      (stroke (width 0.15) (type solid)) (fill none) (layer "F.Fab"))
    (pad "" smd roundrect (at -0.346 0 90) (size 0.318 0.36) (layers "F.Paste") (roundrect_rratio 0.25))
    (pad "" smd roundrect (at 0.344 0 90) (size 0.318 0.36) (layers "F.Paste") (roundrect_rratio 0.25))
    (pad "1" smd roundrect (at -0.32 0 90) (size 0.46 0.4) (layers "F.Cu" "F.Mask") (roundrect_rratio 0.25)
      (net 558 "/Ethernet/INT_ETH3_N") (pintype "passive"))
    (pad "2" smd roundrect (at 0.32 0 90) (size 0.46 0.4) (layers "F.Cu" "F.Mask") (roundrect_rratio 0.25)
      (net 829 "/Ethernet/ETH3_BP_N") (pintype "passive"))
  )

  (footprint "data-center-rdimm-ddr4-tester-footprints:R_0402_1005Metric" (layer "F.Cu")
    (at 221.85 125.4)
    (descr "Resistor SMD 0402")
    (tags "resistor SMD 0402")
    (property "Author" "Antmicro")
    (property "License" "Apache-2.0")
    (property "MPN" "CR0402-FX-4701GLF")
    (property "Manufacturer" "Bourns")
    (property "Sheetfile" "interfaces.kicad_sch")
    (property "Sheetname" "Interfaces")
    (property "Tolerance" "1%")
    (property "Val" "4k7")
    (property "ki_description" "4k7 resistor in 0402 package with 1% tolerance")
    (attr smd)
    (fp_text reference "R190" (at -1.41 -0.52) (layer "F.SilkS")
        (effects (font (size 0.7 0.7) (thickness 0.15)) (justify left bottom))
    )
    (fp_text value "R_4k7_0402" (at 0 1.4) (layer "F.Fab") hide
        (effects (font (size 0.7 0.7) (thickness 0.15)) (justify left bottom))
    )
    (fp_text user "Author: Antmicro" (at -0.95 4.169) (layer "F.Fab") hide
        (effects (font (size 0.7 0.7) (thickness 0.15)) (justify left bottom))
    )
    (fp_text user "License: Apache-2.0" (at -0.95 5.169) (layer "F.Fab") hide
        (effects (font (size 0.7 0.7) (thickness 0.15)) (justify left bottom))
    )
    (fp_text user "${REFERENCE}" (at -0.95 3.168) (layer "F.Fab") hide
        (effects (font (size 0.7 0.7) (thickness 0.15)) (justify left bottom))
    )
    (fp_rect (start -0.93 -0.47) (end 0.93 0.47)
      (stroke (width 0.05) (type solid)) (fill none) (layer "F.CrtYd"))
    (fp_rect (start -0.5 -0.25) (end 0.5 0.25)
      (stroke (width 0.15) (type solid)) (fill none) (layer "F.Fab"))
    (pad "1" smd roundrect (at -0.485 0) (size 0.59 0.64) (layers "F.Cu" "F.Paste" "F.Mask") (roundrect_rratio 0.25)
      (net 143 "3V3_SYS") (pintype "passive"))
    (pad "2" smd roundrect (at 0.485 0) (size 0.59 0.64) (layers "F.Cu" "F.Paste" "F.Mask") (roundrect_rratio 0.25)
      (net 149 "HOT_SWAP_BUTTON") (pintype "passive"))
  )

  (footprint "data-center-rdimm-ddr4-tester-footprints:NetTie-2_SMD_Pad0.127mm" (layer "F.Cu")
    (at 119.65 82.633 90)
    (descr "Net tie, 2 pin, 0.127mm  SMD pads")
    (tags "net tie")
    (property "Author" "Antmicro")
    (property "License" "Apache-2.0")
    (property "MPN" "")
    (property "Manufacturer" "")
    (property "Sheetfile" "supply.kicad_sch")
    (property "Sheetname" "Supply")
    (property "ki_description" "Net tie, 2 pins")
    (property "ki_keywords" "net tie short")
    (attr through_hole exclude_from_pos_files)
    (net_tie_pad_groups "1, 2")
    (fp_text reference "NT4" (at -0.128 -1.345 90) (layer "F.SilkS") hide
        (effects (font (size 0.7 0.7) (thickness 0.15)) (justify left bottom))
    )
    (fp_text value "Net-Tie_2" (at 0 1.199 90) (layer "F.Fab") hide
        (effects (font (size 0.7 0.7) (thickness 0.15)) (justify left bottom))
    )
    (fp_text user "Author: Antmicro" (at -0.128 4.4 90) (layer "F.Fab") hide
        (effects (font (size 0.7 0.7) (thickness 0.15)) (justify left bottom))
    )
    (fp_text user "${REFERENCE}" (at -0.128 3.2 90) (layer "F.Fab") hide
        (effects (font (size 0.7 0.7) (thickness 0.15)) (justify left bottom))
    )
    (fp_text user "License: Apache-2.0" (at -0.128 5.6 90) (layer "F.Fab") hide
        (effects (font (size 0.7 0.7) (thickness 0.15)) (justify left bottom))
    )
    (fp_poly
      (pts
        (xy -0.0635 -0.0635)
        (xy 0.0625 -0.0635)
        (xy 0.0625 0.0635)
        (xy -0.0635 0.0635)
      )

      (stroke (width 0) (type solid)) (fill solid) (layer "F.Cu"))
    (pad "1" smd roundrect (at -0.127 0 270) (size 0.127 0.127) (layers "F.Cu") (roundrect_rratio 0.5)
      (chamfer_ratio 0) (chamfer top_left bottom_left)
      (net 835 "/Supply/VDDQ_SEN_-") (pinfunction "1") (pintype "passive"))
    (pad "2" smd roundrect (at 0.126 0 90) (size 0.127 0.127) (layers "F.Cu") (roundrect_rratio 0.5)
      (chamfer_ratio 0) (chamfer top_left bottom_left)
      (net 77 "VDDQ") (pinfunction "2") (pintype "passive"))
  )

  (footprint "data-center-rdimm-ddr4-tester-footprints:NetTie-2_SMD_Pad0.127mm" (layer "F.Cu")
    (at 130.7 82.53 90)
    (descr "Net tie, 2 pin, 0.127mm  SMD pads")
    (tags "net tie")
    (property "Author" "Antmicro")
    (property "License" "Apache-2.0")
    (property "MPN" "")
    (property "Manufacturer" "")
    (property "Sheetfile" "supply.kicad_sch")
    (property "Sheetname" "Supply")
    (property "ki_description" "Net tie, 2 pins")
    (property "ki_keywords" "net tie short")
    (attr through_hole exclude_from_pos_files)
    (net_tie_pad_groups "1, 2")
    (fp_text reference "NT13" (at -0.128 -1.345 90) (layer "F.SilkS") hide
        (effects (font (size 0.7 0.7) (thickness 0.15)) (justify left bottom))
    )
    (fp_text value "Net-Tie_2" (at 0 1.199 90) (layer "F.Fab") hide
        (effects (font (size 0.7 0.7) (thickness 0.15)) (justify left bottom))
    )
    (fp_text user "Author: Antmicro" (at -0.128 4.4 90) (layer "F.Fab") hide
        (effects (font (size 0.7 0.7) (thickness 0.15)) (justify left bottom))
    )
    (fp_text user "License: Apache-2.0" (at -0.128 5.6 90) (layer "F.Fab") hide
        (effects (font (size 0.7 0.7) (thickness 0.15)) (justify left bottom))
    )
    (fp_text user "${REFERENCE}" (at -0.128 3.2 90) (layer "F.Fab") hide
        (effects (font (size 0.7 0.7) (thickness 0.15)) (justify left bottom))
    )
    (fp_poly
      (pts
        (xy -0.0635 -0.0635)
        (xy 0.0625 -0.0635)
        (xy 0.0625 0.0635)
        (xy -0.0635 0.0635)
      )

      (stroke (width 0) (type solid)) (fill solid) (layer "F.Cu"))
    (pad "1" smd roundrect (at -0.127 0 270) (size 0.127 0.127) (layers "F.Cu") (roundrect_rratio 0.5)
      (chamfer_ratio 0) (chamfer top_left bottom_left)
      (net 844 "/Supply/1V8_SEN_-") (pinfunction "1") (pintype "passive"))
    (pad "2" smd roundrect (at 0.126 0 90) (size 0.127 0.127) (layers "F.Cu") (roundrect_rratio 0.5)
      (chamfer_ratio 0) (chamfer top_left bottom_left)
      (net 144 "1V8_SYS") (pinfunction "2") (pintype "passive"))
  )

  (footprint "data-center-rdimm-ddr4-tester-footprints:R_0402_1005Metric" (layer "F.Cu")
    (at 250.9 120.815 180)
    (descr "Resistor SMD 0402")
    (tags "resistor SMD 0402")
    (property "Author" "Antmicro")
    (property "License" "Apache-2.0")
    (property "MPN" "CR0402-FX-33R0GLF")
    (property "Manufacturer" "Bourns")
    (property "Sheetfile" "fmc_hpc.kicad_sch")
    (property "Sheetname" "FMC HPC")
    (property "Tolerance" "1%")
    (property "Val" "33R")
    (property "ki_description" "33R resistor in 0402 package with 1% tolerance")
    (attr smd)
    (fp_text reference "R210" (at 1.03 1.565 180) (layer "F.SilkS")
        (effects (font (size 0.7 0.7) (thickness 0.15)) (justify left bottom))
    )
    (fp_text value "R_33R_0402" (at 0 1.4 180) (layer "F.Fab") hide
        (effects (font (size 0.7 0.7) (thickness 0.15)) (justify left bottom))
    )
    (fp_text user "${REFERENCE}" (at -0.95 3.168 180) (layer "F.Fab") hide
        (effects (font (size 0.7 0.7) (thickness 0.15)) (justify left bottom))
    )
    (fp_text user "Author: Antmicro" (at -0.95 4.169 180) (layer "F.Fab") hide
        (effects (font (size 0.7 0.7) (thickness 0.15)) (justify left bottom))
    )
    (fp_text user "License: Apache-2.0" (at -0.95 5.169 180) (layer "F.Fab") hide
        (effects (font (size 0.7 0.7) (thickness 0.15)) (justify left bottom))
    )
    (fp_rect (start -0.93 -0.47) (end 0.93 0.47)
      (stroke (width 0.05) (type solid)) (fill none) (layer "F.CrtYd"))
    (fp_rect (start -0.5 -0.25) (end 0.5 0.25)
      (stroke (width 0.15) (type solid)) (fill none) (layer "F.Fab"))
    (pad "1" smd roundrect (at -0.485 0 180) (size 0.59 0.64) (layers "F.Cu" "F.Paste" "F.Mask") (roundrect_rratio 0.25)
      (net 668 "/FMC HPC/GTR_REFCLK0_R_P") (pintype "passive"))
    (pad "2" smd roundrect (at 0.485 0 180) (size 0.59 0.64) (layers "F.Cu" "F.Paste" "F.Mask") (roundrect_rratio 0.25)
      (net 403 "GTR_REFCLK0_C_P") (pintype "passive"))
  )

  (footprint "data-center-rdimm-ddr4-tester-footprints:SW_1-1825027-1_THT" (layer "F.Cu")
    (at 234.156 131.6725)
    (descr "Tactile Switches, Round Actuator Style, NO, 5.74mm")
    (property "Author" "Antmicro")
    (property "License" "Apache-2.0")
    (property "MPN" "1-1825027-1")
    (property "Manufacturer" "TE Connectivity")
    (property "Sheetfile" "supply.kicad_sch")
    (property "Sheetname" "Supply")
    (property "ki_description" "Tactile Switch, Side Actuated, Through Hole, Round Button, 160 gf, 50mA at 24VDC")
    (property "ki_keywords" "HORIZONTAL, SWITCH, THT, MECHANICAL, TACTILE")
    (attr through_hole)
    (fp_text reference "S3" (at 7.144 2.9475 90) (layer "F.SilkS")
        (effects (font (size 0.7 0.7) (thickness 0.15)) (justify left bottom))
    )
    (fp_text value "SW_1-1825027-1" (at -2.4 9.6) (layer "F.Fab")
        (effects (font (size 0.7 0.7) (thickness 0.15)) (justify left bottom))
    )
    (fp_text user "${REFERENCE}" (at -2.452 11) (layer "F.Fab") hide
        (effects (font (size 0.7 0.7) (thickness 0.15)) (justify left bottom))
    )
    (fp_text user "Author: Antmicro" (at -2.452 12.4) (layer "F.Fab") hide
        (effects (font (size 0.7 0.7) (thickness 0.15)) (justify left bottom))
    )
    (fp_text user "License: Apache-2.0" (at -2.452 13.88) (layer "F.Fab") hide
        (effects (font (size 0.7 0.7) (thickness 0.15)) (justify left bottom))
    )
    (fp_line (start -1.331 -4.01) (end 5.828 -4.01)
      (stroke (width 0.15) (type solid)) (layer "F.SilkS"))
    (fp_line (start -1.307 2.548) (end -1.307 -0.485)
      (stroke (width 0.15) (type solid)) (layer "F.SilkS"))
    (fp_line (start 4.004 2.6) (end 0.494 2.6)
      (stroke (width 0.15) (type solid)) (layer "F.SilkS"))
    (fp_line (start 5.804 -0.5) (end 5.799 2.6)
      (stroke (width 0.15) (type solid)) (layer "F.SilkS"))
    (fp_line (start -1.6 -4.21) (end -1.6 2.89)
      (stroke (width 0.05) (type solid)) (layer "F.CrtYd"))
    (fp_line (start -1.6 2.89) (end 0.14 2.89)
      (stroke (width 0.05) (type solid)) (layer "F.CrtYd"))
    (fp_line (start 0.14 2.89) (end 0.14 8.58)
      (stroke (width 0.05) (type solid)) (layer "F.CrtYd"))
    (fp_line (start 0.14 8.58) (end 4.24 8.58)
      (stroke (width 0.05) (type solid)) (layer "F.CrtYd"))
    (fp_line (start 4.24 2.89) (end 6.1 2.89)
      (stroke (width 0.05) (type solid)) (layer "F.CrtYd"))
    (fp_line (start 4.24 8.58) (end 4.24 2.89)
      (stroke (width 0.05) (type solid)) (layer "F.CrtYd"))
    (fp_line (start 6.1 -4.21) (end -1.6 -4.21)
      (stroke (width 0.05) (type solid)) (layer "F.CrtYd"))
    (fp_line (start 6.1 2.89) (end 6.1 -4.21)
      (stroke (width 0.05) (type solid)) (layer "F.CrtYd"))
    (fp_line (start -1.307 -4.01) (end 5.804 -4.01)
      (stroke (width 0.15) (type solid)) (layer "F.Fab"))
    (fp_line (start -1.307 2.6) (end -1.307 -4.01)
      (stroke (width 0.15) (type solid)) (layer "F.Fab"))
    (fp_line (start 0.494 2.6) (end -1.307 2.6)
      (stroke (width 0.15) (type solid)) (layer "F.Fab"))
    (fp_line (start 0.494 2.6) (end 0.494 8.349)
      (stroke (width 0.15) (type solid)) (layer "F.Fab"))
    (fp_line (start 0.494 8.349) (end 4.004 8.349)
      (stroke (width 0.15) (type solid)) (layer "F.Fab"))
    (fp_line (start 4.004 8.349) (end 3.999 2.6)
      (stroke (width 0.15) (type solid)) (layer "F.Fab"))
    (fp_line (start 5.799 2.6) (end 3.999 2.6)
      (stroke (width 0.15) (type solid)) (layer "F.Fab"))
    (fp_line (start 5.804 -4.01) (end 5.804 2.6)
      (stroke (width 0.15) (type solid)) (layer "F.Fab"))
    (pad "1" thru_hole circle (at 0 0) (size 1.498 1.498) (drill 0.99) (layers "*.Cu" "*.Mask")
      (net 664 "Net-(U26-~{PB_IN})") (pinfunction "1") (pintype "passive"))
    (pad "2" thru_hole circle (at 4.498 0) (size 1.498 1.498) (drill 0.99) (layers "*.Cu" "*.Mask")
      (net 9 "GND") (pinfunction "2") (pintype "passive"))
    (pad "SH" thru_hole circle (at -1.256 -2.492) (size 1.95 1.95) (drill 1.3) (layers "*.Cu" "*.Mask")
      (net 9 "GND") (pinfunction "SH") (pintype "passive"))
    (pad "SH" thru_hole circle (at 5.754 -2.492) (size 1.95 1.95) (drill 1.3) (layers "*.Cu" "*.Mask")
      (net 9 "GND") (pinfunction "SH") (pintype "passive"))
  )

  (footprint "data-center-rdimm-ddr4-tester-footprints:C_0402_1005Metric" (layer "F.Cu")
    (at 115.975 96.6 180)
    (descr "Capacitor SMD 0402")
    (tags "capacitor SMD 0402")
    (property "Author" "Antmicro")
    (property "Dielectric" "")
    (property "License" "Apache-2.0")
    (property "MPN" "CC0402MRX5R5BB106")
    (property "Manufacturer" "Yaego")
    (property "Sheetfile" "supply.kicad_sch")
    (property "Sheetname" "Supply")
    (property "Val" "10u")
    (property "Voltage" "")
    (property "ki_description" " ")
    (attr smd)
    (fp_text reference "C33" (at 1.065 0.53 180) (layer "F.SilkS")
        (effects (font (size 0.7 0.7) (thickness 0.15)) (justify left bottom))
    )
    (fp_text value "C_10u_0402" (at 0 1.4 180) (layer "F.Fab") hide
        (effects (font (size 0.7 0.7) (thickness 0.15)) (justify left bottom))
    )
    (fp_text user "License: Apache-2.0" (at -0.932 5.17 180) (layer "F.Fab") hide
        (effects (font (size 0.7 0.7) (thickness 0.15)) (justify left bottom))
    )
    (fp_text user "Author: Antmicro" (at -0.932 4.17 180) (layer "F.Fab") hide
        (effects (font (size 0.7 0.7) (thickness 0.15)) (justify left bottom))
    )
    (fp_text user "${REFERENCE}" (at -0.932 3.168 180) (layer "F.Fab") hide
        (effects (font (size 0.7 0.7) (thickness 0.15)) (justify left bottom))
    )
    (fp_rect (start -0.94 -0.47) (end 0.94 0.47)
      (stroke (width 0.05) (type solid)) (fill none) (layer "F.CrtYd"))
    (fp_rect (start -0.499 -0.249) (end 0.499 0.249)
      (stroke (width 0.15) (type solid)) (fill none) (layer "F.Fab"))
    (pad "1" smd roundrect (at -0.484 0 180) (size 0.59 0.64) (layers "F.Cu" "F.Paste" "F.Mask") (roundrect_rratio 0.25)
      (net 301 "VDD1V2") (pintype "passive"))
    (pad "2" smd roundrect (at 0.484 0 180) (size 0.59 0.64) (layers "F.Cu" "F.Paste" "F.Mask") (roundrect_rratio 0.25)
      (net 9 "GND") (pintype "passive"))
  )

  (footprint "data-center-rdimm-ddr4-tester-footprints:NetTie-2_SMD_Pad0.127mm" (layer "F.Cu")
    (at 131.6 98.633 90)
    (descr "Net tie, 2 pin, 0.127mm  SMD pads")
    (tags "net tie")
    (property "Author" "Antmicro")
    (property "License" "Apache-2.0")
    (property "MPN" "")
    (property "Manufacturer" "")
    (property "Sheetfile" "supply.kicad_sch")
    (property "Sheetname" "Supply")
    (property "ki_description" "Net tie, 2 pins")
    (property "ki_keywords" "net tie short")
    (attr through_hole exclude_from_pos_files)
    (net_tie_pad_groups "1, 2")
    (fp_text reference "NT11" (at -0.128 -1.345 90) (layer "F.SilkS") hide
        (effects (font (size 0.7 0.7) (thickness 0.15)) (justify left bottom))
    )
    (fp_text value "Net-Tie_2" (at 0 1.199 90) (layer "F.Fab") hide
        (effects (font (size 0.7 0.7) (thickness 0.15)) (justify left bottom))
    )
    (fp_text user "${REFERENCE}" (at -0.128 3.2 90) (layer "F.Fab") hide
        (effects (font (size 0.7 0.7) (thickness 0.15)) (justify left bottom))
    )
    (fp_text user "Author: Antmicro" (at -0.128 4.4 90) (layer "F.Fab") hide
        (effects (font (size 0.7 0.7) (thickness 0.15)) (justify left bottom))
    )
    (fp_text user "License: Apache-2.0" (at -0.128 5.6 90) (layer "F.Fab") hide
        (effects (font (size 0.7 0.7) (thickness 0.15)) (justify left bottom))
    )
    (fp_poly
      (pts
        (xy -0.0635 -0.0635)
        (xy 0.0625 -0.0635)
        (xy 0.0625 0.0635)
        (xy -0.0635 0.0635)
      )

      (stroke (width 0) (type solid)) (fill solid) (layer "F.Cu"))
    (pad "1" smd roundrect (at -0.127 0 270) (size 0.127 0.127) (layers "F.Cu") (roundrect_rratio 0.5)
      (chamfer_ratio 0) (chamfer top_left bottom_left)
      (net 842 "/Supply/5V0_SEN_-") (pinfunction "1") (pintype "passive"))
    (pad "2" smd roundrect (at 0.126 0 90) (size 0.127 0.127) (layers "F.Cu") (roundrect_rratio 0.5)
      (chamfer_ratio 0) (chamfer top_left bottom_left)
      (net 307 "5V0_SYS") (pinfunction "2") (pintype "passive"))
  )

  (footprint "data-center-rdimm-ddr4-tester-footprints:NetTie-2_SMD_Pad0.127mm" (layer "F.Cu")
    (at 123.2 89.267 -90)
    (descr "Net tie, 2 pin, 0.127mm  SMD pads")
    (tags "net tie")
    (property "Author" "Antmicro")
    (property "License" "Apache-2.0")
    (property "MPN" "")
    (property "Manufacturer" "")
    (property "Sheetfile" "supply.kicad_sch")
    (property "Sheetname" "Supply")
    (property "ki_description" "Net tie, 2 pins")
    (property "ki_keywords" "net tie short")
    (attr through_hole exclude_from_pos_files)
    (net_tie_pad_groups "1, 2")
    (fp_text reference "NT1" (at -0.128 -1.345 -90) (layer "F.SilkS") hide
        (effects (font (size 0.7 0.7) (thickness 0.15)) (justify left bottom))
    )
    (fp_text value "Net-Tie_2" (at 0 1.199 -90) (layer "F.Fab") hide
        (effects (font (size 0.7 0.7) (thickness 0.15)) (justify left bottom))
    )
    (fp_text user "License: Apache-2.0" (at -0.128 5.6 -90) (layer "F.Fab") hide
        (effects (font (size 0.7 0.7) (thickness 0.15)) (justify left bottom))
    )
    (fp_text user "Author: Antmicro" (at -0.128 4.4 -90) (layer "F.Fab") hide
        (effects (font (size 0.7 0.7) (thickness 0.15)) (justify left bottom))
    )
    (fp_text user "${REFERENCE}" (at -0.128 3.2 -90) (layer "F.Fab") hide
        (effects (font (size 0.7 0.7) (thickness 0.15)) (justify left bottom))
    )
    (fp_poly
      (pts
        (xy -0.0635 -0.0635)
        (xy 0.0625 -0.0635)
        (xy 0.0625 0.0635)
        (xy -0.0635 0.0635)
      )

      (stroke (width 0) (type solid)) (fill solid) (layer "F.Cu"))
    (pad "1" smd roundrect (at -0.127 0 90) (size 0.127 0.127) (layers "F.Cu") (roundrect_rratio 0.5)
      (chamfer_ratio 0) (chamfer top_left bottom_left)
      (net 832 "/Supply/VPP_SEN_+") (pinfunction "1") (pintype "passive"))
    (pad "2" smd roundrect (at 0.126 0 270) (size 0.127 0.127) (layers "F.Cu") (roundrect_rratio 0.5)
      (chamfer_ratio 0) (chamfer top_left bottom_left)
      (net 303 "VCC2V5") (pinfunction "2") (pintype "passive"))
  )

  (footprint "data-center-rdimm-ddr4-tester-footprints:C_0402_1005Metric" (layer "F.Cu")
    (at 254.71 81.715 180)
    (descr "Capacitor SMD 0402")
    (tags "capacitor SMD 0402")
    (property "Author" "Antmicro")
    (property "Dielectric" "X5R")
    (property "License" "Apache-2.0")
    (property "MPN" "GRM155R61H104KE14D")
    (property "Manufacturer" "Murata")
    (property "Sheetfile" "fmc_hpc.kicad_sch")
    (property "Sheetname" "FMC HPC")
    (property "Val" "100n")
    (property "Voltage" "50V")
    (property "ki_description" " ")
    (attr smd)
    (fp_text reference "C268" (at -0.78 -0.295 180) (layer "F.SilkS")
        (effects (font (size 0.7 0.7) (thickness 0.15)) (justify left bottom))
    )
    (fp_text value "C_100n_0402" (at 0 1.4 180) (layer "F.Fab") hide
        (effects (font (size 0.7 0.7) (thickness 0.15)) (justify left bottom))
    )
    (fp_text user "${REFERENCE}" (at -0.932 3.168 180) (layer "F.Fab") hide
        (effects (font (size 0.7 0.7) (thickness 0.15)) (justify left bottom))
    )
    (fp_text user "License: Apache-2.0" (at -0.932 5.17 180) (layer "F.Fab") hide
        (effects (font (size 0.7 0.7) (thickness 0.15)) (justify left bottom))
    )
    (fp_text user "Author: Antmicro" (at -0.932 4.17 180) (layer "F.Fab") hide
        (effects (font (size 0.7 0.7) (thickness 0.15)) (justify left bottom))
    )
    (fp_rect (start -0.94 -0.47) (end 0.94 0.47)
      (stroke (width 0.05) (type solid)) (fill none) (layer "F.CrtYd"))
    (fp_rect (start -0.499 -0.249) (end 0.499 0.249)
      (stroke (width 0.15) (type solid)) (fill none) (layer "F.Fab"))
    (pad "1" smd roundrect (at -0.484 0 180) (size 0.59 0.64) (layers "F.Cu" "F.Paste" "F.Mask") (roundrect_rratio 0.25)
      (net 466 "/FMC HPC/GTX_TX4_C_N") (pintype "passive"))
    (pad "2" smd roundrect (at 0.484 0 180) (size 0.59 0.64) (layers "F.Cu" "F.Paste" "F.Mask") (roundrect_rratio 0.25)
      (net 479 "GTX_TX4_N") (pintype "passive"))
  )

  (footprint "data-center-rdimm-ddr4-tester-footprints:C_0402_1005Metric" (layer "F.Cu")
    (at 254.175 120.86)
    (descr "Capacitor SMD 0402")
    (tags "capacitor SMD 0402")
    (property "Author" "Antmicro")
    (property "Dielectric" "X5R")
    (property "License" "Apache-2.0")
    (property "MPN" "GRM155R61H104KE14D")
    (property "Manufacturer" "Murata")
    (property "Sheetfile" "fmc_hpc.kicad_sch")
    (property "Sheetname" "FMC HPC")
    (property "Val" "100n")
    (property "Voltage" "50V")
    (property "ki_description" " ")
    (attr smd)
    (fp_text reference "C260" (at -1.315 -1.58) (layer "F.SilkS")
        (effects (font (size 0.7 0.7) (thickness 0.15)) (justify left bottom))
    )
    (fp_text value "C_100n_0402" (at 0 1.4) (layer "F.Fab") hide
        (effects (font (size 0.7 0.7) (thickness 0.15)) (justify left bottom))
    )
    (fp_text user "${REFERENCE}" (at -0.932 3.168) (layer "F.Fab") hide
        (effects (font (size 0.7 0.7) (thickness 0.15)) (justify left bottom))
    )
    (fp_text user "License: Apache-2.0" (at -0.932 5.17) (layer "F.Fab") hide
        (effects (font (size 0.7 0.7) (thickness 0.15)) (justify left bottom))
    )
    (fp_text user "Author: Antmicro" (at -0.932 4.17) (layer "F.Fab") hide
        (effects (font (size 0.7 0.7) (thickness 0.15)) (justify left bottom))
    )
    (fp_rect (start -0.94 -0.47) (end 0.94 0.47)
      (stroke (width 0.05) (type solid)) (fill none) (layer "F.CrtYd"))
    (fp_rect (start -0.499 -0.249) (end 0.499 0.249)
      (stroke (width 0.15) (type solid)) (fill none) (layer "F.Fab"))
    (pad "1" smd roundrect (at -0.484 0) (size 0.59 0.64) (layers "F.Cu" "F.Paste" "F.Mask") (roundrect_rratio 0.25)
      (net 412 "/FMC HPC/GTX_TX0_C_N") (pintype "passive"))
    (pad "2" smd roundrect (at 0.484 0) (size 0.59 0.64) (layers "F.Cu" "F.Paste" "F.Mask") (roundrect_rratio 0.25)
      (net 418 "GTX_TX0_N") (pintype "passive"))
  )

  (footprint "data-center-rdimm-ddr4-tester-footprints:R_0402_1005Metric" (layer "F.Cu")
    (at 238.3 122.8 -90)
    (descr "Resistor SMD 0402")
    (tags "resistor SMD 0402")
    (property "Author" "Antmicro")
    (property "DNP" "DNP")
    (property "License" "Apache-2.0")
    (property "MPN" "CR0402-FX-4702GLF")
    (property "Manufacturer" "Bourns")
    (property "Sheetfile" "supply.kicad_sch")
    (property "Sheetname" "Supply")
    (property "Tolerance" "1%")
    (property "Val" "47k")
    (property "dnp" "")
    (property "exclude_from_bom" "")
    (property "ki_description" "47k resistor in 0402 package with 1% tolerance")
    (attr exclude_from_pos_files exclude_from_bom)
    (fp_text reference "R118" (at -0.03 -1.32 -90) (layer "F.SilkS")
        (effects (font (size 0.7 0.7) (thickness 0.15)) (justify left bottom))
    )
    (fp_text value "R_47k_0402" (at 0 1.4 -90) (layer "F.Fab") hide
        (effects (font (size 0.7 0.7) (thickness 0.15)) (justify left bottom))
    )
    (fp_text user "${REFERENCE}" (at -0.95 3.168 -90) (layer "F.Fab") hide
        (effects (font (size 0.7 0.7) (thickness 0.15)) (justify left bottom))
    )
    (fp_text user "Author: Antmicro" (at -0.95 4.169 -90) (layer "F.Fab") hide
        (effects (font (size 0.7 0.7) (thickness 0.15)) (justify left bottom))
    )
    (fp_text user "License: Apache-2.0" (at -0.95 5.169 -90) (layer "F.Fab") hide
        (effects (font (size 0.7 0.7) (thickness 0.15)) (justify left bottom))
    )
    (fp_rect (start -0.93 -0.47) (end 0.93 0.47)
      (stroke (width 0.05) (type solid)) (fill none) (layer "F.CrtYd"))
    (fp_rect (start -0.5 -0.25) (end 0.5 0.25)
      (stroke (width 0.15) (type solid)) (fill none) (layer "F.Fab"))
    (pad "1" smd roundrect (at -0.485 0 270) (size 0.59 0.64) (layers "F.Cu" "F.Paste" "F.Mask") (roundrect_rratio 0.25)
      (net 864 "VIN_POE") (pintype "passive"))
    (pad "2" smd roundrect (at 0.485 0 270) (size 0.59 0.64) (layers "F.Cu" "F.Paste" "F.Mask") (roundrect_rratio 0.25)
      (net 108 "Net-(U27-~{OE})") (pintype "passive"))
  )

  (footprint "data-center-rdimm-ddr4-tester-footprints:mounting-hole-3mm-NPTH" (layer "F.Cu")
    (at 110 133)
    (property "Author" "Antmicro")
    (property "License" "Apache-2.0")
    (property "MPN" "")
    (property "Manufacturer" "")
    (property "Sheetfile" "data-center-rdimm-ddr4-tester.kicad_sch")
    (property "Sheetname" "")
    (attr through_hole)
    (fp_text reference "MP1" (at 0 -1.8) (layer "F.SilkS") hide
        (effects (font (size 0.7 0.7) (thickness 0.15)) (justify left bottom))
    )
    (fp_text value "PCB_Mount_Hole_3mm_NPTH" (at 0 2.3) (layer "F.Fab") hide
        (effects (font (size 0.7 0.7) (thickness 0.15)) (justify left bottom))
    )
    (fp_text user "Author: Antmicro" (at 0 5.95) (layer "F.Fab") hide
        (effects (font (size 0.7 0.7) (thickness 0.15)) (justify left bottom))
    )
    (fp_text user "License: Apache-2.0" (at 0 7.15) (layer "F.Fab") hide
        (effects (font (size 0.7 0.7) (thickness 0.15)) (justify left bottom))
    )
    (fp_text user "${REFERENCE}" (at 0 4.749) (layer "F.Fab") hide
        (effects (font (size 0.7 0.7) (thickness 0.15)) (justify left bottom))
    )
    (pad "" np_thru_hole circle (at 0 0) (size 3 3) (drill 3) (layers "*.Cu" "*.Mask"))
  )

  (footprint "data-center-rdimm-ddr4-tester-footprints:C_0402_1005Metric" (layer "F.Cu")
    (at 254.71 82.715 180)
    (descr "Capacitor SMD 0402")
    (tags "capacitor SMD 0402")
    (property "Author" "Antmicro")
    (property "Dielectric" "X5R")
    (property "License" "Apache-2.0")
    (property "MPN" "GRM155R61H104KE14D")
    (property "Manufacturer" "Murata")
    (property "Sheetfile" "fmc_hpc.kicad_sch")
    (property "Sheetname" "FMC HPC")
    (property "Val" "100n")
    (property "Voltage" "50V")
    (property "ki_description" " ")
    (attr smd)
    (fp_text reference "C267" (at -0.78 -0.295 180) (layer "F.SilkS")
        (effects (font (size 0.7 0.7) (thickness 0.15)) (justify left bottom))
    )
    (fp_text value "C_100n_0402" (at 0 1.4 180) (layer "F.Fab") hide
        (effects (font (size 0.7 0.7) (thickness 0.15)) (justify left bottom))
    )
    (fp_text user "${REFERENCE}" (at -0.932 3.168 180) (layer "F.Fab") hide
        (effects (font (size 0.7 0.7) (thickness 0.15)) (justify left bottom))
    )
    (fp_text user "License: Apache-2.0" (at -0.932 5.17 180) (layer "F.Fab") hide
        (effects (font (size 0.7 0.7) (thickness 0.15)) (justify left bottom))
    )
    (fp_text user "Author: Antmicro" (at -0.932 4.17 180) (layer "F.Fab") hide
        (effects (font (size 0.7 0.7) (thickness 0.15)) (justify left bottom))
    )
    (fp_rect (start -0.94 -0.47) (end 0.94 0.47)
      (stroke (width 0.05) (type solid)) (fill none) (layer "F.CrtYd"))
    (fp_rect (start -0.499 -0.249) (end 0.499 0.249)
      (stroke (width 0.15) (type solid)) (fill none) (layer "F.Fab"))
    (pad "1" smd roundrect (at -0.484 0 180) (size 0.59 0.64) (layers "F.Cu" "F.Paste" "F.Mask") (roundrect_rratio 0.25)
      (net 464 "/FMC HPC/GTX_TX4_C_P") (pintype "passive"))
    (pad "2" smd roundrect (at 0.484 0 180) (size 0.59 0.64) (layers "F.Cu" "F.Paste" "F.Mask") (roundrect_rratio 0.25)
      (net 465 "GTX_TX4_P") (pintype "passive"))
  )

  (footprint "data-center-rdimm-ddr4-tester-footprints:R_0201" (layer "F.Cu")
    (at 160.325 104.3 90)
    (descr "Resistor SMD 0201")
    (tags "resistor SMD 0201")
    (property "Author" "Antmicro")
    (property "License" "Apache-2.0")
    (property "MPN" "CR0201-FX-0R00GLF")
    (property "Manufacturer" "Bourns")
    (property "Sheetfile" "ethernet.kicad_sch")
    (property "Sheetname" "Ethernet")
    (property "Tolerance" "1%")
    (property "Val" "0R")
    (property "ki_description" "0R resistor in 0201 package with 1% tolerance")
    (attr smd)
    (fp_text reference "R102" (at 0.62 0.325 90) (layer "F.SilkS")
        (effects (font (size 0.7 0.7) (thickness 0.15)) (justify left bottom))
    )
    (fp_text value "R_0R_0201" (at 0 1.25 90) (layer "F.Fab") hide
        (effects (font (size 0.7 0.7) (thickness 0.15)) (justify left bottom))
    )
    (fp_text user "Author: Antmicro" (at -0.71 5.25 90) (layer "F.Fab") hide
        (effects (font (size 0.7 0.7) (thickness 0.15)) (justify left bottom))
    )
    (fp_text user "${REFERENCE}" (at -0.71 3.25 90) (layer "F.Fab") hide
        (effects (font (size 0.7 0.7) (thickness 0.15)) (justify left bottom))
    )
    (fp_text user "License: Apache-2.0" (at -0.71 4.25 90) (layer "F.Fab") hide
        (effects (font (size 0.7 0.7) (thickness 0.15)) (justify left bottom))
    )
    (fp_rect (start -0.71 -0.36) (end 0.71 0.36)
      (stroke (width 0.05) (type solid)) (fill none) (layer "F.CrtYd"))
    (fp_rect (start -0.3 -0.15) (end 0.298 0.148)
      (stroke (width 0.15) (type solid)) (fill none) (layer "F.Fab"))
    (pad "" smd roundrect (at -0.346 0 90) (size 0.318 0.36) (layers "F.Paste") (roundrect_rratio 0.25))
    (pad "" smd roundrect (at 0.344 0 90) (size 0.318 0.36) (layers "F.Paste") (roundrect_rratio 0.25))
    (pad "1" smd roundrect (at -0.32 0 90) (size 0.46 0.4) (layers "F.Cu" "F.Mask") (roundrect_rratio 0.25)
      (net 829 "/Ethernet/ETH3_BP_N") (pintype "passive"))
    (pad "2" smd roundrect (at 0.32 0 90) (size 0.46 0.4) (layers "F.Cu" "F.Mask") (roundrect_rratio 0.25)
      (net 174 "/Ethernet/ETH3_N") (pintype "passive"))
  )

  (footprint "data-center-rdimm-ddr4-tester-footprints:NetTie-2_SMD_Pad0.127mm" (layer "F.Cu")
    (at 113.12 108.95)
    (descr "Net tie, 2 pin, 0.127mm  SMD pads")
    (tags "net tie")
    (property "Author" "Antmicro")
    (property "License" "Apache-2.0")
    (property "MPN" "")
    (property "Manufacturer" "")
    (property "Sheetfile" "supply.kicad_sch")
    (property "Sheetname" "Supply")
    (property "ki_description" "Net tie, 2 pins")
    (property "ki_keywords" "net tie short")
    (attr through_hole exclude_from_pos_files)
    (net_tie_pad_groups "1, 2")
    (fp_text reference "NT8" (at -0.128 -1.345) (layer "F.SilkS") hide
        (effects (font (size 0.7 0.7) (thickness 0.15)) (justify left bottom))
    )
    (fp_text value "Net-Tie_2" (at 0 1.199) (layer "F.Fab") hide
        (effects (font (size 0.7 0.7) (thickness 0.15)) (justify left bottom))
    )
    (fp_text user "Author: Antmicro" (at -0.128 4.4) (layer "F.Fab") hide
        (effects (font (size 0.7 0.7) (thickness 0.15)) (justify left bottom))
    )
    (fp_text user "${REFERENCE}" (at -0.128 3.2) (layer "F.Fab") hide
        (effects (font (size 0.7 0.7) (thickness 0.15)) (justify left bottom))
    )
    (fp_text user "License: Apache-2.0" (at -0.128 5.6) (layer "F.Fab") hide
        (effects (font (size 0.7 0.7) (thickness 0.15)) (justify left bottom))
    )
    (fp_poly
      (pts
        (xy -0.0635 -0.0635)
        (xy 0.0625 -0.0635)
        (xy 0.0625 0.0635)
        (xy -0.0635 0.0635)
      )

      (stroke (width 0) (type solid)) (fill solid) (layer "F.Cu"))
    (pad "1" smd roundrect (at -0.127 0 180) (size 0.127 0.127) (layers "F.Cu") (roundrect_rratio 0.5)
      (chamfer_ratio 0) (chamfer top_left bottom_left)
      (net 839 "/Supply/3V3_SEN_+") (pinfunction "1") (pintype "passive"))
    (pad "2" smd roundrect (at 0.126 0) (size 0.127 0.127) (layers "F.Cu") (roundrect_rratio 0.5)
      (chamfer_ratio 0) (chamfer top_left bottom_left)
      (net 304 "VCC3V3") (pinfunction "2") (pintype "passive"))
  )

  (footprint "data-center-rdimm-ddr4-tester-footprints:C_0402_1005Metric" (layer "F.Cu")
    (at 254.71 77.635 180)
    (descr "Capacitor SMD 0402")
    (tags "capacitor SMD 0402")
    (property "Author" "Antmicro")
    (property "Dielectric" "X5R")
    (property "License" "Apache-2.0")
    (property "MPN" "GRM155R61H104KE14D")
    (property "Manufacturer" "Murata")
    (property "Sheetfile" "fmc_hpc.kicad_sch")
    (property "Sheetname" "FMC HPC")
    (property "Val" "100n")
    (property "Voltage" "50V")
    (property "ki_description" " ")
    (attr smd)
    (fp_text reference "C269" (at -0.78 -0.375 180) (layer "F.SilkS")
        (effects (font (size 0.7 0.7) (thickness 0.15)) (justify left bottom))
    )
    (fp_text value "C_100n_0402" (at 0 1.4 180) (layer "F.Fab") hide
        (effects (font (size 0.7 0.7) (thickness 0.15)) (justify left bottom))
    )
    (fp_text user "Author: Antmicro" (at -0.932 4.17 180) (layer "F.Fab") hide
        (effects (font (size 0.7 0.7) (thickness 0.15)) (justify left bottom))
    )
    (fp_text user "License: Apache-2.0" (at -0.932 5.17 180) (layer "F.Fab") hide
        (effects (font (size 0.7 0.7) (thickness 0.15)) (justify left bottom))
    )
    (fp_text user "${REFERENCE}" (at -0.932 3.168 180) (layer "F.Fab") hide
        (effects (font (size 0.7 0.7) (thickness 0.15)) (justify left bottom))
    )
    (fp_rect (start -0.94 -0.47) (end 0.94 0.47)
      (stroke (width 0.05) (type solid)) (fill none) (layer "F.CrtYd"))
    (fp_rect (start -0.499 -0.249) (end 0.499 0.249)
      (stroke (width 0.15) (type solid)) (fill none) (layer "F.Fab"))
    (pad "1" smd roundrect (at -0.484 0 180) (size 0.59 0.64) (layers "F.Cu" "F.Paste" "F.Mask") (roundrect_rratio 0.25)
      (net 480 "/FMC HPC/GTX_TX5_C_P") (pintype "passive"))
    (pad "2" smd roundrect (at 0.484 0 180) (size 0.59 0.64) (layers "F.Cu" "F.Paste" "F.Mask") (roundrect_rratio 0.25)
      (net 481 "GTX_TX5_P") (pintype "passive"))
  )

  (footprint "data-center-rdimm-ddr4-tester-footprints:R_0402_1005Metric" (layer "F.Cu")
    (at 256.2 89.3)
    (descr "Resistor SMD 0402")
    (tags "resistor SMD 0402")
    (property "Author" "Antmicro")
    (property "License" "Apache-2.0")
    (property "MPN" "CR0402-FX-4701GLF")
    (property "Manufacturer" "Bourns")
    (property "Sheetfile" "fmc_hpc.kicad_sch")
    (property "Sheetname" "FMC HPC")
    (property "Tolerance" "1%")
    (property "Val" "4k7")
    (property "ki_description" "4k7 resistor in 0402 package with 1% tolerance")
    (attr smd)
    (fp_text reference "R160" (at 0.66 0.35) (layer "F.SilkS")
        (effects (font (size 0.7 0.7) (thickness 0.15)) (justify left bottom))
    )
    (fp_text value "R_4k7_0402" (at 0 1.4) (layer "F.Fab") hide
        (effects (font (size 0.7 0.7) (thickness 0.15)) (justify left bottom))
    )
    (fp_text user "License: Apache-2.0" (at -0.95 5.169) (layer "F.Fab") hide
        (effects (font (size 0.7 0.7) (thickness 0.15)) (justify left bottom))
    )
    (fp_text user "${REFERENCE}" (at -0.95 3.168) (layer "F.Fab") hide
        (effects (font (size 0.7 0.7) (thickness 0.15)) (justify left bottom))
    )
    (fp_text user "Author: Antmicro" (at -0.95 4.169) (layer "F.Fab") hide
        (effects (font (size 0.7 0.7) (thickness 0.15)) (justify left bottom))
    )
    (fp_rect (start -0.93 -0.47) (end 0.93 0.47)
      (stroke (width 0.05) (type solid)) (fill none) (layer "F.CrtYd"))
    (fp_rect (start -0.5 -0.25) (end 0.5 0.25)
      (stroke (width 0.15) (type solid)) (fill none) (layer "F.Fab"))
    (pad "1" smd roundrect (at -0.485 0) (size 0.59 0.64) (layers "F.Cu" "F.Paste" "F.Mask") (roundrect_rratio 0.25)
      (net 143 "3V3_SYS") (pintype "passive"))
    (pad "2" smd roundrect (at 0.485 0) (size 0.59 0.64) (layers "F.Cu" "F.Paste" "F.Mask") (roundrect_rratio 0.25)
      (net 908 "FMC_SDA_3V3") (pintype "passive"))
  )

  (footprint "data-center-rdimm-ddr4-tester-footprints:Fiducial_1mm_Mask2mm" (layer "F.Cu")
    (at 257 128)
    (descr "Circular Fiducial, 1mm bare copper, 3mm soldermask opening")
    (tags "fiducial")
    (property "Author" "Antmicro")
    (property "License" "Apache-2.0")
    (property "MPN" "")
    (property "Manufacturer" "")
    (property "Sheetfile" "data-center-rdimm-ddr4-tester.kicad_sch")
    (property "Sheetname" "")
    (property "exclude_from_bom" "")
    (property "ki_description" "Fiducial Marker for use with single board only")
    (attr exclude_from_pos_files exclude_from_bom)
    (fp_text reference "FID3" (at -1.13 -1.14) (layer "F.SilkS")
        (effects (font (size 0.7 0.7) (thickness 0.15)) (justify left bottom))
    )
    (fp_text value "Fiducial_1mm_Mask2mm" (at 0 2.2) (layer "F.Fab")
        (effects (font (size 0.7 0.7) (thickness 0.15)) (justify left bottom))
    )
    (fp_text user "Author: Antmicro" (at -1.25 5.803) (layer "F.Fab") hide
        (effects (font (size 0.7 0.7) (thickness 0.15)) (justify left bottom))
    )
    (fp_text user "${REFERENCE}" (at -1.25 4.603) (layer "F.Fab") hide
        (effects (font (size 0.7 0.7) (thickness 0.15)) (justify left bottom))
    )
    (fp_text user "License: Apache-2.0" (at -1.25 7.003) (layer "F.Fab") hide
        (effects (font (size 0.7 0.7) (thickness 0.15)) (justify left bottom))
    )
    (fp_circle (center 0 0) (end 1.24 0)
      (stroke (width 0.05) (type solid)) (fill none) (layer "F.CrtYd"))
    (fp_circle (center 0 0) (end 0.999 0)
      (stroke (width 0.15) (type solid)) (fill none) (layer "F.Fab"))
    (pad "" smd circle (at 0 0) (size 1 1) (layers "F.Cu" "F.Mask")
      (solder_mask_margin 0.5) (clearance 0.5))
  )

  (footprint "data-center-rdimm-ddr4-tester-footprints:Testpoint_smd_1mm" (layer "F.Cu")
    (at 228.899999 125.3 180)
    (property "Author" "Antmicro")
    (property "License" "Apache-2.0")
    (property "MPN" "")
    (property "Manufacturer" "")
    (property "Sheetfile" "supply.kicad_sch")
    (property "Sheetname" "Supply")
    (property "ki_description" "Test Point 1mm")
    (attr exclude_from_pos_files)
    (fp_text reference "TP13" (at 1.589999 -1.44 180) (layer "F.SilkS")
        (effects (font (size 0.7 0.7) (thickness 0.15)) (justify left bottom))
    )
    (fp_text value "TP_1mm_SMD" (at 0 1.4 180) (layer "F.Fab") hide
        (effects (font (size 0.7 0.7) (thickness 0.15)) (justify left bottom))
    )
    (fp_text user "License: Apache-2.0" (at -0.5 5.2 180) (layer "F.Fab") hide
        (effects (font (size 0.7 0.7) (thickness 0.15)) (justify left bottom))
    )
    (fp_text user "${REFERENCE}" (at -0.5 2.8 180) (layer "F.Fab") hide
        (effects (font (size 0.7 0.7) (thickness 0.15)) (justify left bottom))
    )
    (fp_text user "Author: Antmicro" (at -0.5 4 180) (layer "F.Fab") hide
        (effects (font (size 0.7 0.7) (thickness 0.15)) (justify left bottom))
    )
    (pad "1" smd circle (at 0 0 180) (size 1 1) (layers "F.Cu" "F.Mask")
      (net 860 "/Supply/~{CLR}") (pinfunction "1") (pintype "passive"))
  )

  (footprint "data-center-rdimm-ddr4-tester-footprints:NetTie-2_SMD_Pad0.127mm" (layer "F.Cu")
    (at 119.675 84.367 -90)
    (descr "Net tie, 2 pin, 0.127mm  SMD pads")
    (tags "net tie")
    (property "Author" "Antmicro")
    (property "License" "Apache-2.0")
    (property "MPN" "")
    (property "Manufacturer" "")
    (property "Sheetfile" "supply.kicad_sch")
    (property "Sheetname" "Supply")
    (property "ki_description" "Net tie, 2 pins")
    (property "ki_keywords" "net tie short")
    (attr through_hole exclude_from_pos_files)
    (net_tie_pad_groups "1, 2")
    (fp_text reference "NT2" (at -0.128 -1.345 -90) (layer "F.SilkS") hide
        (effects (font (size 0.7 0.7) (thickness 0.15)) (justify left bottom))
    )
    (fp_text value "Net-Tie_2" (at 0 1.199 -90) (layer "F.Fab") hide
        (effects (font (size 0.7 0.7) (thickness 0.15)) (justify left bottom))
    )
    (fp_text user "${REFERENCE}" (at -0.128 3.2 -90) (layer "F.Fab") hide
        (effects (font (size 0.7 0.7) (thickness 0.15)) (justify left bottom))
    )
    (fp_text user "Author: Antmicro" (at -0.128 4.4 -90) (layer "F.Fab") hide
        (effects (font (size 0.7 0.7) (thickness 0.15)) (justify left bottom))
    )
    (fp_text user "License: Apache-2.0" (at -0.128 5.6 -90) (layer "F.Fab") hide
        (effects (font (size 0.7 0.7) (thickness 0.15)) (justify left bottom))
    )
    (fp_poly
      (pts
        (xy -0.0635 -0.0635)
        (xy 0.0625 -0.0635)
        (xy 0.0625 0.0635)
        (xy -0.0635 0.0635)
      )

      (stroke (width 0) (type solid)) (fill solid) (layer "F.Cu"))
    (pad "1" smd roundrect (at -0.127 0 90) (size 0.127 0.127) (layers "F.Cu") (roundrect_rratio 0.5)
      (chamfer_ratio 0) (chamfer top_left bottom_left)
      (net 833 "/Supply/VDDQ_SEN_+") (pinfunction "1") (pintype "passive"))
    (pad "2" smd roundrect (at 0.126 0 270) (size 0.127 0.127) (layers "F.Cu") (roundrect_rratio 0.5)
      (chamfer_ratio 0) (chamfer top_left bottom_left)
      (net 301 "VDD1V2") (pinfunction "2") (pintype "passive"))
  )

  (footprint "data-center-rdimm-ddr4-tester-footprints:R_0402_1005Metric" (layer "F.Cu")
    (at 244.772901 120.82 180)
    (descr "Resistor SMD 0402")
    (tags "resistor SMD 0402")
    (property "Author" "Antmicro")
    (property "License" "Apache-2.0")
    (property "MPN" "CR0402-FX-33R0GLF")
    (property "Manufacturer" "Bourns")
    (property "Sheetfile" "fmc_hpc.kicad_sch")
    (property "Sheetname" "FMC HPC")
    (property "Tolerance" "1%")
    (property "Val" "33R")
    (property "ki_description" "33R resistor in 0402 package with 1% tolerance")
    (attr smd)
    (fp_text reference "R150" (at 0.582901 1.57 180) (layer "F.SilkS")
        (effects (font (size 0.7 0.7) (thickness 0.15)) (justify left bottom))
    )
    (fp_text value "R_33R_0402" (at 0 1.4 180) (layer "F.Fab") hide
        (effects (font (size 0.7 0.7) (thickness 0.15)) (justify left bottom))
    )
    (fp_text user "${REFERENCE}" (at -0.95 3.168 180) (layer "F.Fab") hide
        (effects (font (size 0.7 0.7) (thickness 0.15)) (justify left bottom))
    )
    (fp_text user "Author: Antmicro" (at -0.95 4.169 180) (layer "F.Fab") hide
        (effects (font (size 0.7 0.7) (thickness 0.15)) (justify left bottom))
    )
    (fp_text user "License: Apache-2.0" (at -0.95 5.169 180) (layer "F.Fab") hide
        (effects (font (size 0.7 0.7) (thickness 0.15)) (justify left bottom))
    )
    (fp_rect (start -0.93 -0.47) (end 0.93 0.47)
      (stroke (width 0.05) (type solid)) (fill none) (layer "F.CrtYd"))
    (fp_rect (start -0.5 -0.25) (end 0.5 0.25)
      (stroke (width 0.15) (type solid)) (fill none) (layer "F.Fab"))
    (pad "1" smd roundrect (at -0.485 0 180) (size 0.59 0.64) (layers "F.Cu" "F.Paste" "F.Mask") (roundrect_rratio 0.25)
      (net 903 "/FMC HPC/GTR_REFCLK2_R_P") (pintype "passive"))
    (pad "2" smd roundrect (at 0.485 0 180) (size 0.59 0.64) (layers "F.Cu" "F.Paste" "F.Mask") (roundrect_rratio 0.25)
      (net 893 "GTR_REFCLK2_C_P") (pintype "passive"))
  )

  (footprint "data-center-rdimm-ddr4-tester-footprints:C_0402_1005Metric" (layer "F.Cu")
    (at 248.555 119.81 180)
    (descr "Capacitor SMD 0402")
    (tags "capacitor SMD 0402")
    (property "Author" "Antmicro")
    (property "Dielectric" "X5R")
    (property "License" "Apache-2.0")
    (property "MPN" "GRM155R61H104KE14D")
    (property "Manufacturer" "Murata")
    (property "Sheetfile" "pcie.kicad_sch")
    (property "Sheetname" "FPGA banks 115-116")
    (property "Val" "100n")
    (property "Voltage" "50V")
    (property "ki_description" " ")
    (attr smd)
    (fp_text reference "C247" (at 1.485 1.56 180) (layer "F.SilkS")
        (effects (font (size 0.7 0.7) (thickness 0.15)) (justify left bottom))
    )
    (fp_text value "C_100n_0402" (at 0 1.4 180) (layer "F.Fab") hide
        (effects (font (size 0.7 0.7) (thickness 0.15)) (justify left bottom))
    )
    (fp_text user "${REFERENCE}" (at -0.932 3.168 180) (layer "F.Fab") hide
        (effects (font (size 0.7 0.7) (thickness 0.15)) (justify left bottom))
    )
    (fp_text user "Author: Antmicro" (at -0.932 4.17 180) (layer "F.Fab") hide
        (effects (font (size 0.7 0.7) (thickness 0.15)) (justify left bottom))
    )
    (fp_text user "License: Apache-2.0" (at -0.932 5.17 180) (layer "F.Fab") hide
        (effects (font (size 0.7 0.7) (thickness 0.15)) (justify left bottom))
    )
    (fp_rect (start -0.94 -0.47) (end 0.94 0.47)
      (stroke (width 0.05) (type solid)) (fill none) (layer "F.CrtYd"))
    (fp_rect (start -0.499 -0.249) (end 0.499 0.249)
      (stroke (width 0.15) (type solid)) (fill none) (layer "F.Fab"))
    (pad "1" smd roundrect (at -0.484 0 180) (size 0.59 0.64) (layers "F.Cu" "F.Paste" "F.Mask") (roundrect_rratio 0.25)
      (net 408 "GTR_REFCLK0_C_N") (pintype "passive"))
    (pad "2" smd roundrect (at 0.484 0 180) (size 0.59 0.64) (layers "F.Cu" "F.Paste" "F.Mask") (roundrect_rratio 0.25)
      (net 409 "/FPGA banks 115-116/GTR_REFCLK0_N") (pintype "passive"))
  )

  (footprint "data-center-rdimm-ddr4-tester-footprints:C_0402_1005Metric" (layer "F.Cu")
    (at 243.71 122.975)
    (descr "Capacitor SMD 0402")
    (tags "capacitor SMD 0402")
    (property "Author" "Antmicro")
    (property "Dielectric" "X5R")
    (property "License" "Apache-2.0")
    (property "MPN" "GRM155R61H104KE14D")
    (property "Manufacturer" "Murata")
    (property "Sheetfile" "pcie.kicad_sch")
    (property "Sheetname" "FPGA banks 115-116")
    (property "Val" "100n")
    (property "Voltage" "50V")
    (property "ki_description" " ")
    (attr smd)
    (fp_text reference "C317" (at -2.82 -1.475) (layer "F.SilkS")
        (effects (font (size 0.7 0.7) (thickness 0.15)) (justify left bottom))
    )
    (fp_text value "C_100n_0402" (at 0 1.4) (layer "F.Fab") hide
        (effects (font (size 0.7 0.7) (thickness 0.15)) (justify left bottom))
    )
    (fp_text user "License: Apache-2.0" (at -0.932 5.17) (layer "F.Fab") hide
        (effects (font (size 0.7 0.7) (thickness 0.15)) (justify left bottom))
    )
    (fp_text user "${REFERENCE}" (at -0.932 3.168) (layer "F.Fab") hide
        (effects (font (size 0.7 0.7) (thickness 0.15)) (justify left bottom))
    )
    (fp_text user "Author: Antmicro" (at -0.932 4.17) (layer "F.Fab") hide
        (effects (font (size 0.7 0.7) (thickness 0.15)) (justify left bottom))
    )
    (fp_rect (start -0.94 -0.47) (end 0.94 0.47)
      (stroke (width 0.05) (type solid)) (fill none) (layer "F.CrtYd"))
    (fp_rect (start -0.499 -0.249) (end 0.499 0.249)
      (stroke (width 0.15) (type solid)) (fill none) (layer "F.Fab"))
    (pad "1" smd roundrect (at -0.484 0) (size 0.59 0.64) (layers "F.Cu" "F.Paste" "F.Mask") (roundrect_rratio 0.25)
      (net 887 "/FPGA banks 115-116/GTR_REFCLK3_P") (pintype "passive"))
    (pad "2" smd roundrect (at 0.484 0) (size 0.59 0.64) (layers "F.Cu" "F.Paste" "F.Mask") (roundrect_rratio 0.25)
      (net 895 "GTR_REFCLK3_C_P") (pintype "passive"))
  )

  (footprint "data-center-rdimm-ddr4-tester-footprints:R_1206_3216Metric" (layer "F.Cu")
    (at 131.6 99.5 90)
    (property "Author" "Antmicro")
    (property "License" "Apache-2.0")
    (property "MPN" "RL1206FR-7W0R01L")
    (property "Manufacturer" "Yaego")
    (property "Sheetfile" "supply.kicad_sch")
    (property "Sheetname" "Supply")
    (property "Tolerance" "1%")
    (property "Val" "0R01")
    (property "ki_description" "0R01 resistor in 1206 package with unspecified tolerance")
    (attr smd)
    (fp_text reference "R201" (at -2.03 -1.1 90) (layer "F.SilkS")
        (effects (font (size 0.7 0.7) (thickness 0.15)) (justify left bottom))
    )
    (fp_text value "R_0R01_1206" (at 0 2 90) (layer "F.Fab") hide
        (effects (font (size 0.7 0.7) (thickness 0.15)) (justify left bottom))
    )
    (fp_text user "License: Apache-2.0" (at -2.401 6.3 90) (layer "F.Fab") hide
        (effects (font (size 0.7 0.7) (thickness 0.15)) (justify left bottom))
    )
    (fp_text user "${REFERENCE}" (at -2.401 3.5 90) (layer "F.Fab") hide
        (effects (font (size 0.7 0.7) (thickness 0.15)) (justify left bottom))
    )
    (fp_text user "Author: Antmicro" (at -2.401 4.899 90) (layer "F.Fab") hide
        (effects (font (size 0.7 0.7) (thickness 0.15)) (justify left bottom))
    )
    (fp_line (start 0 -0.902) (end -0.5 -0.902)
      (stroke (width 0.15) (type solid)) (layer "F.SilkS"))
    (fp_line (start 0 -0.902) (end 0.498 -0.902)
      (stroke (width 0.15) (type solid)) (layer "F.SilkS"))
    (fp_line (start 0 0.9) (end -0.5 0.9)
      (stroke (width 0.15) (type solid)) (layer "F.SilkS"))
    (fp_line (start 0 0.9) (end 0.498 0.9)
      (stroke (width 0.15) (type solid)) (layer "F.SilkS"))
    (fp_rect (start -2.25 -1.05) (end 2.25 1.05)
      (stroke (width 0.05) (type solid)) (fill none) (layer "F.CrtYd"))
    (fp_line (start -1.601 -0.802) (end -1.601 0.8)
      (stroke (width 0.15) (type solid)) (layer "F.Fab"))
    (fp_line (start -1.601 -0.802) (end 1.6 -0.802)
      (stroke (width 0.15) (type solid)) (layer "F.Fab"))
    (fp_line (start -1.601 0.8) (end 1.6 0.8)
      (stroke (width 0.15) (type solid)) (layer "F.Fab"))
    (fp_line (start 1.6 -0.802) (end 1.6 0.8)
      (stroke (width 0.15) (type solid)) (layer "F.Fab"))
    (pad "1" smd roundrect (at -1.5 0 90) (size 1.2 1.8) (layers "F.Cu" "F.Paste" "F.Mask") (roundrect_rratio 0.15)
      (net 104 "VCC5V0") (pintype "passive"))
    (pad "2" smd roundrect (at 1.499 0 90) (size 1.2 1.8) (layers "F.Cu" "F.Paste" "F.Mask") (roundrect_rratio 0.15)
      (net 307 "5V0_SYS") (pintype "passive"))
  )

  (footprint "data-center-rdimm-ddr4-tester-footprints:NetTie-2_SMD_Pad0.127mm" (layer "F.Cu")
    (at 143.03 83.7 180)
    (descr "Net tie, 2 pin, 0.127mm  SMD pads")
    (tags "net tie")
    (property "Author" "Antmicro")
    (property "License" "Apache-2.0")
    (property "MPN" "")
    (property "Manufacturer" "")
    (property "Sheetfile" "supply.kicad_sch")
    (property "Sheetname" "Supply")
    (property "ki_description" "Net tie, 2 pins")
    (property "ki_keywords" "net tie short")
    (attr through_hole exclude_from_pos_files)
    (net_tie_pad_groups "1, 2")
    (fp_text reference "NT10" (at -0.128 -1.345 180) (layer "F.SilkS") hide
        (effects (font (size 0.7 0.7) (thickness 0.15)) (justify left bottom))
    )
    (fp_text value "Net-Tie_2" (at 0 1.199 180) (layer "F.Fab") hide
        (effects (font (size 0.7 0.7) (thickness 0.15)) (justify left bottom))
    )
    (fp_text user "License: Apache-2.0" (at -0.128 5.6 180) (layer "F.Fab") hide
        (effects (font (size 0.7 0.7) (thickness 0.15)) (justify left bottom))
    )
    (fp_text user "Author: Antmicro" (at -0.128 4.4 180) (layer "F.Fab") hide
        (effects (font (size 0.7 0.7) (thickness 0.15)) (justify left bottom))
    )
    (fp_text user "${REFERENCE}" (at -0.128 3.2 180) (layer "F.Fab") hide
        (effects (font (size 0.7 0.7) (thickness 0.15)) (justify left bottom))
    )
    (fp_poly
      (pts
        (xy -0.0635 -0.0635)
        (xy 0.0625 -0.0635)
        (xy 0.0625 0.0635)
        (xy -0.0635 0.0635)
      )

      (stroke (width 0) (type solid)) (fill solid) (layer "F.Cu"))
    (pad "1" smd roundrect (at -0.127 0) (size 0.127 0.127) (layers "F.Cu") (roundrect_rratio 0.5)
      (chamfer_ratio 0) (chamfer top_left bottom_left)
      (net 841 "/Supply/1V0_SEN_+") (pinfunction "1") (pintype "passive"))
    (pad "2" smd roundrect (at 0.126 0 180) (size 0.127 0.127) (layers "F.Cu") (roundrect_rratio 0.5)
      (chamfer_ratio 0) (chamfer top_left bottom_left)
      (net 300 "VCC1V0") (pinfunction "2") (pintype "passive"))
  )

  (footprint "data-center-rdimm-ddr4-tester-footprints:R_0402_1005Metric" (layer "F.Cu")
    (at 109.875 112.075 180)
    (descr "Resistor SMD 0402")
    (tags "resistor SMD 0402")
    (property "Author" "Antmicro")
    (property "Current" "1A")
    (property "DNP" "DNP")
    (property "License" "Apache-2.0")
    (property "MPN" "ERJ2GE0R00X")
    (property "Manufacturer" "Panasonic")
    (property "Sheetfile" "DDR4.kicad_sch")
    (property "Sheetname" "DDR4")
    (property "Tolerance" "")
    (property "Val" "0R")
    (property "dnp" "")
    (property "exclude_from_bom" "")
    (property "ki_description" "0R resistor in 0402 package with unspecified tolerance")
    (attr exclude_from_pos_files exclude_from_bom)
    (fp_text reference "R157" (at 2.785 0.475 180) (layer "F.SilkS")
        (effects (font (size 0.7 0.7) (thickness 0.15)) (justify left bottom))
    )
    (fp_text value "R_0R_0402" (at 0 1.4 180) (layer "F.Fab") hide
        (effects (font (size 0.7 0.7) (thickness 0.15)) (justify left bottom))
    )
    (fp_text user "Author: Antmicro" (at -0.95 4.169 180) (layer "F.Fab") hide
        (effects (font (size 0.7 0.7) (thickness 0.15)) (justify left bottom))
    )
    (fp_text user "License: Apache-2.0" (at -0.95 5.169 180) (layer "F.Fab") hide
        (effects (font (size 0.7 0.7) (thickness 0.15)) (justify left bottom))
    )
    (fp_text user "${REFERENCE}" (at -0.95 3.168 180) (layer "F.Fab") hide
        (effects (font (size 0.7 0.7) (thickness 0.15)) (justify left bottom))
    )
    (fp_rect (start -0.93 -0.47) (end 0.93 0.47)
      (stroke (width 0.05) (type solid)) (fill none) (layer "F.CrtYd"))
    (fp_rect (start -0.5 -0.25) (end 0.5 0.25)
      (stroke (width 0.15) (type solid)) (fill none) (layer "F.Fab"))
    (pad "1" smd roundrect (at -0.485 0 180) (size 0.59 0.64) (layers "F.Cu" "F.Paste" "F.Mask") (roundrect_rratio 0.25)
      (net 103 "VIN") (pintype "passive"))
    (pad "2" smd roundrect (at 0.485 0 180) (size 0.59 0.64) (layers "F.Cu" "F.Paste" "F.Mask") (roundrect_rratio 0.25)
      (net 308 "NC") (pintype "passive"))
  )

  (footprint "data-center-rdimm-ddr4-tester-footprints:C_0402_1005Metric" (layer "F.Cu")
    (at 162.7 104.51 -90)
    (descr "Capacitor SMD 0402")
    (tags "capacitor SMD 0402")
    (property "Author" "Antmicro")
    (property "DNP" "DNP")
    (property "Dielectric" "X5R")
    (property "License" "Apache-2.0")
    (property "MPN" "GRM155R61H104KE14D")
    (property "Manufacturer" "Murata")
    (property "Sheetfile" "ethernet.kicad_sch")
    (property "Sheetname" "Ethernet")
    (property "Val" "100n")
    (property "Voltage" "50V")
    (property "dnp" "")
    (property "exclude_from_bom" "")
    (property "ki_description" " ")
    (attr exclude_from_pos_files exclude_from_bom)
    (fp_text reference "C291" (at 3.58 -0.34 -90) (layer "F.SilkS")
        (effects (font (size 0.7 0.7) (thickness 0.15)) (justify left bottom))
    )
    (fp_text value "C_100n_0402" (at 0 1.4 -90) (layer "F.Fab") hide
        (effects (font (size 0.7 0.7) (thickness 0.15)) (justify left bottom))
    )
    (fp_text user "Author: Antmicro" (at -0.932 4.17 -90) (layer "F.Fab") hide
        (effects (font (size 0.7 0.7) (thickness 0.15)) (justify left bottom))
    )
    (fp_text user "${REFERENCE}" (at -0.932 3.168 -90) (layer "F.Fab") hide
        (effects (font (size 0.7 0.7) (thickness 0.15)) (justify left bottom))
    )
    (fp_text user "License: Apache-2.0" (at -0.932 5.17 -90) (layer "F.Fab") hide
        (effects (font (size 0.7 0.7) (thickness 0.15)) (justify left bottom))
    )
    (fp_rect (start -0.94 -0.47) (end 0.94 0.47)
      (stroke (width 0.05) (type solid)) (fill none) (layer "F.CrtYd"))
    (fp_rect (start -0.499 -0.249) (end 0.499 0.249)
      (stroke (width 0.15) (type solid)) (fill none) (layer "F.Fab"))
    (pad "1" smd roundrect (at -0.484 0 270) (size 0.59 0.64) (layers "F.Cu" "F.Paste" "F.Mask") (roundrect_rratio 0.25)
      (net 143 "3V3_SYS") (pintype "passive"))
    (pad "2" smd roundrect (at 0.484 0 270) (size 0.59 0.64) (layers "F.Cu" "F.Paste" "F.Mask") (roundrect_rratio 0.25)
      (net 9 "GND") (pintype "passive"))
  )

  (footprint "data-center-rdimm-ddr4-tester-footprints:C_0402_1005Metric" (layer "F.Cu")
    (at 153.2 127.515 90)
    (descr "Capacitor SMD 0402")
    (tags "capacitor SMD 0402")
    (property "Author" "Antmicro")
    (property "Dielectric" "X5R")
    (property "License" "Apache-2.0")
    (property "MPN" "GRM155R61H104KE14D")
    (property "Manufacturer" "Murata")
    (property "Sheetfile" "interfaces.kicad_sch")
    (property "Sheetname" "Interfaces")
    (property "Val" "100n")
    (property "Voltage" "50V")
    (property "ki_description" " ")
    (attr smd)
    (fp_text reference "C252" (at -0.965 -0.41 90) (layer "F.SilkS")
        (effects (font (size 0.7 0.7) (thickness 0.15)) (justify left bottom))
    )
    (fp_text value "C_100n_0402" (at 0 1.4 90) (layer "F.Fab") hide
        (effects (font (size 0.7 0.7) (thickness 0.15)) (justify left bottom))
    )
    (fp_text user "Author: Antmicro" (at -0.932 4.17 90) (layer "F.Fab") hide
        (effects (font (size 0.7 0.7) (thickness 0.15)) (justify left bottom))
    )
    (fp_text user "${REFERENCE}" (at -0.932 3.168 90) (layer "F.Fab") hide
        (effects (font (size 0.7 0.7) (thickness 0.15)) (justify left bottom))
    )
    (fp_text user "License: Apache-2.0" (at -0.932 5.17 90) (layer "F.Fab") hide
        (effects (font (size 0.7 0.7) (thickness 0.15)) (justify left bottom))
    )
    (fp_rect (start -0.94 -0.47) (end 0.94 0.47)
      (stroke (width 0.05) (type solid)) (fill none) (layer "F.CrtYd"))
    (fp_rect (start -0.499 -0.249) (end 0.499 0.249)
      (stroke (width 0.15) (type solid)) (fill none) (layer "F.Fab"))
    (pad "1" smd roundrect (at -0.484 0 90) (size 0.59 0.64) (layers "F.Cu" "F.Paste" "F.Mask") (roundrect_rratio 0.25)
      (net 862 "GNDS") (pintype "passive"))
    (pad "2" smd roundrect (at 0.484 0 90) (size 0.59 0.64) (layers "F.Cu" "F.Paste" "F.Mask") (roundrect_rratio 0.25)
      (net 9 "GND") (pintype "passive"))
  )

  (footprint "data-center-rdimm-ddr4-tester-footprints:R_0402_1005Metric" (layer "F.Cu")
    (at 246.042902 122.36 180)
    (descr "Resistor SMD 0402")
    (tags "resistor SMD 0402")
    (property "Author" "Antmicro")
    (property "License" "Apache-2.0")
    (property "MPN" "CR0402-FX-33R0GLF")
    (property "Manufacturer" "Bourns")
    (property "Sheetfile" "fmc_hpc.kicad_sch")
    (property "Sheetname" "FMC HPC")
    (property "Tolerance" "1%")
    (property "Val" "33R")
    (property "ki_description" "33R resistor in 0402 package with 1% tolerance")
    (attr smd)
    (fp_text reference "R153" (at -0.697098 -0.37 180) (layer "F.SilkS")
        (effects (font (size 0.7 0.7) (thickness 0.15)) (justify left bottom))
    )
    (fp_text value "R_33R_0402" (at 0 1.4 180) (layer "F.Fab") hide
        (effects (font (size 0.7 0.7) (thickness 0.15)) (justify left bottom))
    )
    (fp_text user "License: Apache-2.0" (at -0.95 5.169 180) (layer "F.Fab") hide
        (effects (font (size 0.7 0.7) (thickness 0.15)) (justify left bottom))
    )
    (fp_text user "${REFERENCE}" (at -0.95 3.168 180) (layer "F.Fab") hide
        (effects (font (size 0.7 0.7) (thickness 0.15)) (justify left bottom))
    )
    (fp_text user "Author: Antmicro" (at -0.95 4.169 180) (layer "F.Fab") hide
        (effects (font (size 0.7 0.7) (thickness 0.15)) (justify left bottom))
    )
    (fp_rect (start -0.93 -0.47) (end 0.93 0.47)
      (stroke (width 0.05) (type solid)) (fill none) (layer "F.CrtYd"))
    (fp_rect (start -0.5 -0.25) (end 0.5 0.25)
      (stroke (width 0.15) (type solid)) (fill none) (layer "F.Fab"))
    (pad "1" smd roundrect (at -0.485 0 180) (size 0.59 0.64) (layers "F.Cu" "F.Paste" "F.Mask") (roundrect_rratio 0.25)
      (net 900 "/FMC HPC/GTR_REFCLK3_R_N") (pintype "passive"))
    (pad "2" smd roundrect (at 0.485 0 180) (size 0.59 0.64) (layers "F.Cu" "F.Paste" "F.Mask") (roundrect_rratio 0.25)
      (net 896 "GTR_REFCLK3_C_N") (pintype "passive"))
  )

  (footprint "data-center-rdimm-ddr4-tester-footprints:R_0402_1005Metric" (layer "F.Cu")
    (at 250.9 114.5 180)
    (descr "Resistor SMD 0402")
    (tags "resistor SMD 0402")
    (property "Author" "Antmicro")
    (property "License" "Apache-2.0")
    (property "MPN" "CR0402-FX-1002GLF")
    (property "Manufacturer" "Bourns")
    (property "Sheetfile" "fmc_hpc.kicad_sch")
    (property "Sheetname" "FMC HPC")
    (property "Tolerance" "1%")
    (property "Val" "10k")
    (property "ki_description" "10k resistor in 0402 package with 1% tolerance")
    (attr smd)
    (fp_text reference "R209" (at 3.7 -0.4 180) (layer "F.SilkS")
        (effects (font (size 0.7 0.7) (thickness 0.15)) (justify left bottom))
    )
    (fp_text value "R_10k_0402" (at 0 1.4 180) (layer "F.Fab") hide
        (effects (font (size 0.7 0.7) (thickness 0.15)) (justify left bottom))
    )
    (fp_text user "License: Apache-2.0" (at -0.95 5.169 180) (layer "F.Fab") hide
        (effects (font (size 0.7 0.7) (thickness 0.15)) (justify left bottom))
    )
    (fp_text user "${REFERENCE}" (at -0.95 3.168 180) (layer "F.Fab") hide
        (effects (font (size 0.7 0.7) (thickness 0.15)) (justify left bottom))
    )
    (fp_text user "Author: Antmicro" (at -0.95 4.169 180) (layer "F.Fab") hide
        (effects (font (size 0.7 0.7) (thickness 0.15)) (justify left bottom))
    )
    (fp_rect (start -0.93 -0.47) (end 0.93 0.47)
      (stroke (width 0.05) (type solid)) (fill none) (layer "F.CrtYd"))
    (fp_rect (start -0.5 -0.25) (end 0.5 0.25)
      (stroke (width 0.15) (type solid)) (fill none) (layer "F.Fab"))
    (pad "1" smd roundrect (at -0.485 0 180) (size 0.59 0.64) (layers "F.Cu" "F.Paste" "F.Mask") (roundrect_rratio 0.25)
      (net 120 "~{PERST}") (pintype "passive"))
    (pad "2" smd roundrect (at 0.485 0 180) (size 0.59 0.64) (layers "F.Cu" "F.Paste" "F.Mask") (roundrect_rratio 0.25)
      (net 143 "3V3_SYS") (pintype "passive"))
  )

  (footprint "data-center-rdimm-ddr4-tester-footprints:R_0402_1005Metric" (layer "F.Cu")
    (at 146.9 127.5 -90)
    (descr "Resistor SMD 0402")
    (tags "resistor SMD 0402")
    (property "Author" "Antmicro")
    (property "License" "Apache-2.0")
    (property "MPN" "CR0402-FX-5111GLF")
    (property "Manufacturer" "Bourns")
    (property "Sheetfile" "interfaces.kicad_sch")
    (property "Sheetname" "Interfaces")
    (property "Tolerance" "1%")
    (property "Val" "5k11")
    (property "ki_description" "5k11 resistor in 0402 package with 1% tolerance")
    (attr smd)
    (fp_text reference "R15" (at -0.78 -0.39 -90) (layer "F.SilkS")
        (effects (font (size 0.7 0.7) (thickness 0.15)) (justify left bottom))
    )
    (fp_text value "R_5k11_0402" (at 0 1.4 -90) (layer "F.Fab") hide
        (effects (font (size 0.7 0.7) (thickness 0.15)) (justify left bottom))
    )
    (fp_text user "${REFERENCE}" (at -0.95 3.168 -90) (layer "F.Fab") hide
        (effects (font (size 0.7 0.7) (thickness 0.15)) (justify left bottom))
    )
    (fp_text user "License: Apache-2.0" (at -0.95 5.169 -90) (layer "F.Fab") hide
        (effects (font (size 0.7 0.7) (thickness 0.15)) (justify left bottom))
    )
    (fp_text user "Author: Antmicro" (at -0.95 4.169 -90) (layer "F.Fab") hide
        (effects (font (size 0.7 0.7) (thickness 0.15)) (justify left bottom))
    )
    (fp_rect (start -0.93 -0.47) (end 0.93 0.47)
      (stroke (width 0.05) (type solid)) (fill none) (layer "F.CrtYd"))
    (fp_rect (start -0.5 -0.25) (end 0.5 0.25)
      (stroke (width 0.15) (type solid)) (fill none) (layer "F.Fab"))
    (pad "1" smd roundrect (at -0.485 0 270) (size 0.59 0.64) (layers "F.Cu" "F.Paste" "F.Mask") (roundrect_rratio 0.25)
      (net 9 "GND") (pintype "passive"))
    (pad "2" smd roundrect (at 0.485 0 270) (size 0.59 0.64) (layers "F.Cu" "F.Paste" "F.Mask") (roundrect_rratio 0.25)
      (net 565 "Net-(J9-CC1)") (pintype "passive"))
  )

  (footprint "data-center-rdimm-ddr4-tester-footprints:SW_1-1825027-1_THT" (layer "F.Cu")
    (at 223.65 131.6725)
    (descr "Tactile Switches, Round Actuator Style, NO, 5.74mm")
    (property "Author" "Antmicro")
    (property "License" "Apache-2.0")
    (property "MPN" "1-1825027-1")
    (property "Manufacturer" "TE Connectivity")
    (property "Sheetfile" "interfaces.kicad_sch")
    (property "Sheetname" "Interfaces")
    (property "ki_description" "Tactile Switch, Side Actuated, Through Hole, Round Button, 160 gf, 50mA at 24VDC")
    (property "ki_keywords" "HORIZONTAL, SWITCH, THT, MECHANICAL, TACTILE")
    (attr through_hole)
    (fp_text reference "S1" (at 7.49 2.9475 90) (layer "F.SilkS")
        (effects (font (size 0.7 0.7) (thickness 0.15)) (justify left bottom))
    )
    (fp_text value "SW_1-1825027-1" (at -2.4 9.6) (layer "F.Fab")
        (effects (font (size 0.7 0.7) (thickness 0.15)) (justify left bottom))
    )
    (fp_text user "${REFERENCE}" (at -2.452 11) (layer "F.Fab") hide
        (effects (font (size 0.7 0.7) (thickness 0.15)) (justify left bottom))
    )
    (fp_text user "License: Apache-2.0" (at -2.452 13.88) (layer "F.Fab") hide
        (effects (font (size 0.7 0.7) (thickness 0.15)) (justify left bottom))
    )
    (fp_text user "Author: Antmicro" (at -2.452 12.4) (layer "F.Fab") hide
        (effects (font (size 0.7 0.7) (thickness 0.15)) (justify left bottom))
    )
    (fp_line (start -1.331 -4.01) (end 5.828 -4.01)
      (stroke (width 0.15) (type solid)) (layer "F.SilkS"))
    (fp_line (start -1.307 2.548) (end -1.307 -0.485)
      (stroke (width 0.15) (type solid)) (layer "F.SilkS"))
    (fp_line (start 4.004 2.6) (end 0.494 2.6)
      (stroke (width 0.15) (type solid)) (layer "F.SilkS"))
    (fp_line (start 5.804 -0.5) (end 5.799 2.6)
      (stroke (width 0.15) (type solid)) (layer "F.SilkS"))
    (fp_line (start -1.6 -4.21) (end -1.6 2.89)
      (stroke (width 0.05) (type solid)) (layer "F.CrtYd"))
    (fp_line (start -1.6 2.89) (end 0.14 2.89)
      (stroke (width 0.05) (type solid)) (layer "F.CrtYd"))
    (fp_line (start 0.14 2.89) (end 0.14 8.58)
      (stroke (width 0.05) (type solid)) (layer "F.CrtYd"))
    (fp_line (start 0.14 8.58) (end 4.24 8.58)
      (stroke (width 0.05) (type solid)) (layer "F.CrtYd"))
    (fp_line (start 4.24 2.89) (end 6.1 2.89)
      (stroke (width 0.05) (type solid)) (layer "F.CrtYd"))
    (fp_line (start 4.24 8.58) (end 4.24 2.89)
      (stroke (width 0.05) (type solid)) (layer "F.CrtYd"))
    (fp_line (start 6.1 -4.21) (end -1.6 -4.21)
      (stroke (width 0.05) (type solid)) (layer "F.CrtYd"))
    (fp_line (start 6.1 2.89) (end 6.1 -4.21)
      (stroke (width 0.05) (type solid)) (layer "F.CrtYd"))
    (fp_line (start -1.307 -4.01) (end 5.804 -4.01)
      (stroke (width 0.15) (type solid)) (layer "F.Fab"))
    (fp_line (start -1.307 2.6) (end -1.307 -4.01)
      (stroke (width 0.15) (type solid)) (layer "F.Fab"))
    (fp_line (start 0.494 2.6) (end -1.307 2.6)
      (stroke (width 0.15) (type solid)) (layer "F.Fab"))
    (fp_line (start 0.494 2.6) (end 0.494 8.349)
      (stroke (width 0.15) (type solid)) (layer "F.Fab"))
    (fp_line (start 0.494 8.349) (end 4.004 8.349)
      (stroke (width 0.15) (type solid)) (layer "F.Fab"))
    (fp_line (start 4.004 8.349) (end 3.999 2.6)
      (stroke (width 0.15) (type solid)) (layer "F.Fab"))
    (fp_line (start 5.799 2.6) (end 3.999 2.6)
      (stroke (width 0.15) (type solid)) (layer "F.Fab"))
    (fp_line (start 5.804 -4.01) (end 5.804 2.6)
      (stroke (width 0.15) (type solid)) (layer "F.Fab"))
    (pad "1" thru_hole circle (at 0 0) (size 1.498 1.498) (drill 0.99) (layers "*.Cu" "*.Mask")
      (net 149 "HOT_SWAP_BUTTON") (pinfunction "1") (pintype "passive"))
    (pad "2" thru_hole circle (at 4.498 0) (size 1.498 1.498) (drill 0.99) (layers "*.Cu" "*.Mask")
      (net 9 "GND") (pinfunction "2") (pintype "passive"))
    (pad "SH" thru_hole circle (at -1.256 -2.492) (size 1.95 1.95) (drill 1.3) (layers "*.Cu" "*.Mask")
      (net 9 "GND") (pinfunction "SH") (pintype "passive"))
    (pad "SH" thru_hole circle (at 5.754 -2.492) (size 1.95 1.95) (drill 1.3) (layers "*.Cu" "*.Mask")
      (net 9 "GND") (pinfunction "SH") (pintype "passive"))
  )

  (footprint "data-center-rdimm-ddr4-tester-footprints:R_0201" (layer "F.Cu")
    (at 157.8 109.03 -90)
    (descr "Resistor SMD 0201")
    (tags "resistor SMD 0201")
    (property "Author" "Antmicro")
    (property "License" "Apache-2.0")
    (property "MPN" "CR0201-FX-0R00GLF")
    (property "Manufacturer" "Bourns")
    (property "Sheetfile" "ethernet.kicad_sch")
    (property "Sheetname" "Ethernet")
    (property "Tolerance" "1%")
    (property "Val" "0R")
    (property "ki_description" "0R resistor in 0201 package with 1% tolerance")
    (attr smd)
    (fp_text reference "R107" (at 3.46 -0.22 -90) (layer "F.SilkS")
        (effects (font (size 0.7 0.7) (thickness 0.15)) (justify left bottom))
    )
    (fp_text value "R_0R_0201" (at 0 1.25 -90) (layer "F.Fab") hide
        (effects (font (size 0.7 0.7) (thickness 0.15)) (justify left bottom))
    )
    (fp_text user "${REFERENCE}" (at -0.71 3.25 -90) (layer "F.Fab") hide
        (effects (font (size 0.7 0.7) (thickness 0.15)) (justify left bottom))
    )
    (fp_text user "License: Apache-2.0" (at -0.71 4.25 -90) (layer "F.Fab") hide
        (effects (font (size 0.7 0.7) (thickness 0.15)) (justify left bottom))
    )
    (fp_text user "Author: Antmicro" (at -0.71 5.25 -90) (layer "F.Fab") hide
        (effects (font (size 0.7 0.7) (thickness 0.15)) (justify left bottom))
    )
    (fp_rect (start -0.71 -0.36) (end 0.71 0.36)
      (stroke (width 0.05) (type solid)) (fill none) (layer "F.CrtYd"))
    (fp_rect (start -0.3 -0.15) (end 0.298 0.148)
      (stroke (width 0.15) (type solid)) (fill none) (layer "F.Fab"))
    (pad "" smd roundrect (at -0.346 0 270) (size 0.318 0.36) (layers "F.Paste") (roundrect_rratio 0.25))
    (pad "" smd roundrect (at 0.344 0 270) (size 0.318 0.36) (layers "F.Paste") (roundrect_rratio 0.25))
    (pad "1" smd roundrect (at -0.32 0 270) (size 0.46 0.4) (layers "F.Cu" "F.Mask") (roundrect_rratio 0.25)
      (net 826 "/Ethernet/ETH2_BP_P") (pintype "passive"))
    (pad "2" smd roundrect (at 0.32 0 270) (size 0.46 0.4) (layers "F.Cu" "F.Mask") (roundrect_rratio 0.25)
      (net 568 "/Ethernet/INT_ETH2_P") (pintype "passive"))
  )

  (footprint "data-center-rdimm-ddr4-tester-footprints:C_0402_1005Metric" (layer "F.Cu")
    (at 153.65 108.09 -90)
    (descr "Capacitor SMD 0402")
    (tags "capacitor SMD 0402")
    (property "Author" "Antmicro")
    (property "DNP" "DNP")
    (property "Dielectric" "X5R")
    (property "License" "Apache-2.0")
    (property "MPN" "GRM155R61H104KE14D")
    (property "Manufacturer" "Murata")
    (property "Sheetfile" "ethernet.kicad_sch")
    (property "Sheetname" "Ethernet")
    (property "Val" "100n")
    (property "Voltage" "50V")
    (property "dnp" "")
    (property "exclude_from_bom" "")
    (property "ki_description" " ")
    (attr exclude_from_pos_files exclude_from_bom)
    (fp_text reference "C293" (at 1.6 -1.24 -90) (layer "F.SilkS")
        (effects (font (size 0.7 0.7) (thickness 0.15)) (justify left bottom))
    )
    (fp_text value "C_100n_0402" (at 0 1.4 -90) (layer "F.Fab") hide
        (effects (font (size 0.7 0.7) (thickness 0.15)) (justify left bottom))
    )
    (fp_text user "License: Apache-2.0" (at -0.932 5.17 -90) (layer "F.Fab") hide
        (effects (font (size 0.7 0.7) (thickness 0.15)) (justify left bottom))
    )
    (fp_text user "Author: Antmicro" (at -0.932 4.17 -90) (layer "F.Fab") hide
        (effects (font (size 0.7 0.7) (thickness 0.15)) (justify left bottom))
    )
    (fp_text user "${REFERENCE}" (at -0.932 3.168 -90) (layer "F.Fab") hide
        (effects (font (size 0.7 0.7) (thickness 0.15)) (justify left bottom))
    )
    (fp_rect (start -0.94 -0.47) (end 0.94 0.47)
      (stroke (width 0.05) (type solid)) (fill none) (layer "F.CrtYd"))
    (fp_rect (start -0.499 -0.249) (end 0.499 0.249)
      (stroke (width 0.15) (type solid)) (fill none) (layer "F.Fab"))
    (pad "1" smd roundrect (at -0.484 0 270) (size 0.59 0.64) (layers "F.Cu" "F.Paste" "F.Mask") (roundrect_rratio 0.25)
      (net 143 "3V3_SYS") (pintype "passive"))
    (pad "2" smd roundrect (at 0.484 0 270) (size 0.59 0.64) (layers "F.Cu" "F.Paste" "F.Mask") (roundrect_rratio 0.25)
      (net 9 "GND") (pintype "passive"))
  )

  (footprint "data-center-rdimm-ddr4-tester-footprints:C_0402_1005Metric" (layer "F.Cu")
    (at 254.71 86.795 180)
    (descr "Capacitor SMD 0402")
    (tags "capacitor SMD 0402")
    (property "Author" "Antmicro")
    (property "Dielectric" "X5R")
    (property "License" "Apache-2.0")
    (property "MPN" "GRM155R61H104KE14D")
    (property "Manufacturer" "Murata")
    (property "Sheetfile" "fmc_hpc.kicad_sch")
    (property "Sheetname" "FMC HPC")
    (property "Val" "100n")
    (property "Voltage" "50V")
    (property "ki_description" " ")
    (attr smd)
    (fp_text reference "C266" (at -0.8 -0.355 180) (layer "F.SilkS")
        (effects (font (size 0.7 0.7) (thickness 0.15)) (justify left bottom))
    )
    (fp_text value "C_100n_0402" (at 0 1.4 180) (layer "F.Fab") hide
        (effects (font (size 0.7 0.7) (thickness 0.15)) (justify left bottom))
    )
    (fp_text user "${REFERENCE}" (at -0.932 3.168 180) (layer "F.Fab") hide
        (effects (font (size 0.7 0.7) (thickness 0.15)) (justify left bottom))
    )
    (fp_text user "Author: Antmicro" (at -0.932 4.17 180) (layer "F.Fab") hide
        (effects (font (size 0.7 0.7) (thickness 0.15)) (justify left bottom))
    )
    (fp_text user "License: Apache-2.0" (at -0.932 5.17 180) (layer "F.Fab") hide
        (effects (font (size 0.7 0.7) (thickness 0.15)) (justify left bottom))
    )
    (fp_rect (start -0.94 -0.47) (end 0.94 0.47)
      (stroke (width 0.05) (type solid)) (fill none) (layer "F.CrtYd"))
    (fp_rect (start -0.499 -0.249) (end 0.499 0.249)
      (stroke (width 0.15) (type solid)) (fill none) (layer "F.Fab"))
    (pad "1" smd roundrect (at -0.484 0 180) (size 0.59 0.64) (layers "F.Cu" "F.Paste" "F.Mask") (roundrect_rratio 0.25)
      (net 451 "/FMC HPC/GTX_TX3_C_N") (pintype "passive"))
    (pad "2" smd roundrect (at 0.484 0 180) (size 0.59 0.64) (layers "F.Cu" "F.Paste" "F.Mask") (roundrect_rratio 0.25)
      (net 463 "GTX_TX3_N") (pintype "passive"))
  )

  (footprint "data-center-rdimm-ddr4-tester-footprints:NetTie-2_SMD_Pad0.127mm" (layer "F.Cu")
    (at 112.45 92.33 -90)
    (descr "Net tie, 2 pin, 0.127mm  SMD pads")
    (tags "net tie")
    (property "Author" "Antmicro")
    (property "License" "Apache-2.0")
    (property "MPN" "")
    (property "Manufacturer" "")
    (property "Sheetfile" "supply.kicad_sch")
    (property "Sheetname" "Supply")
    (property "ki_description" "Net tie, 2 pins")
    (property "ki_keywords" "net tie short")
    (attr through_hole exclude_from_pos_files)
    (net_tie_pad_groups "1, 2")
    (fp_text reference "NT3" (at -0.128 -1.345 -90) (layer "F.SilkS") hide
        (effects (font (size 0.7 0.7) (thickness 0.15)) (justify left bottom))
    )
    (fp_text value "Net-Tie_2" (at 0 1.199 -90) (layer "F.Fab") hide
        (effects (font (size 0.7 0.7) (thickness 0.15)) (justify left bottom))
    )
    (fp_text user "License: Apache-2.0" (at -0.128 5.6 -90) (layer "F.Fab") hide
        (effects (font (size 0.7 0.7) (thickness 0.15)) (justify left bottom))
    )
    (fp_text user "Author: Antmicro" (at -0.128 4.4 -90) (layer "F.Fab") hide
        (effects (font (size 0.7 0.7) (thickness 0.15)) (justify left bottom))
    )
    (fp_text user "${REFERENCE}" (at -0.128 3.2 -90) (layer "F.Fab") hide
        (effects (font (size 0.7 0.7) (thickness 0.15)) (justify left bottom))
    )
    (fp_poly
      (pts
        (xy -0.0635 -0.0635)
        (xy 0.0625 -0.0635)
        (xy 0.0625 0.0635)
        (xy -0.0635 0.0635)
      )

      (stroke (width 0) (type solid)) (fill solid) (layer "F.Cu"))
    (pad "1" smd roundrect (at -0.127 0 90) (size 0.127 0.127) (layers "F.Cu") (roundrect_rratio 0.5)
      (chamfer_ratio 0) (chamfer top_left bottom_left)
      (net 834 "/Supply/VTT_SEN_+") (pinfunction "1") (pintype "passive"))
    (pad "2" smd roundrect (at 0.126 0 270) (size 0.127 0.127) (layers "F.Cu") (roundrect_rratio 0.5)
      (chamfer_ratio 0) (chamfer top_left bottom_left)
      (net 299 "VCC0V6") (pinfunction "2") (pintype "passive"))
  )

  (footprint "data-center-rdimm-ddr4-tester-footprints:SOT-23-6" (layer "F.Cu")
    (at 229.55 122.8 90)
    (property "Author" "Antmicro")
    (property "License" "Apache-2.0")
    (property "MPN" "MAX16150AUT+T")
    (property "Manufacturer" "Maxim Integrated")
    (property "Sheetfile" "supply.kicad_sch")
    (property "Sheetname" "Supply")
    (property "ki_description" "nanoPower Pushbutton On/Off Controller and Battery Freshness Seal")
    (attr smd)
    (fp_text reference "U26" (at -2.06 1.58 180) (layer "F.SilkS")
        (effects (font (size 0.7 0.7) (thickness 0.15)) (justify left bottom))
    )
    (fp_text value "MAX16150A_SOT" (at -1.75 2.75 90) (layer "F.Fab") hide
        (effects (font (size 0.7 0.7) (thickness 0.15)) (justify left bottom))
    )
    (fp_text user "." (at -1.4 1.2 270) (layer "F.SilkS")
        (effects (font (size 1 1) (thickness 0.15)))
    )
    (fp_text user "License: Apache-2.0" (at -1.75 6.5 90) (layer "F.Fab") hide
        (effects (font (size 0.7 0.7) (thickness 0.15)) (justify left bottom))
    )
    (fp_text user "Author: Antmicro" (at -1.829 5.25 90) (layer "F.Fab") hide
        (effects (font (size 0.7 0.7) (thickness 0.15)) (justify left bottom))
    )
    (fp_text user "${REFERENCE}" (at -1.75 4 90) (layer "F.Fab") hide
        (effects (font (size 0.7 0.7) (thickness 0.15)) (justify left bottom))
    )
    (fp_line (start -1.45 -0.7) (end -1.45 -0.4)
      (stroke (width 0.12) (type solid)) (layer "F.SilkS"))
    (fp_line (start -1.45 0.7) (end -1.45 0.4)
      (stroke (width 0.12) (type solid)) (layer "F.SilkS"))
    (fp_line (start -1.3 -0.7) (end -1.45 -0.7)
      (stroke (width 0.12) (type solid)) (layer "F.SilkS"))
    (fp_line (start 1.3 -0.7) (end 1.45 -0.7)
      (stroke (width 0.12) (type solid)) (layer "F.SilkS"))
    (fp_line (start 1.3 0.7) (end 1.45 0.7)
      (stroke (width 0.12) (type solid)) (layer "F.SilkS"))
    (fp_line (start 1.45 -0.7) (end 1.45 -0.4)
      (stroke (width 0.12) (type solid)) (layer "F.SilkS"))
    (fp_line (start 1.45 0.7) (end 1.45 0.4)
      (stroke (width 0.12) (type solid)) (layer "F.SilkS"))
    (fp_rect (start -1.55 -1.85) (end 1.55 1.75)
      (stroke (width 0.05) (type solid)) (fill none) (layer "F.CrtYd"))
    (fp_line (start -1.5 -0.7) (end 1.5 -0.7)
      (stroke (width 0.1) (type solid)) (layer "F.Fab"))
    (fp_line (start -1.5 0.7) (end -1.5 -0.7)
      (stroke (width 0.1) (type solid)) (layer "F.Fab"))
    (fp_line (start 1.5 -0.7) (end 1.5 0.7)
      (stroke (width 0.1) (type solid)) (layer "F.Fab"))
    (fp_line (start 1.5 0.7) (end -1.5 0.7)
      (stroke (width 0.1) (type solid)) (layer "F.Fab"))
    (pad "1" smd roundrect (at -0.954 1.1 90) (size 0.55 1) (layers "F.Cu" "F.Paste" "F.Mask") (roundrect_rratio 0.15)
      (net 664 "Net-(U26-~{PB_IN})") (pinfunction "~{PB_IN}") (pintype "input"))
    (pad "2" smd roundrect (at -0.003 1.1 90) (size 0.55 1) (layers "F.Cu" "F.Paste" "F.Mask") (roundrect_rratio 0.15)
      (net 9 "GND") (pinfunction "GND") (pintype "power_in"))
    (pad "3" smd roundrect (at 0.947 1.1 90) (size 0.55 1) (layers "F.Cu" "F.Paste" "F.Mask") (roundrect_rratio 0.15)
      (net 846 "5V_ON_OFF") (pinfunction "VCC") (pintype "power_in"))
    (pad "4" smd roundrect (at 0.947 -1.214 90) (size 0.55 1) (layers "F.Cu" "F.Paste" "F.Mask") (roundrect_rratio 0.15)
      (net 859 "/Supply/OUT") (pinfunction "OUT") (pintype "output"))
    (pad "5" smd roundrect (at -0.003 -1.214 90) (size 0.55 1) (layers "F.Cu" "F.Paste" "F.Mask") (roundrect_rratio 0.15)
      (net 119 "/Supply/~{INT}") (pinfunction "~{INT}") (pintype "output"))
    (pad "6" smd roundrect (at -0.954 -1.214 90) (size 0.55 1) (layers "F.Cu" "F.Paste" "F.Mask") (roundrect_rratio 0.15)
      (net 860 "/Supply/~{CLR}") (pinfunction "~{CLR}") (pintype "input"))
  )

  (footprint "data-center-rdimm-ddr4-tester-footprints:R_0201" (layer "F.Cu")
    (at 155.275 109.03 -90)
    (descr "Resistor SMD 0201")
    (tags "resistor SMD 0201")
    (property "Author" "Antmicro")
    (property "License" "Apache-2.0")
    (property "MPN" "CR0201-FX-0R00GLF")
    (property "Manufacturer" "Bourns")
    (property "Sheetfile" "ethernet.kicad_sch")
    (property "Sheetname" "Ethernet")
    (property "Tolerance" "1%")
    (property "Val" "0R")
    (property "ki_description" "0R resistor in 0201 package with 1% tolerance")
    (attr smd)
    (fp_text reference "R105" (at 3.49 -0.275 -90) (layer "F.SilkS")
        (effects (font (size 0.7 0.7) (thickness 0.15)) (justify left bottom))
    )
    (fp_text value "R_0R_0201" (at 0 1.25 -90) (layer "F.Fab") hide
        (effects (font (size 0.7 0.7) (thickness 0.15)) (justify left bottom))
    )
    (fp_text user "License: Apache-2.0" (at -0.71 4.25 -90) (layer "F.Fab") hide
        (effects (font (size 0.7 0.7) (thickness 0.15)) (justify left bottom))
    )
    (fp_text user "Author: Antmicro" (at -0.71 5.25 -90) (layer "F.Fab") hide
        (effects (font (size 0.7 0.7) (thickness 0.15)) (justify left bottom))
    )
    (fp_text user "${REFERENCE}" (at -0.71 3.25 -90) (layer "F.Fab") hide
        (effects (font (size 0.7 0.7) (thickness 0.15)) (justify left bottom))
    )
    (fp_rect (start -0.71 -0.36) (end 0.71 0.36)
      (stroke (width 0.05) (type solid)) (fill none) (layer "F.CrtYd"))
    (fp_rect (start -0.3 -0.15) (end 0.298 0.148)
      (stroke (width 0.15) (type solid)) (fill none) (layer "F.Fab"))
    (pad "" smd roundrect (at -0.346 0 270) (size 0.318 0.36) (layers "F.Paste") (roundrect_rratio 0.25))
    (pad "" smd roundrect (at 0.344 0 270) (size 0.318 0.36) (layers "F.Paste") (roundrect_rratio 0.25))
    (pad "1" smd roundrect (at -0.32 0 270) (size 0.46 0.4) (layers "F.Cu" "F.Mask") (roundrect_rratio 0.25)
      (net 824 "/Ethernet/ETH1_BP_P") (pintype "passive"))
    (pad "2" smd roundrect (at 0.32 0 270) (size 0.46 0.4) (layers "F.Cu" "F.Mask") (roundrect_rratio 0.25)
      (net 631 "/Ethernet/INT_ETH1_P") (pintype "passive"))
  )

  (footprint "data-center-rdimm-ddr4-tester-footprints:C_0201" (layer "F.Cu")
    (at 252.85 80.5 90)
    (descr "Capacitor SMD 0201")
    (tags "capacitor SMD 0201")
    (property "Author" "Antmicro")
    (property "Dielectric" "")
    (property "License" "Apache-2.0")
    (property "MPN" "CC0201KRX6S5BB104")
    (property "Manufacturer" "Yaego")
    (property "Sheetfile" "fmc_hpc.kicad_sch")
    (property "Sheetname" "FMC HPC")
    (property "Val" "100n")
    (property "Voltage" "")
    (property "ki_description" " ")
    (attr smd)
    (fp_text reference "C257" (at -1.31 -0.42 90) (layer "F.SilkS")
        (effects (font (size 0.7 0.7) (thickness 0.15)) (justify left bottom))
    )
    (fp_text value "C_100n_0201" (at 0 1.4 90) (layer "F.Fab") hide
        (effects (font (size 0.7 0.7) (thickness 0.15)) (justify left bottom))
    )
    (fp_text user "${REFERENCE}" (at -0.72 3.4 90) (layer "F.Fab") hide
        (effects (font (size 0.7 0.7) (thickness 0.15)) (justify left bottom))
    )
    (fp_text user "Author: Antmicro" (at -0.72 5.4 90) (layer "F.Fab") hide
        (effects (font (size 0.7 0.7) (thickness 0.15)) (justify left bottom))
    )
    (fp_text user "License: Apache-2.0" (at -0.72 4.4 90) (layer "F.Fab") hide
        (effects (font (size 0.7 0.7) (thickness 0.15)) (justify left bottom))
    )
    (fp_rect (start -0.72 -0.38) (end 0.72 0.38)
      (stroke (width 0.05) (type solid)) (fill none) (layer "F.CrtYd"))
    (fp_rect (start 0.3 0.15) (end -0.301 -0.149)
      (stroke (width 0.15) (type solid)) (fill none) (layer "F.Fab"))
    (pad "" smd roundrect (at -0.349 -0.002 90) (size 0.318 0.36) (layers "F.Paste") (roundrect_rratio 0.25))
    (pad "" smd roundrect (at 0.341 -0.002 90) (size 0.318 0.36) (layers "F.Paste") (roundrect_rratio 0.25))
    (pad "1" smd roundrect (at -0.321 -0.002 90) (size 0.46 0.4) (layers "F.Cu" "F.Mask") (roundrect_rratio 0.25)
      (net 535 "12P0V") (pintype "passive"))
    (pad "2" smd roundrect (at 0.32 -0.002 90) (size 0.46 0.4) (layers "F.Cu" "F.Mask") (roundrect_rratio 0.25)
      (net 9 "GND") (pintype "passive"))
  )

  (footprint "data-center-rdimm-ddr4-tester-footprints:Fiducial_1mm_Mask2mm" (layer "F.Cu")
    (at 114.35 48.55)
    (descr "Circular Fiducial, 1mm bare copper, 3mm soldermask opening")
    (tags "fiducial")
    (property "Author" "Antmicro")
    (property "License" "Apache-2.0")
    (property "MPN" "")
    (property "Manufacturer" "")
    (property "Sheetfile" "data-center-rdimm-ddr4-tester.kicad_sch")
    (property "Sheetname" "")
    (property "exclude_from_bom" "")
    (property "ki_description" "Fiducial Marker for use with single board only")
    (attr exclude_from_pos_files exclude_from_bom)
    (fp_text reference "FID1" (at 1.39 -0.43) (layer "F.SilkS")
        (effects (font (size 0.7 0.7) (thickness 0.15)) (justify left bottom))
    )
    (fp_text value "Fiducial_1mm_Mask2mm" (at 0 2.2) (layer "F.Fab")
        (effects (font (size 0.7 0.7) (thickness 0.15)) (justify left bottom))
    )
    (fp_text user "${REFERENCE}" (at -1.25 4.603) (layer "F.Fab") hide
        (effects (font (size 0.7 0.7) (thickness 0.15)) (justify left bottom))
    )
    (fp_text user "Author: Antmicro" (at -1.25 5.803) (layer "F.Fab") hide
        (effects (font (size 0.7 0.7) (thickness 0.15)) (justify left bottom))
    )
    (fp_text user "License: Apache-2.0" (at -1.25 7.003) (layer "F.Fab") hide
        (effects (font (size 0.7 0.7) (thickness 0.15)) (justify left bottom))
    )
    (fp_circle (center 0 0) (end 1.24 0)
      (stroke (width 0.05) (type solid)) (fill none) (layer "F.CrtYd"))
    (fp_circle (center 0 0) (end 0.999 0)
      (stroke (width 0.15) (type solid)) (fill none) (layer "F.Fab"))
    (pad "" smd circle (at 0 0) (size 1 1) (layers "F.Cu" "F.Mask")
      (solder_mask_margin 0.5) (clearance 0.5))
  )

  (footprint "data-center-rdimm-ddr4-tester-footprints:NetTie-2_SMD_Pad0.127mm" (layer "F.Cu")
    (at 123.2 87.53 90)
    (descr "Net tie, 2 pin, 0.127mm  SMD pads")
    (tags "net tie")
    (property "Author" "Antmicro")
    (property "License" "Apache-2.0")
    (property "MPN" "")
    (property "Manufacturer" "")
    (property "Sheetfile" "supply.kicad_sch")
    (property "Sheetname" "Supply")
    (property "ki_description" "Net tie, 2 pins")
    (property "ki_keywords" "net tie short")
    (attr through_hole exclude_from_pos_files)
    (net_tie_pad_groups "1, 2")
    (fp_text reference "NT5" (at -0.128 -1.345 90) (layer "F.SilkS") hide
        (effects (font (size 0.7 0.7) (thickness 0.15)) (justify left bottom))
    )
    (fp_text value "Net-Tie_2" (at 0 1.199 90) (layer "F.Fab") hide
        (effects (font (size 0.7 0.7) (thickness 0.15)) (justify left bottom))
    )
    (fp_text user "Author: Antmicro" (at -0.128 4.4 90) (layer "F.Fab") hide
        (effects (font (size 0.7 0.7) (thickness 0.15)) (justify left bottom))
    )
    (fp_text user "${REFERENCE}" (at -0.128 3.2 90) (layer "F.Fab") hide
        (effects (font (size 0.7 0.7) (thickness 0.15)) (justify left bottom))
    )
    (fp_text user "License: Apache-2.0" (at -0.128 5.6 90) (layer "F.Fab") hide
        (effects (font (size 0.7 0.7) (thickness 0.15)) (justify left bottom))
    )
    (fp_poly
      (pts
        (xy -0.0635 -0.0635)
        (xy 0.0625 -0.0635)
        (xy 0.0625 0.0635)
        (xy -0.0635 0.0635)
      )

      (stroke (width 0) (type solid)) (fill solid) (layer "F.Cu"))
    (pad "1" smd roundrect (at -0.127 0 270) (size 0.127 0.127) (layers "F.Cu") (roundrect_rratio 0.5)
      (chamfer_ratio 0) (chamfer top_left bottom_left)
      (net 836 "/Supply/VPP_SEN_-") (pinfunction "1") (pintype "passive"))
    (pad "2" smd roundrect (at 0.126 0 90) (size 0.127 0.127) (layers "F.Cu") (roundrect_rratio 0.5)
      (chamfer_ratio 0) (chamfer top_left bottom_left)
      (net 184 "VPP") (pinfunction "2") (pintype "passive"))
  )

  (footprint "data-center-rdimm-ddr4-tester-footprints:NetTie-2_SMD_Pad0.127mm" (layer "F.Cu")
    (at 112.425 90.67 90)
    (descr "Net tie, 2 pin, 0.127mm  SMD pads")
    (tags "net tie")
    (property "Author" "Antmicro")
    (property "License" "Apache-2.0")
    (property "MPN" "")
    (property "Manufacturer" "")
    (property "Sheetfile" "supply.kicad_sch")
    (property "Sheetname" "Supply")
    (property "ki_description" "Net tie, 2 pins")
    (property "ki_keywords" "net tie short")
    (attr through_hole exclude_from_pos_files)
    (net_tie_pad_groups "1, 2")
    (fp_text reference "NT6" (at -0.128 -1.345 90) (layer "F.SilkS") hide
        (effects (font (size 0.7 0.7) (thickness 0.15)) (justify left bottom))
    )
    (fp_text value "Net-Tie_2" (at 0 1.199 90) (layer "F.Fab") hide
        (effects (font (size 0.7 0.7) (thickness 0.15)) (justify left bottom))
    )
    (fp_text user "${REFERENCE}" (at -0.128 3.2 90) (layer "F.Fab") hide
        (effects (font (size 0.7 0.7) (thickness 0.15)) (justify left bottom))
    )
    (fp_text user "Author: Antmicro" (at -0.128 4.4 90) (layer "F.Fab") hide
        (effects (font (size 0.7 0.7) (thickness 0.15)) (justify left bottom))
    )
    (fp_text user "License: Apache-2.0" (at -0.128 5.6 90) (layer "F.Fab") hide
        (effects (font (size 0.7 0.7) (thickness 0.15)) (justify left bottom))
    )
    (fp_poly
      (pts
        (xy -0.0635 -0.0635)
        (xy 0.0625 -0.0635)
        (xy 0.0625 0.0635)
        (xy -0.0635 0.0635)
      )

      (stroke (width 0) (type solid)) (fill solid) (layer "F.Cu"))
    (pad "1" smd roundrect (at -0.127 0 270) (size 0.127 0.127) (layers "F.Cu") (roundrect_rratio 0.5)
      (chamfer_ratio 0) (chamfer top_left bottom_left)
      (net 837 "/Supply/VTT_SEN_-") (pinfunction "1") (pintype "passive"))
    (pad "2" smd roundrect (at 0.126 0 90) (size 0.127 0.127) (layers "F.Cu") (roundrect_rratio 0.5)
      (chamfer_ratio 0) (chamfer top_left bottom_left)
      (net 186 "VTT") (pinfunction "2") (pintype "passive"))
  )

  (footprint "data-center-rdimm-ddr4-tester-footprints:R_1206_3216Metric" (layer "F.Cu")
    (at 123.2 88.4 90)
    (property "Author" "Antmicro")
    (property "License" "Apache-2.0")
    (property "MPN" "RL1206FR-7W0R01L")
    (property "Manufacturer" "Yaego")
    (property "Sheetfile" "supply.kicad_sch")
    (property "Sheetname" "Supply")
    (property "Tolerance" "1%")
    (property "Val" "0R01")
    (property "ki_description" "0R01 resistor in 1206 package with unspecified tolerance")
    (attr smd)
    (fp_text reference "R198" (at 0 -1.2 90) (layer "F.SilkS")
        (effects (font (size 0.7 0.7) (thickness 0.15)) (justify left bottom))
    )
    (fp_text value "R_0R01_1206" (at 0 2 90) (layer "F.Fab") hide
        (effects (font (size 0.7 0.7) (thickness 0.15)) (justify left bottom))
    )
    (fp_text user "License: Apache-2.0" (at -2.401 6.3 90) (layer "F.Fab") hide
        (effects (font (size 0.7 0.7) (thickness 0.15)) (justify left bottom))
    )
    (fp_text user "${REFERENCE}" (at -2.401 3.5 90) (layer "F.Fab") hide
        (effects (font (size 0.7 0.7) (thickness 0.15)) (justify left bottom))
    )
    (fp_text user "Author: Antmicro" (at -2.401 4.899 90) (layer "F.Fab") hide
        (effects (font (size 0.7 0.7) (thickness 0.15)) (justify left bottom))
    )
    (fp_line (start 0 -0.902) (end -0.5 -0.902)
      (stroke (width 0.15) (type solid)) (layer "F.SilkS"))
    (fp_line (start 0 -0.902) (end 0.498 -0.902)
      (stroke (width 0.15) (type solid)) (layer "F.SilkS"))
    (fp_line (start 0 0.9) (end -0.5 0.9)
      (stroke (width 0.15) (type solid)) (layer "F.SilkS"))
    (fp_line (start 0 0.9) (end 0.498 0.9)
      (stroke (width 0.15) (type solid)) (layer "F.SilkS"))
    (fp_rect (start -2.25 -1.05) (end 2.25 1.05)
      (stroke (width 0.05) (type solid)) (fill none) (layer "F.CrtYd"))
    (fp_line (start -1.601 -0.802) (end -1.601 0.8)
      (stroke (width 0.15) (type solid)) (layer "F.Fab"))
    (fp_line (start -1.601 -0.802) (end 1.6 -0.802)
      (stroke (width 0.15) (type solid)) (layer "F.Fab"))
    (fp_line (start -1.601 0.8) (end 1.6 0.8)
      (stroke (width 0.15) (type solid)) (layer "F.Fab"))
    (fp_line (start 1.6 -0.802) (end 1.6 0.8)
      (stroke (width 0.15) (type solid)) (layer "F.Fab"))
    (pad "1" smd roundrect (at -1.5 0 90) (size 1.2 1.8) (layers "F.Cu" "F.Paste" "F.Mask") (roundrect_rratio 0.15)
      (net 303 "VCC2V5") (pintype "passive"))
    (pad "2" smd roundrect (at 1.499 0 90) (size 1.2 1.8) (layers "F.Cu" "F.Paste" "F.Mask") (roundrect_rratio 0.15)
      (net 184 "VPP") (pintype "passive"))
  )

  (footprint "data-center-rdimm-ddr4-tester-footprints:R_0201" (layer "F.Cu")
    (at 164.04 109.02 90)
    (descr "Resistor SMD 0201")
    (tags "resistor SMD 0201")
    (property "Author" "Antmicro")
    (property "License" "Apache-2.0")
    (property "MPN" "CR0201-FX-0R00GLF")
    (property "Manufacturer" "Bourns")
    (property "Sheetfile" "ethernet.kicad_sch")
    (property "Sheetname" "Ethernet")
    (property "Tolerance" "1%")
    (property "Val" "0R")
    (property "ki_description" "0R resistor in 0201 package with 1% tolerance")
    (attr smd)
    (fp_text reference "R112" (at -3.43 0.48 90) (layer "F.SilkS")
        (effects (font (size 0.7 0.7) (thickness 0.15)) (justify left bottom))
    )
    (fp_text value "R_0R_0201" (at 0 1.25 90) (layer "F.Fab") hide
        (effects (font (size 0.7 0.7) (thickness 0.15)) (justify left bottom))
    )
    (fp_text user "${REFERENCE}" (at -0.71 3.25 90) (layer "F.Fab") hide
        (effects (font (size 0.7 0.7) (thickness 0.15)) (justify left bottom))
    )
    (fp_text user "Author: Antmicro" (at -0.71 5.25 90) (layer "F.Fab") hide
        (effects (font (size 0.7 0.7) (thickness 0.15)) (justify left bottom))
    )
    (fp_text user "License: Apache-2.0" (at -0.71 4.25 90) (layer "F.Fab") hide
        (effects (font (size 0.7 0.7) (thickness 0.15)) (justify left bottom))
    )
    (fp_rect (start -0.71 -0.36) (end 0.71 0.36)
      (stroke (width 0.05) (type solid)) (fill none) (layer "F.CrtYd"))
    (fp_rect (start -0.3 -0.15) (end 0.298 0.148)
      (stroke (width 0.15) (type solid)) (fill none) (layer "F.Fab"))
    (pad "" smd roundrect (at -0.346 0 90) (size 0.318 0.36) (layers "F.Paste") (roundrect_rratio 0.25))
    (pad "" smd roundrect (at 0.344 0 90) (size 0.318 0.36) (layers "F.Paste") (roundrect_rratio 0.25))
    (pad "1" smd roundrect (at -0.32 0 90) (size 0.46 0.4) (layers "F.Cu" "F.Mask") (roundrect_rratio 0.25)
      (net 547 "/Ethernet/INT_ETH4_N") (pintype "passive"))
    (pad "2" smd roundrect (at 0.32 0 90) (size 0.46 0.4) (layers "F.Cu" "F.Mask") (roundrect_rratio 0.25)
      (net 831 "/Ethernet/ETH4_BP_N") (pintype "passive"))
  )

  (footprint "data-center-rdimm-ddr4-tester-footprints:R_1206_3216Metric" (layer "F.Cu")
    (at 152.3 121.7)
    (property "Author" "Antmicro")
    (property "License" "Apache-2.0")
    (property "MPN" "RL1206FR-7W0R01L")
    (property "Manufacturer" "Yaego")
    (property "Sheetfile" "supply.kicad_sch")
    (property "Sheetname" "Supply")
    (property "Tolerance" "1%")
    (property "Val" "0R01")
    (property "ki_description" "0R01 resistor in 1206 package with unspecified tolerance")
    (attr smd)
    (fp_text reference "R162" (at -1.45 1.86) (layer "F.SilkS")
        (effects (font (size 0.7 0.7) (thickness 0.15)) (justify left bottom))
    )
    (fp_text value "R_0R01_1206" (at 0 2) (layer "F.Fab") hide
        (effects (font (size 0.7 0.7) (thickness 0.15)) (justify left bottom))
    )
    (fp_text user "License: Apache-2.0" (at -2.401 6.3) (layer "F.Fab") hide
        (effects (font (size 0.7 0.7) (thickness 0.15)) (justify left bottom))
    )
    (fp_text user "${REFERENCE}" (at -2.401 3.5) (layer "F.Fab") hide
        (effects (font (size 0.7 0.7) (thickness 0.15)) (justify left bottom))
    )
    (fp_text user "Author: Antmicro" (at -2.401 4.899) (layer "F.Fab") hide
        (effects (font (size 0.7 0.7) (thickness 0.15)) (justify left bottom))
    )
    (fp_line (start 0 -0.902) (end -0.5 -0.902)
      (stroke (width 0.15) (type solid)) (layer "F.SilkS"))
    (fp_line (start 0 -0.902) (end 0.498 -0.902)
      (stroke (width 0.15) (type solid)) (layer "F.SilkS"))
    (fp_line (start 0 0.9) (end -0.5 0.9)
      (stroke (width 0.15) (type solid)) (layer "F.SilkS"))
    (fp_line (start 0 0.9) (end 0.498 0.9)
      (stroke (width 0.15) (type solid)) (layer "F.SilkS"))
    (fp_rect (start -2.25 -1.05) (end 2.25 1.05)
      (stroke (width 0.05) (type solid)) (fill none) (layer "F.CrtYd"))
    (fp_line (start -1.601 -0.802) (end -1.601 0.8)
      (stroke (width 0.15) (type solid)) (layer "F.Fab"))
    (fp_line (start -1.601 -0.802) (end 1.6 -0.802)
      (stroke (width 0.15) (type solid)) (layer "F.Fab"))
    (fp_line (start -1.601 0.8) (end 1.6 0.8)
      (stroke (width 0.15) (type solid)) (layer "F.Fab"))
    (fp_line (start 1.6 -0.802) (end 1.6 0.8)
      (stroke (width 0.15) (type solid)) (layer "F.Fab"))
    (pad "1" smd roundrect (at -1.5 0) (size 1.2 1.8) (layers "F.Cu" "F.Paste" "F.Mask") (roundrect_rratio 0.15)
      (net 176 "VCC1V2") (pintype "passive"))
    (pad "2" smd roundrect (at 1.499 0) (size 1.2 1.8) (layers "F.Cu" "F.Paste" "F.Mask") (roundrect_rratio 0.15)
      (net 306 "1V2_SYS") (pintype "passive"))
  )

  (footprint "data-center-rdimm-ddr4-tester-footprints:R_0402_1005Metric" (layer "F.Cu")
    (at 238.785 123.3 180)
    (descr "Resistor SMD 0402")
    (tags "resistor SMD 0402")
    (property "Author" "Antmicro")
    (property "License" "Apache-2.0")
    (property "MPN" "CR0402-FX-4702GLF")
    (property "Manufacturer" "Bourns")
    (property "Sheetfile" "supply.kicad_sch")
    (property "Sheetname" "Supply")
    (property "Tolerance" "1%")
    (property "Val" "47k")
    (property "ki_description" "47k resistor in 0402 package with 1% tolerance")
    (attr smd)
    (fp_text reference "R120" (at -0.785 -0.11 180) (layer "F.SilkS")
        (effects (font (size 0.7 0.7) (thickness 0.15)) (justify left bottom))
    )
    (fp_text value "R_47k_0402" (at 0 1.4 180) (layer "F.Fab") hide
        (effects (font (size 0.7 0.7) (thickness 0.15)) (justify left bottom))
    )
    (fp_text user "${REFERENCE}" (at -0.95 3.168 180) (layer "F.Fab") hide
        (effects (font (size 0.7 0.7) (thickness 0.15)) (justify left bottom))
    )
    (fp_text user "Author: Antmicro" (at -0.95 4.169 180) (layer "F.Fab") hide
        (effects (font (size 0.7 0.7) (thickness 0.15)) (justify left bottom))
    )
    (fp_text user "License: Apache-2.0" (at -0.95 5.169 180) (layer "F.Fab") hide
        (effects (font (size 0.7 0.7) (thickness 0.15)) (justify left bottom))
    )
    (fp_rect (start -0.93 -0.47) (end 0.93 0.47)
      (stroke (width 0.05) (type solid)) (fill none) (layer "F.CrtYd"))
    (fp_rect (start -0.5 -0.25) (end 0.5 0.25)
      (stroke (width 0.15) (type solid)) (fill none) (layer "F.Fab"))
    (pad "1" smd roundrect (at -0.485 0 180) (size 0.59 0.64) (layers "F.Cu" "F.Paste" "F.Mask") (roundrect_rratio 0.25)
      (net 9 "GND") (pintype "passive"))
    (pad "2" smd roundrect (at 0.485 0 180) (size 0.59 0.64) (layers "F.Cu" "F.Paste" "F.Mask") (roundrect_rratio 0.25)
      (net 108 "Net-(U27-~{OE})") (pintype "passive"))
  )

  (footprint "data-center-rdimm-ddr4-tester-footprints:C_0402_1005Metric" (layer "F.Cu")
    (at 256.63 100.5)
    (descr "Capacitor SMD 0402")
    (tags "capacitor SMD 0402")
    (property "Author" "Antmicro")
    (property "Dielectric" "X5R")
    (property "License" "Apache-2.0")
    (property "MPN" "GRM155R61H104KE14D")
    (property "Manufacturer" "Murata")
    (property "Sheetfile" "pcie.kicad_sch")
    (property "Sheetname" "FPGA banks 115-116")
    (property "Val" "100n")
    (property "Voltage" "50V")
    (property "ki_description" " ")
    (attr smd)
    (fp_text reference "C194" (at -0.65 2.28) (layer "F.SilkS")
        (effects (font (size 0.7 0.7) (thickness 0.15)) (justify left bottom))
    )
    (fp_text value "C_100n_0402" (at 0 1.4) (layer "F.Fab") hide
        (effects (font (size 0.7 0.7) (thickness 0.15)) (justify left bottom))
    )
    (fp_text user "License: Apache-2.0" (at -0.932 5.17) (layer "F.Fab") hide
        (effects (font (size 0.7 0.7) (thickness 0.15)) (justify left bottom))
    )
    (fp_text user "Author: Antmicro" (at -0.932 4.17) (layer "F.Fab") hide
        (effects (font (size 0.7 0.7) (thickness 0.15)) (justify left bottom))
    )
    (fp_text user "${REFERENCE}" (at -0.932 3.168) (layer "F.Fab") hide
        (effects (font (size 0.7 0.7) (thickness 0.15)) (justify left bottom))
    )
    (fp_rect (start -0.94 -0.47) (end 0.94 0.47)
      (stroke (width 0.05) (type solid)) (fill none) (layer "F.CrtYd"))
    (fp_rect (start -0.499 -0.249) (end 0.499 0.249)
      (stroke (width 0.15) (type solid)) (fill none) (layer "F.Fab"))
    (pad "1" smd roundrect (at -0.484 0) (size 0.59 0.64) (layers "F.Cu" "F.Paste" "F.Mask") (roundrect_rratio 0.25)
      (net 891 "GTR_REFCLK1_C_P") (pintype "passive"))
    (pad "2" smd roundrect (at 0.484 0) (size 0.59 0.64) (layers "F.Cu" "F.Paste" "F.Mask") (roundrect_rratio 0.25)
      (net 883 "/FPGA banks 115-116/GTR_REFCLK1_P") (pintype "passive"))
  )

  (footprint "data-center-rdimm-ddr4-tester-footprints:Testpoint_smd_1mm" (layer "F.Cu")
    (at 143.375 126.65)
    (property "Author" "Antmicro")
    (property "License" "Apache-2.0")
    (property "MPN" "")
    (property "Manufacturer" "")
    (property "Sheetfile" "interfaces.kicad_sch")
    (property "Sheetname" "Interfaces")
    (property "ki_description" "Test Point 1mm")
    (attr exclude_from_pos_files)
    (fp_text reference "VBUS1" (at -3.885 0.4) (layer "F.SilkS")
        (effects (font (size 0.7 0.7) (thickness 0.15)) (justify left bottom))
    )
    (fp_text value "TP_1mm_SMD" (at 0 1.4) (layer "F.Fab") hide
        (effects (font (size 0.7 0.7) (thickness 0.15)) (justify left bottom))
    )
    (fp_text user "License: Apache-2.0" (at -0.5 5.2) (layer "F.Fab") hide
        (effects (font (size 0.7 0.7) (thickness 0.15)) (justify left bottom))
    )
    (fp_text user "Author: Antmicro" (at -0.5 4) (layer "F.Fab") hide
        (effects (font (size 0.7 0.7) (thickness 0.15)) (justify left bottom))
    )
    (fp_text user "${REFERENCE}" (at -0.5 2.8) (layer "F.Fab") hide
        (effects (font (size 0.7 0.7) (thickness 0.15)) (justify left bottom))
    )
    (pad "1" smd circle (at 0 0) (size 1 1) (layers "F.Cu" "F.Mask")
      (net 853 "VBUS") (pinfunction "1") (pintype "passive"))
  )

  (footprint "data-center-rdimm-ddr4-tester-footprints:C_0402_1005Metric" (layer "F.Cu")
    (at 158.7 104.475 -90)
    (descr "Capacitor SMD 0402")
    (tags "capacitor SMD 0402")
    (property "Author" "Antmicro")
    (property "DNP" "DNP")
    (property "Dielectric" "X5R")
    (property "License" "Apache-2.0")
    (property "MPN" "GRM155R61H104KE14D")
    (property "Manufacturer" "Murata")
    (property "Sheetfile" "ethernet.kicad_sch")
    (property "Sheetname" "Ethernet")
    (property "Val" "100n")
    (property "Voltage" "50V")
    (property "dnp" "")
    (property "exclude_from_bom" "")
    (property "ki_description" " ")
    (attr exclude_from_pos_files exclude_from_bom)
    (fp_text reference "C290" (at 3.615 -0.37 -90) (layer "F.SilkS")
        (effects (font (size 0.7 0.7) (thickness 0.15)) (justify left bottom))
    )
    (fp_text value "C_100n_0402" (at 0 1.4 -90) (layer "F.Fab") hide
        (effects (font (size 0.7 0.7) (thickness 0.15)) (justify left bottom))
    )
    (fp_text user "${REFERENCE}" (at -0.932 3.168 -90) (layer "F.Fab") hide
        (effects (font (size 0.7 0.7) (thickness 0.15)) (justify left bottom))
    )
    (fp_text user "License: Apache-2.0" (at -0.932 5.17 -90) (layer "F.Fab") hide
        (effects (font (size 0.7 0.7) (thickness 0.15)) (justify left bottom))
    )
    (fp_text user "Author: Antmicro" (at -0.932 4.17 -90) (layer "F.Fab") hide
        (effects (font (size 0.7 0.7) (thickness 0.15)) (justify left bottom))
    )
    (fp_rect (start -0.94 -0.47) (end 0.94 0.47)
      (stroke (width 0.05) (type solid)) (fill none) (layer "F.CrtYd"))
    (fp_rect (start -0.499 -0.249) (end 0.499 0.249)
      (stroke (width 0.15) (type solid)) (fill none) (layer "F.Fab"))
    (pad "1" smd roundrect (at -0.484 0 270) (size 0.59 0.64) (layers "F.Cu" "F.Paste" "F.Mask") (roundrect_rratio 0.25)
      (net 143 "3V3_SYS") (pintype "passive"))
    (pad "2" smd roundrect (at 0.484 0 270) (size 0.59 0.64) (layers "F.Cu" "F.Paste" "F.Mask") (roundrect_rratio 0.25)
      (net 9 "GND") (pintype "passive"))
  )

  (footprint "data-center-rdimm-ddr4-tester-footprints:C_0402_1005Metric" (layer "F.Cu")
    (at 254.71 87.795 180)
    (descr "Capacitor SMD 0402")
    (tags "capacitor SMD 0402")
    (property "Author" "Antmicro")
    (property "Dielectric" "X5R")
    (property "License" "Apache-2.0")
    (property "MPN" "GRM155R61H104KE14D")
    (property "Manufacturer" "Murata")
    (property "Sheetfile" "fmc_hpc.kicad_sch")
    (property "Sheetname" "FMC HPC")
    (property "Val" "100n")
    (property "Voltage" "50V")
    (property "ki_description" " ")
    (attr smd)
    (fp_text reference "C265" (at -0.8 -0.355 180) (layer "F.SilkS")
        (effects (font (size 0.7 0.7) (thickness 0.15)) (justify left bottom))
    )
    (fp_text value "C_100n_0402" (at 0 1.4 180) (layer "F.Fab") hide
        (effects (font (size 0.7 0.7) (thickness 0.15)) (justify left bottom))
    )
    (fp_text user "${REFERENCE}" (at -0.932 3.168 180) (layer "F.Fab") hide
        (effects (font (size 0.7 0.7) (thickness 0.15)) (justify left bottom))
    )
    (fp_text user "License: Apache-2.0" (at -0.932 5.17 180) (layer "F.Fab") hide
        (effects (font (size 0.7 0.7) (thickness 0.15)) (justify left bottom))
    )
    (fp_text user "Author: Antmicro" (at -0.932 4.17 180) (layer "F.Fab") hide
        (effects (font (size 0.7 0.7) (thickness 0.15)) (justify left bottom))
    )
    (fp_rect (start -0.94 -0.47) (end 0.94 0.47)
      (stroke (width 0.05) (type solid)) (fill none) (layer "F.CrtYd"))
    (fp_rect (start -0.499 -0.249) (end 0.499 0.249)
      (stroke (width 0.15) (type solid)) (fill none) (layer "F.Fab"))
    (pad "1" smd roundrect (at -0.484 0 180) (size 0.59 0.64) (layers "F.Cu" "F.Paste" "F.Mask") (roundrect_rratio 0.25)
      (net 440 "/FMC HPC/GTX_TX3_C_P") (pintype "passive"))
    (pad "2" smd roundrect (at 0.484 0 180) (size 0.59 0.64) (layers "F.Cu" "F.Paste" "F.Mask") (roundrect_rratio 0.25)
      (net 450 "GTX_TX3_P") (pintype "passive"))
  )

  (footprint "data-center-rdimm-ddr4-tester-footprints:R_0402_1005Metric" (layer "F.Cu")
    (at 202 124.3)
    (descr "Resistor SMD 0402")
    (tags "resistor SMD 0402")
    (property "Author" "Antmicro")
    (property "License" "Apache-2.0")
    (property "MPN" "CR0402-FX-3300GLF")
    (property "Manufacturer" "Bourns")
    (property "Sheetfile" "interfaces.kicad_sch")
    (property "Sheetname" "Interfaces")
    (property "Tolerance" "1%")
    (property "Val" "330R")
    (property "ki_description" "330R resistor in 0402 package with 1% tolerance")
    (attr smd)
    (fp_text reference "R147" (at 0.78 0.4) (layer "F.SilkS")
        (effects (font (size 0.7 0.7) (thickness 0.15)) (justify left bottom))
    )
    (fp_text value "R_330R_0402" (at 0 1.4) (layer "F.Fab") hide
        (effects (font (size 0.7 0.7) (thickness 0.15)) (justify left bottom))
    )
    (fp_text user "Author: Antmicro" (at -0.95 4.169) (layer "F.Fab") hide
        (effects (font (size 0.7 0.7) (thickness 0.15)) (justify left bottom))
    )
    (fp_text user "${REFERENCE}" (at -0.95 3.168) (layer "F.Fab") hide
        (effects (font (size 0.7 0.7) (thickness 0.15)) (justify left bottom))
    )
    (fp_text user "License: Apache-2.0" (at -0.95 5.169) (layer "F.Fab") hide
        (effects (font (size 0.7 0.7) (thickness 0.15)) (justify left bottom))
    )
    (fp_rect (start -0.93 -0.47) (end 0.93 0.47)
      (stroke (width 0.05) (type solid)) (fill none) (layer "F.CrtYd"))
    (fp_rect (start -0.5 -0.25) (end 0.5 0.25)
      (stroke (width 0.15) (type solid)) (fill none) (layer "F.Fab"))
    (pad "1" smd roundrect (at -0.485 0) (size 0.59 0.64) (layers "F.Cu" "F.Paste" "F.Mask") (roundrect_rratio 0.25)
      (net 9 "GND") (pintype "passive"))
    (pad "2" smd roundrect (at 0.485 0) (size 0.59 0.64) (layers "F.Cu" "F.Paste" "F.Mask") (roundrect_rratio 0.25)
      (net 863 "GND1") (pintype "passive"))
  )

  (footprint "data-center-rdimm-ddr4-tester-footprints:R_0201" (layer "F.Cu")
    (at 157.81 104.29 90)
    (descr "Resistor SMD 0201")
    (tags "resistor SMD 0201")
    (property "Author" "Antmicro")
    (property "License" "Apache-2.0")
    (property "MPN" "CR0201-FX-0R00GLF")
    (property "Manufacturer" "Bourns")
    (property "Sheetfile" "ethernet.kicad_sch")
    (property "Sheetname" "Ethernet")
    (property "Tolerance" "1%")
    (property "Val" "0R")
    (property "ki_description" "0R resistor in 0201 package with 1% tolerance")
    (attr smd)
    (fp_text reference "R100" (at 0.64 0.43 90) (layer "F.SilkS")
        (effects (font (size 0.7 0.7) (thickness 0.15)) (justify left bottom))
    )
    (fp_text value "R_0R_0201" (at 0 1.25 90) (layer "F.Fab") hide
        (effects (font (size 0.7 0.7) (thickness 0.15)) (justify left bottom))
    )
    (fp_text user "License: Apache-2.0" (at -0.71 4.25 90) (layer "F.Fab") hide
        (effects (font (size 0.7 0.7) (thickness 0.15)) (justify left bottom))
    )
    (fp_text user "Author: Antmicro" (at -0.71 5.25 90) (layer "F.Fab") hide
        (effects (font (size 0.7 0.7) (thickness 0.15)) (justify left bottom))
    )
    (fp_text user "${REFERENCE}" (at -0.71 3.25 90) (layer "F.Fab") hide
        (effects (font (size 0.7 0.7) (thickness 0.15)) (justify left bottom))
    )
    (fp_rect (start -0.71 -0.36) (end 0.71 0.36)
      (stroke (width 0.05) (type solid)) (fill none) (layer "F.CrtYd"))
    (fp_rect (start -0.3 -0.15) (end 0.298 0.148)
      (stroke (width 0.15) (type solid)) (fill none) (layer "F.Fab"))
    (pad "" smd roundrect (at -0.346 0 90) (size 0.318 0.36) (layers "F.Paste") (roundrect_rratio 0.25))
    (pad "" smd roundrect (at 0.344 0 90) (size 0.318 0.36) (layers "F.Paste") (roundrect_rratio 0.25))
    (pad "1" smd roundrect (at -0.32 0 90) (size 0.46 0.4) (layers "F.Cu" "F.Mask") (roundrect_rratio 0.25)
      (net 827 "/Ethernet/ETH2_BP_N") (pintype "passive"))
    (pad "2" smd roundrect (at 0.32 0 90) (size 0.46 0.4) (layers "F.Cu" "F.Mask") (roundrect_rratio 0.25)
      (net 172 "/Ethernet/ETH2_N") (pintype "passive"))
  )

  (footprint "data-center-rdimm-ddr4-tester-footprints:R_0402_1005Metric" (layer "F.Cu")
    (at 252.55 127.375 -90)
    (descr "Resistor SMD 0402")
    (tags "resistor SMD 0402")
    (property "Author" "Antmicro")
    (property "License" "Apache-2.0")
    (property "MPN" "CR0402-FX-1002GLF")
    (property "Manufacturer" "Bourns")
    (property "Sheetfile" "fmc_hpc.kicad_sch")
    (property "Sheetname" "FMC HPC")
    (property "Tolerance" "1%")
    (property "Val" "10k")
    (property "ki_description" "10k resistor in 0402 package with 1% tolerance")
    (attr smd)
    (fp_text reference "R154" (at 3.565 -0.57 -90) (layer "F.SilkS")
        (effects (font (size 0.7 0.7) (thickness 0.15)) (justify left bottom))
    )
    (fp_text value "R_10k_0402" (at 0 1.4 -90) (layer "F.Fab") hide
        (effects (font (size 0.7 0.7) (thickness 0.15)) (justify left bottom))
    )
    (fp_text user "Author: Antmicro" (at -0.95 4.169 -90) (layer "F.Fab") hide
        (effects (font (size 0.7 0.7) (thickness 0.15)) (justify left bottom))
    )
    (fp_text user "License: Apache-2.0" (at -0.95 5.169 -90) (layer "F.Fab") hide
        (effects (font (size 0.7 0.7) (thickness 0.15)) (justify left bottom))
    )
    (fp_text user "${REFERENCE}" (at -0.95 3.168 -90) (layer "F.Fab") hide
        (effects (font (size 0.7 0.7) (thickness 0.15)) (justify left bottom))
    )
    (fp_rect (start -0.93 -0.47) (end 0.93 0.47)
      (stroke (width 0.05) (type solid)) (fill none) (layer "F.CrtYd"))
    (fp_rect (start -0.5 -0.25) (end 0.5 0.25)
      (stroke (width 0.15) (type solid)) (fill none) (layer "F.Fab"))
    (pad "1" smd roundrect (at -0.485 0 270) (size 0.59 0.64) (layers "F.Cu" "F.Paste" "F.Mask") (roundrect_rratio 0.25)
      (net 181 "Net-(J5D-PG_{C2M})") (pintype "passive"))
    (pad "2" smd roundrect (at 0.485 0 270) (size 0.59 0.64) (layers "F.Cu" "F.Paste" "F.Mask") (roundrect_rratio 0.25)
      (net 143 "3V3_SYS") (pintype "passive"))
  )

  (footprint "data-center-rdimm-ddr4-tester-footprints:R_0402_1005Metric" (layer "F.Cu")
    (at 254.7 99.5)
    (descr "Resistor SMD 0402")
    (tags "resistor SMD 0402")
    (property "Author" "Antmicro")
    (property "License" "Apache-2.0")
    (property "MPN" "CR0402-FX-33R0GLF")
    (property "Manufacturer" "Bourns")
    (property "Sheetfile" "fmc_hpc.kicad_sch")
    (property "Sheetname" "FMC HPC")
    (property "Tolerance" "1%")
    (property "Val" "33R")
    (property "ki_description" "33R resistor in 0402 package with 1% tolerance")
    (attr smd)
    (fp_text reference "R149" (at -1.74 2.35) (layer "F.SilkS")
        (effects (font (size 0.7 0.7) (thickness 0.15)) (justify left bottom))
    )
    (fp_text value "R_33R_0402" (at 0 1.4) (layer "F.Fab") hide
        (effects (font (size 0.7 0.7) (thickness 0.15)) (justify left bottom))
    )
    (fp_text user "License: Apache-2.0" (at -0.95 5.169) (layer "F.Fab") hide
        (effects (font (size 0.7 0.7) (thickness 0.15)) (justify left bottom))
    )
    (fp_text user "Author: Antmicro" (at -0.95 4.169) (layer "F.Fab") hide
        (effects (font (size 0.7 0.7) (thickness 0.15)) (justify left bottom))
    )
    (fp_text user "${REFERENCE}" (at -0.95 3.168) (layer "F.Fab") hide
        (effects (font (size 0.7 0.7) (thickness 0.15)) (justify left bottom))
    )
    (fp_rect (start -0.93 -0.47) (end 0.93 0.47)
      (stroke (width 0.05) (type solid)) (fill none) (layer "F.CrtYd"))
    (fp_rect (start -0.5 -0.25) (end 0.5 0.25)
      (stroke (width 0.15) (type solid)) (fill none) (layer "F.Fab"))
    (pad "1" smd roundrect (at -0.485 0) (size 0.59 0.64) (layers "F.Cu" "F.Paste" "F.Mask") (roundrect_rratio 0.25)
      (net 898 "/FMC HPC/GTR_REFCLK1_R_N") (pintype "passive"))
    (pad "2" smd roundrect (at 0.485 0) (size 0.59 0.64) (layers "F.Cu" "F.Paste" "F.Mask") (roundrect_rratio 0.25)
      (net 892 "GTR_REFCLK1_C_N") (pintype "passive"))
  )

  (footprint "data-center-rdimm-ddr4-tester-footprints:USB-C_GCT_USB4105-GF-A" (layer "F.Cu")
    (at 148.85 132.988)
    (property "Author" "Antmicro")
    (property "License" "Apache-2.0")
    (property "MPN" "USB4105-GF-A")
    (property "Manufacturer" "GCT")
    (property "Sheetfile" "interfaces.kicad_sch")
    (property "Sheetname" "Interfaces")
    (attr smd)
    (fp_text reference "J9" (at -5.06 -4.558) (layer "F.SilkS")
        (effects (font (size 0.7 0.7) (thickness 0.15)) (justify left bottom))
    )
    (fp_text value "USB-C_USB4105-GF-A" (at 0 5) (layer "F.Fab")
        (effects (font (size 0.7 0.7) (thickness 0.15)) (justify left bottom))
    )
    (fp_text user "Author: Antmicro" (at -4.79 7.853) (layer "F.Fab") hide
        (effects (font (size 0.7 0.7) (thickness 0.15)) (justify left bottom))
    )
    (fp_text user "PCB-EDGE" (at -4.79 5.853) (layer "F.Fab") hide
        (effects (font (size 0.7 0.7) (thickness 0.15)) (justify left bottom))
    )
    (fp_text user "${REFERENCE}" (at -4.79 6.853) (layer "F.Fab") hide
        (effects (font (size 0.7 0.7) (thickness 0.15)) (justify left bottom))
    )
    (fp_text user "License: Apache-2.0" (at -4.79 8.855) (layer "F.Fab") hide
        (effects (font (size 0.7 0.7) (thickness 0.15)) (justify left bottom))
    )
    (fp_line (start -4.79 -1.395) (end -4.79 -0.145)
      (stroke (width 0.15) (type solid)) (layer "F.SilkS"))
    (fp_line (start -4.79 2.575) (end -4.79 3.854)
      (stroke (width 0.15) (type solid)) (layer "F.SilkS"))
    (fp_line (start -4.79 3.854) (end 4.788 3.854)
      (stroke (width 0.15) (type solid)) (layer "F.SilkS"))
    (fp_line (start 4.788 -1.395) (end 4.788 -0.145)
      (stroke (width 0.15) (type solid)) (layer "F.SilkS"))
    (fp_line (start 4.788 3.854) (end 4.788 2.575)
      (stroke (width 0.15) (type solid)) (layer "F.SilkS"))
    (fp_circle (center -3.8 -4.27071) (end -3.75 -4.22071)
      (stroke (width 0.15) (type solid)) (fill solid) (layer "F.SilkS"))
    (fp_rect (start -5.1 -4.4) (end 5.1 3.9)
      (stroke (width 0.05) (type solid)) (fill none) (layer "F.CrtYd"))
    (fp_line (start -4.79 -3.676) (end 4.788 -3.676)
      (stroke (width 0.15) (type solid)) (layer "F.Fab"))
    (fp_line (start -4.79 3.854) (end -4.79 -3.676)
      (stroke (width 0.15) (type solid)) (layer "F.Fab"))
    (fp_line (start -4.702 3.854) (end 4.788 3.854)
      (stroke (width 0.15) (type solid)) (layer "F.Fab"))
    (fp_line (start 4.788 -3.676) (end 4.788 3.854)
      (stroke (width 0.15) (type solid)) (layer "F.Fab"))
    (fp_line (start 4.788 3.854) (end -4.79 3.854)
      (stroke (width 0.15) (type solid)) (layer "F.Fab"))
    (pad "" np_thru_hole circle (at -2.891 -2.426) (size 0.65 0.65) (drill 0.65) (layers "*.Cu" "*.Mask"))
    (pad "" np_thru_hole circle (at 2.89 -2.426) (size 0.65 0.65) (drill 0.65) (layers "*.Cu" "*.Mask"))
    (pad "A1" smd roundrect (at -3.202 -3.5) (size 0.6 1.15) (layers "F.Cu" "F.Paste" "F.Mask") (roundrect_rratio 0.25)
      (net 9 "GND") (pinfunction "GND") (pintype "passive"))
    (pad "A4" smd roundrect (at -2.4 -3.5) (size 0.6 1.15) (layers "F.Cu" "F.Paste" "F.Mask") (roundrect_rratio 0.25)
      (net 853 "VBUS") (pinfunction "VBUS") (pintype "passive"))
    (pad "A5" smd roundrect (at -1.25 -3.5) (size 0.3 1.15) (layers "F.Cu" "F.Paste" "F.Mask") (roundrect_rratio 0.25)
      (net 565 "Net-(J9-CC1)") (pinfunction "CC1") (pintype "bidirectional"))
    (pad "A6" smd roundrect (at -0.25 -3.5) (size 0.3 1.15) (layers "F.Cu" "F.Paste" "F.Mask") (roundrect_rratio 0.25)
      (net 10 "DBG_USB_P") (pinfunction "D+") (pintype "bidirectional"))
    (pad "A7" smd roundrect (at 0.248 -3.5) (size 0.3 1.15) (layers "F.Cu" "F.Paste" "F.Mask") (roundrect_rratio 0.25)
      (net 11 "DBG_USB_N") (pinfunction "D-") (pintype "bidirectional"))
    (pad "A8" smd roundrect (at 1.249 -3.5) (size 0.3 1.15) (layers "F.Cu" "F.Paste" "F.Mask") (roundrect_rratio 0.25)
      (net 566 "unconnected-(J9-SBU1-PadA8)") (pinfunction "SBU1") (pintype "bidirectional+no_connect"))
    (pad "A9" smd roundrect (at 2.398 -3.5) (size 0.6 1.15) (layers "F.Cu" "F.Paste" "F.Mask") (roundrect_rratio 0.25)
      (net 853 "VBUS") (pinfunction "VBUS") (pintype "passive"))
    (pad "A12" smd roundrect (at 3.2 -3.5) (size 0.6 1.15) (layers "F.Cu" "F.Paste" "F.Mask") (roundrect_rratio 0.25)
      (net 9 "GND") (pinfunction "GND") (pintype "passive"))
    (pad "B1" smd roundrect (at 3.2 -3.5) (size 0.6 1.15) (layers "F.Cu" "F.Paste" "F.Mask") (roundrect_rratio 0.25)
      (net 9 "GND") (pinfunction "GND") (pintype "passive"))
    (pad "B4" smd roundrect (at 2.398 -3.5) (size 0.6 1.15) (layers "F.Cu" "F.Paste" "F.Mask") (roundrect_rratio 0.25)
      (net 853 "VBUS") (pinfunction "VBUS") (pintype "passive"))
    (pad "B5" smd roundrect (at 1.749 -3.5) (size 0.3 1.15) (layers "F.Cu" "F.Paste" "F.Mask") (roundrect_rratio 0.25)
      (net 569 "Net-(J9-CC2)") (pinfunction "CC2") (pintype "bidirectional"))
    (pad "B6" smd roundrect (at 0.748 -3.5) (size 0.3 1.15) (layers "F.Cu" "F.Paste" "F.Mask") (roundrect_rratio 0.25)
      (net 10 "DBG_USB_P") (pinfunction "D+") (pintype "passive"))
    (pad "B7" smd roundrect (at -0.75 -3.5) (size 0.3 1.15) (layers "F.Cu" "F.Paste" "F.Mask") (roundrect_rratio 0.25)
      (net 11 "DBG_USB_N") (pinfunction "D-") (pintype "passive"))
    (pad "B8" smd roundrect (at -1.75 -3.5) (size 0.3 1.15) (layers "F.Cu" "F.Paste" "F.Mask") (roundrect_rratio 0.25)
      (net 570 "unconnected-(J9-SBU2-PadB8)") (pinfunction "SBU2") (pintype "bidirectional+no_connect"))
    (pad "B9" smd roundrect (at -2.4 -3.5) (size 0.6 1.15) (layers "F.Cu" "F.Paste" "F.Mask") (roundrect_rratio 0.25)
      (net 853 "VBUS") (pinfunction "VBUS") (pintype "passive"))
    (pad "B12" smd roundrect (at -3.202 -3.5) (size 0.6 1.15) (layers "F.Cu" "F.Paste" "F.Mask") (roundrect_rratio 0.25)
      (net 9 "GND") (pinfunction "GND") (pintype "passive"))
    (pad "SH" thru_hole oval (at -4.321 -2.926) (size 1.05 2.1) (drill oval 0.6 1.7) (layers "*.Cu" "*.Mask")
      (net 862 "GNDS") (pinfunction "SHIELD") (pintype "passive"))
    (pad "SH" thru_hole oval (at -4.321 1.255) (size 1 2) (drill oval 0.6 1.4) (layers "*.Cu" "*.Mask")
      (net 862 "GNDS") (pinfunction "SHIELD") (pintype "passive"))
    (pad "SH" thru_hole oval (at 4.32 -2.926) (size 1.05 2.1) (drill oval 0.6 1.7) (layers "*.Cu" "*.Mask")
      (net 862 "GNDS") (pinfunction "SHIELD") (pintype "passive"))
    (pad "SH" thru_hole oval (at 4.32 1.255) (size 1 2) (drill oval 0.6 1.4) (layers "*.Cu" "*.Mask")
      (net 862 "GNDS") (pinfunction "SHIELD") (pintype "passive"))
  )

  (footprint "data-center-rdimm-ddr4-tester-footprints:TP_SMD_0.75mm" (layer "F.Cu")
    (at 250.675 123.4742)
    (property "Author" "Antmicro")
    (property "License" "Apache-2.0")
    (property "MPN" "")
    (property "Manufacturer" "")
    (property "Sheetfile" "fmc_hpc.kicad_sch")
    (property "Sheetname" "FMC HPC")
    (property "ki_description" "Test Point 0.75mm")
    (attr exclude_from_pos_files)
    (fp_text reference "TP19" (at 0.515 0.3558) (layer "F.SilkS")
        (effects (font (size 0.7 0.7) (thickness 0.15)) (justify left bottom))
    )
    (fp_text value "TP_0.75mm_SMD" (at 0 1.2) (layer "F.Fab") hide
        (effects (font (size 0.7 0.7) (thickness 0.15)) (justify left bottom))
    )
    (fp_text user "License: Apache-2.0" (at -0.4 5.101) (layer "F.Fab") hide
        (effects (font (size 0.7 0.7) (thickness 0.15)) (justify left bottom))
    )
    (fp_text user "${REFERENCE}" (at -0.4 2.7) (layer "F.Fab") hide
        (effects (font (size 0.7 0.7) (thickness 0.15)) (justify left bottom))
    )
    (fp_text user "Author: Antmicro" (at -0.4 3.901) (layer "F.Fab") hide
        (effects (font (size 0.7 0.7) (thickness 0.15)) (justify left bottom))
    )
    (pad "1" smd circle (at 0 0) (size 0.75 0.75) (layers "F.Cu" "F.Mask")
      (net 405 "Net-(J5C-PG_{M2C})") (pinfunction "1") (pintype "passive"))
  )

  (footprint "data-center-rdimm-ddr4-tester-footprints:mounting-hole-3mm-NPTH" (layer "F.Cu")
    (at 256.75 49)
    (property "Author" "Antmicro")
    (property "License" "Apache-2.0")
    (property "MPN" "")
    (property "Manufacturer" "")
    (property "Sheetfile" "data-center-rdimm-ddr4-tester.kicad_sch")
    (property "Sheetname" "")
    (attr through_hole)
    (fp_text reference "MP3" (at 0 -1.8) (layer "F.SilkS") hide
        (effects (font (size 0.7 0.7) (thickness 0.15)) (justify left bottom))
    )
    (fp_text value "PCB_Mount_Hole_3mm_NPTH" (at 0 2.3) (layer "F.Fab") hide
        (effects (font (size 0.7 0.7) (thickness 0.15)) (justify left bottom))
    )
    (fp_text user "${REFERENCE}" (at 0 4.749) (layer "F.Fab") hide
        (effects (font (size 0.7 0.7) (thickness 0.15)) (justify left bottom))
    )
    (fp_text user "License: Apache-2.0" (at 0 7.15) (layer "F.Fab") hide
        (effects (font (size 0.7 0.7) (thickness 0.15)) (justify left bottom))
    )
    (fp_text user "Author: Antmicro" (at 0 5.95) (layer "F.Fab") hide
        (effects (font (size 0.7 0.7) (thickness 0.15)) (justify left bottom))
    )
    (pad "" np_thru_hole circle (at 0 0) (size 3 3) (drill 3) (layers "*.Cu" "*.Mask"))
  )

  (footprint "data-center-rdimm-ddr4-tester-footprints:R_0201" (layer "F.Cu")
    (at 155.29 104.29 90)
    (descr "Resistor SMD 0201")
    (tags "resistor SMD 0201")
    (property "Author" "Antmicro")
    (property "License" "Apache-2.0")
    (property "MPN" "CR0201-FX-0R00GLF")
    (property "Manufacturer" "Bourns")
    (property "Sheetfile" "ethernet.kicad_sch")
    (property "Sheetname" "Ethernet")
    (property "Tolerance" "1%")
    (property "Val" "0R")
    (property "ki_description" "0R resistor in 0201 package with 1% tolerance")
    (attr smd)
    (fp_text reference "R98" (at 0.6 0.37 90) (layer "F.SilkS")
        (effects (font (size 0.7 0.7) (thickness 0.15)) (justify left bottom))
    )
    (fp_text value "R_0R_0201" (at 0 1.25 90) (layer "F.Fab") hide
        (effects (font (size 0.7 0.7) (thickness 0.15)) (justify left bottom))
    )
    (fp_text user "License: Apache-2.0" (at -0.71 4.25 90) (layer "F.Fab") hide
        (effects (font (size 0.7 0.7) (thickness 0.15)) (justify left bottom))
    )
    (fp_text user "Author: Antmicro" (at -0.71 5.25 90) (layer "F.Fab") hide
        (effects (font (size 0.7 0.7) (thickness 0.15)) (justify left bottom))
    )
    (fp_text user "${REFERENCE}" (at -0.71 3.25 90) (layer "F.Fab") hide
        (effects (font (size 0.7 0.7) (thickness 0.15)) (justify left bottom))
    )
    (fp_rect (start -0.71 -0.36) (end 0.71 0.36)
      (stroke (width 0.05) (type solid)) (fill none) (layer "F.CrtYd"))
    (fp_rect (start -0.3 -0.15) (end 0.298 0.148)
      (stroke (width 0.15) (type solid)) (fill none) (layer "F.Fab"))
    (pad "" smd roundrect (at -0.346 0 90) (size 0.318 0.36) (layers "F.Paste") (roundrect_rratio 0.25))
    (pad "" smd roundrect (at 0.344 0 90) (size 0.318 0.36) (layers "F.Paste") (roundrect_rratio 0.25))
    (pad "1" smd roundrect (at -0.32 0 90) (size 0.46 0.4) (layers "F.Cu" "F.Mask") (roundrect_rratio 0.25)
      (net 825 "/Ethernet/ETH1_BP_N") (pintype "passive"))
    (pad "2" smd roundrect (at 0.32 0 90) (size 0.46 0.4) (layers "F.Cu" "F.Mask") (roundrect_rratio 0.25)
      (net 173 "/Ethernet/ETH1_N") (pintype "passive"))
  )

  (footprint "data-center-rdimm-ddr4-tester-footprints:C_0402_1005Metric" (layer "F.Cu")
    (at 202 123.3 180)
    (descr "Capacitor SMD 0402")
    (tags "capacitor SMD 0402")
    (property "Author" "Antmicro")
    (property "Dielectric" "X5R")
    (property "License" "Apache-2.0")
    (property "MPN" "GRM155R61H104KE14D")
    (property "Manufacturer" "Murata")
    (property "Sheetfile" "interfaces.kicad_sch")
    (property "Sheetname" "Interfaces")
    (property "Val" "100n")
    (property "Voltage" "50V")
    (property "ki_description" " ")
    (attr smd)
    (fp_text reference "C311" (at -0.76 -0.39 180) (layer "F.SilkS")
        (effects (font (size 0.7 0.7) (thickness 0.15)) (justify left bottom))
    )
    (fp_text value "C_100n_0402" (at 0 1.4 180) (layer "F.Fab") hide
        (effects (font (size 0.7 0.7) (thickness 0.15)) (justify left bottom))
    )
    (fp_text user "License: Apache-2.0" (at -0.932 5.17 180) (layer "F.Fab") hide
        (effects (font (size 0.7 0.7) (thickness 0.15)) (justify left bottom))
    )
    (fp_text user "Author: Antmicro" (at -0.932 4.17 180) (layer "F.Fab") hide
        (effects (font (size 0.7 0.7) (thickness 0.15)) (justify left bottom))
    )
    (fp_text user "${REFERENCE}" (at -0.932 3.168 180) (layer "F.Fab") hide
        (effects (font (size 0.7 0.7) (thickness 0.15)) (justify left bottom))
    )
    (fp_rect (start -0.94 -0.47) (end 0.94 0.47)
      (stroke (width 0.05) (type solid)) (fill none) (layer "F.CrtYd"))
    (fp_rect (start -0.499 -0.249) (end 0.499 0.249)
      (stroke (width 0.15) (type solid)) (fill none) (layer "F.Fab"))
    (pad "1" smd roundrect (at -0.484 0 180) (size 0.59 0.64) (layers "F.Cu" "F.Paste" "F.Mask") (roundrect_rratio 0.25)
      (net 863 "GND1") (pintype "passive"))
    (pad "2" smd roundrect (at 0.484 0 180) (size 0.59 0.64) (layers "F.Cu" "F.Paste" "F.Mask") (roundrect_rratio 0.25)
      (net 9 "GND") (pintype "passive"))
  )

  (footprint "data-center-rdimm-ddr4-tester-footprints:C_0402_1005Metric" (layer "F.Cu")
    (at 153.67 105.01 -90)
    (descr "Capacitor SMD 0402")
    (tags "capacitor SMD 0402")
    (property "Author" "Antmicro")
    (property "DNP" "DNP")
    (property "Dielectric" "X5R")
    (property "License" "Apache-2.0")
    (property "MPN" "GRM155R61H104KE14D")
    (property "Manufacturer" "Murata")
    (property "Sheetfile" "ethernet.kicad_sch")
    (property "Sheetname" "Ethernet")
    (property "Val" "100n")
    (property "Voltage" "50V")
    (property "dnp" "")
    (property "exclude_from_bom" "")
    (property "ki_description" " ")
    (attr exclude_from_pos_files exclude_from_bom)
    (fp_text reference "C288" (at 1.23 0.53 -90) (layer "F.SilkS")
        (effects (font (size 0.7 0.7) (thickness 0.15)) (justify left bottom))
    )
    (fp_text value "C_100n_0402" (at 0 1.4 -90) (layer "F.Fab") hide
        (effects (font (size 0.7 0.7) (thickness 0.15)) (justify left bottom))
    )
    (fp_text user "License: Apache-2.0" (at -0.932 5.17 -90) (layer "F.Fab") hide
        (effects (font (size 0.7 0.7) (thickness 0.15)) (justify left bottom))
    )
    (fp_text user "${REFERENCE}" (at -0.932 3.168 -90) (layer "F.Fab") hide
        (effects (font (size 0.7 0.7) (thickness 0.15)) (justify left bottom))
    )
    (fp_text user "Author: Antmicro" (at -0.932 4.17 -90) (layer "F.Fab") hide
        (effects (font (size 0.7 0.7) (thickness 0.15)) (justify left bottom))
    )
    (fp_rect (start -0.94 -0.47) (end 0.94 0.47)
      (stroke (width 0.05) (type solid)) (fill none) (layer "F.CrtYd"))
    (fp_rect (start -0.499 -0.249) (end 0.499 0.249)
      (stroke (width 0.15) (type solid)) (fill none) (layer "F.Fab"))
    (pad "1" smd roundrect (at -0.484 0 270) (size 0.59 0.64) (layers "F.Cu" "F.Paste" "F.Mask") (roundrect_rratio 0.25)
      (net 143 "3V3_SYS") (pintype "passive"))
    (pad "2" smd roundrect (at 0.484 0 270) (size 0.59 0.64) (layers "F.Cu" "F.Paste" "F.Mask") (roundrect_rratio 0.25)
      (net 9 "GND") (pintype "passive"))
  )

  (footprint "data-center-rdimm-ddr4-tester-footprints:PROBE_PAD_1206" (layer "F.Cu")
    (at 134.7 133.45 180)
    (property "Author" "Antmicro")
    (property "License" "Apache-2.0")
    (property "MPN" "RCW-0C")
    (property "Manufacturer" "TE Connectivity")
    (property "Sheetfile" "supply.kicad_sch")
    (property "Sheetname" "Supply")
    (property "ki_description" "SMD Circuit Probe Pad 1206")
    (attr smd)
    (fp_text reference "GND1" (at 1.52 1.19 180) (layer "F.SilkS")
        (effects (font (size 0.7 0.7) (thickness 0.15)) (justify left bottom))
    )
    (fp_text value "TestPoint_Probe_1206_RCW-0C" (at 0 2.112 180) (layer "F.Fab") hide
        (effects (font (size 0.7 0.7) (thickness 0.15)) (justify left bottom))
    )
    (fp_text user "License: Apache-2.0" (at -1.95 6.512 180) (layer "F.Fab") hide
        (effects (font (size 0.7 0.7) (thickness 0.15)) (justify left bottom))
    )
    (fp_text user "Author: Antmicro" (at -1.95 5.312 180) (layer "F.Fab") hide
        (effects (font (size 0.7 0.7) (thickness 0.15)) (justify left bottom))
    )
    (fp_text user "${REFERENCE}" (at -1.95 4.112 180) (layer "F.Fab") hide
        (effects (font (size 0.7 0.7) (thickness 0.15)) (justify left bottom))
    )
    (fp_line (start -1.78 -0.92) (end -1.78 -0.419)
      (stroke (width 0.15) (type solid)) (layer "F.SilkS"))
    (fp_line (start -1.78 -0.92) (end -1.28 -0.92)
      (stroke (width 0.15) (type solid)) (layer "F.SilkS"))
    (fp_line (start -1.78 0.541) (end -1.78 1.04)
      (stroke (width 0.15) (type solid)) (layer "F.SilkS"))
    (fp_line (start -1.78 1.04) (end -1.28 1.04)
      (stroke (width 0.15) (type solid)) (layer "F.SilkS"))
    (fp_line (start 1.779 1.042) (end 1.28 1.042)
      (stroke (width 0.15) (type solid)) (layer "F.SilkS"))
    (fp_line (start 1.779 1.042) (end 1.779 0.542)
      (stroke (width 0.15) (type solid)) (layer "F.SilkS"))
    (fp_line (start 1.78 -0.92) (end 1.28 -0.92)
      (stroke (width 0.15) (type solid)) (layer "F.SilkS"))
    (fp_line (start 1.78 -0.92) (end 1.78 -0.419)
      (stroke (width 0.15) (type solid)) (layer "F.SilkS"))
    (fp_line (start -1.95 -1.08) (end -1.95 1.18)
      (stroke (width 0.05) (type solid)) (layer "F.CrtYd"))
    (fp_line (start 1.93 -1.08) (end -1.95 -1.08)
      (stroke (width 0.05) (type solid)) (layer "F.CrtYd"))
    (fp_line (start 1.93 -1.08) (end 1.93 1.18)
      (stroke (width 0.05) (type solid)) (layer "F.CrtYd"))
    (fp_line (start 1.93 1.18) (end -1.95 1.18)
      (stroke (width 0.05) (type solid)) (layer "F.CrtYd"))
    (fp_line (start -1.601 0.861) (end -1.601 -0.738)
      (stroke (width 0.15) (type solid)) (layer "F.Fab"))
    (fp_line (start 1.6 -0.738) (end -1.601 -0.738)
      (stroke (width 0.15) (type solid)) (layer "F.Fab"))
    (fp_line (start 1.6 0.861) (end -1.601 0.861)
      (stroke (width 0.15) (type solid)) (layer "F.Fab"))
    (fp_line (start 1.6 0.861) (end 1.6 -0.738)
      (stroke (width 0.15) (type solid)) (layer "F.Fab"))
    (pad "1" smd rect (at 0 0.061 180) (size 3.4 1.8) (layers "F.Cu" "F.Paste" "F.Mask")
      (net 9 "GND") (pinfunction "1") (pintype "passive"))
  )

  (footprint "data-center-rdimm-ddr4-tester-footprints:Testpoint_smd_1mm" (layer "F.Cu")
    (at 230.9 125.3 180)
    (property "Author" "Antmicro")
    (property "License" "Apache-2.0")
    (property "MPN" "")
    (property "Manufacturer" "")
    (property "Sheetfile" "supply.kicad_sch")
    (property "Sheetname" "Supply")
    (property "ki_description" "Test Point 1mm")
    (attr exclude_from_pos_files)
    (fp_text reference "TP14" (at 0.8 -1.43 180) (layer "F.SilkS")
        (effects (font (size 0.7 0.7) (thickness 0.15)) (justify left bottom))
    )
    (fp_text value "TP_1mm_SMD" (at 0 1.4 180) (layer "F.Fab") hide
        (effects (font (size 0.7 0.7) (thickness 0.15)) (justify left bottom))
    )
    (fp_text user "${REFERENCE}" (at -0.5 2.8 180) (layer "F.Fab") hide
        (effects (font (size 0.7 0.7) (thickness 0.15)) (justify left bottom))
    )
    (fp_text user "License: Apache-2.0" (at -0.5 5.2 180) (layer "F.Fab") hide
        (effects (font (size 0.7 0.7) (thickness 0.15)) (justify left bottom))
    )
    (fp_text user "Author: Antmicro" (at -0.5 4 180) (layer "F.Fab") hide
        (effects (font (size 0.7 0.7) (thickness 0.15)) (justify left bottom))
    )
    (pad "1" smd circle (at 0 0 180) (size 1 1) (layers "F.Cu" "F.Mask")
      (net 119 "/Supply/~{INT}") (pinfunction "1") (pintype "passive"))
  )

  (footprint "data-center-rdimm-ddr4-tester-footprints:C_0402_1005Metric" (layer "F.Cu")
    (at 254.71 76.635 180)
    (descr "Capacitor SMD 0402")
    (tags "capacitor SMD 0402")
    (property "Author" "Antmicro")
    (property "Dielectric" "X5R")
    (property "License" "Apache-2.0")
    (property "MPN" "GRM155R61H104KE14D")
    (property "Manufacturer" "Murata")
    (property "Sheetfile" "fmc_hpc.kicad_sch")
    (property "Sheetname" "FMC HPC")
    (property "Val" "100n")
    (property "Voltage" "50V")
    (property "ki_description" " ")
    (attr smd)
    (fp_text reference "C270" (at -0.78 -0.375 180) (layer "F.SilkS")
        (effects (font (size 0.7 0.7) (thickness 0.15)) (justify left bottom))
    )
    (fp_text value "C_100n_0402" (at 0 1.4 180) (layer "F.Fab") hide
        (effects (font (size 0.7 0.7) (thickness 0.15)) (justify left bottom))
    )
    (fp_text user "Author: Antmicro" (at -0.932 4.17 180) (layer "F.Fab") hide
        (effects (font (size 0.7 0.7) (thickness 0.15)) (justify left bottom))
    )
    (fp_text user "${REFERENCE}" (at -0.932 3.168 180) (layer "F.Fab") hide
        (effects (font (size 0.7 0.7) (thickness 0.15)) (justify left bottom))
    )
    (fp_text user "License: Apache-2.0" (at -0.932 5.17 180) (layer "F.Fab") hide
        (effects (font (size 0.7 0.7) (thickness 0.15)) (justify left bottom))
    )
    (fp_rect (start -0.94 -0.47) (end 0.94 0.47)
      (stroke (width 0.05) (type solid)) (fill none) (layer "F.CrtYd"))
    (fp_rect (start -0.499 -0.249) (end 0.499 0.249)
      (stroke (width 0.15) (type solid)) (fill none) (layer "F.Fab"))
    (pad "1" smd roundrect (at -0.484 0 180) (size 0.59 0.64) (layers "F.Cu" "F.Paste" "F.Mask") (roundrect_rratio 0.25)
      (net 482 "/FMC HPC/GTX_TX5_C_N") (pintype "passive"))
    (pad "2" smd roundrect (at 0.484 0 180) (size 0.59 0.64) (layers "F.Cu" "F.Paste" "F.Mask") (roundrect_rratio 0.25)
      (net 483 "GTX_TX5_N") (pintype "passive"))
  )

  (footprint "data-center-rdimm-ddr4-tester-footprints:C_0402_1005Metric" (layer "F.Cu")
    (at 254.71 91.875 180)
    (descr "Capacitor SMD 0402")
    (tags "capacitor SMD 0402")
    (property "Author" "Antmicro")
    (property "Dielectric" "X5R")
    (property "License" "Apache-2.0")
    (property "MPN" "GRM155R61H104KE14D")
    (property "Manufacturer" "Murata")
    (property "Sheetfile" "fmc_hpc.kicad_sch")
    (property "Sheetname" "FMC HPC")
    (property "Val" "100n")
    (property "Voltage" "50V")
    (property "ki_description" " ")
    (attr smd)
    (fp_text reference "C264" (at -0.8 -0.385 180) (layer "F.SilkS")
        (effects (font (size 0.7 0.7) (thickness 0.15)) (justify left bottom))
    )
    (fp_text value "C_100n_0402" (at 0 1.4 180) (layer "F.Fab") hide
        (effects (font (size 0.7 0.7) (thickness 0.15)) (justify left bottom))
    )
    (fp_text user "${REFERENCE}" (at -0.932 3.168 180) (layer "F.Fab") hide
        (effects (font (size 0.7 0.7) (thickness 0.15)) (justify left bottom))
    )
    (fp_text user "License: Apache-2.0" (at -0.932 5.17 180) (layer "F.Fab") hide
        (effects (font (size 0.7 0.7) (thickness 0.15)) (justify left bottom))
    )
    (fp_text user "Author: Antmicro" (at -0.932 4.17 180) (layer "F.Fab") hide
        (effects (font (size 0.7 0.7) (thickness 0.15)) (justify left bottom))
    )
    (fp_rect (start -0.94 -0.47) (end 0.94 0.47)
      (stroke (width 0.05) (type solid)) (fill none) (layer "F.CrtYd"))
    (fp_rect (start -0.499 -0.249) (end 0.499 0.249)
      (stroke (width 0.15) (type solid)) (fill none) (layer "F.Fab"))
    (pad "1" smd roundrect (at -0.484 0 180) (size 0.59 0.64) (layers "F.Cu" "F.Paste" "F.Mask") (roundrect_rratio 0.25)
      (net 438 "/FMC HPC/GTX_TX2_C_N") (pintype "passive"))
    (pad "2" smd roundrect (at 0.484 0 180) (size 0.59 0.64) (layers "F.Cu" "F.Paste" "F.Mask") (roundrect_rratio 0.25)
      (net 439 "GTX_TX2_N") (pintype "passive"))
  )

  (footprint "data-center-rdimm-ddr4-tester-footprints:R_0201" (layer "F.Cu")
    (at 158.55 109.035 90)
    (descr "Resistor SMD 0201")
    (tags "resistor SMD 0201")
    (property "Author" "Antmicro")
    (property "License" "Apache-2.0")
    (property "MPN" "CR0201-FX-0R00GLF")
    (property "Manufacturer" "Bourns")
    (property "Sheetfile" "ethernet.kicad_sch")
    (property "Sheetname" "Ethernet")
    (property "Tolerance" "1%")
    (property "Val" "0R")
    (property "ki_description" "0R resistor in 0201 package with 1% tolerance")
    (attr smd)
    (fp_text reference "R108" (at -3.465 0.35 90) (layer "F.SilkS")
        (effects (font (size 0.7 0.7) (thickness 0.15)) (justify left bottom))
    )
    (fp_text value "R_0R_0201" (at 0 1.25 90) (layer "F.Fab") hide
        (effects (font (size 0.7 0.7) (thickness 0.15)) (justify left bottom))
    )
    (fp_text user "License: Apache-2.0" (at -0.71 4.25 90) (layer "F.Fab") hide
        (effects (font (size 0.7 0.7) (thickness 0.15)) (justify left bottom))
    )
    (fp_text user "${REFERENCE}" (at -0.71 3.25 90) (layer "F.Fab") hide
        (effects (font (size 0.7 0.7) (thickness 0.15)) (justify left bottom))
    )
    (fp_text user "Author: Antmicro" (at -0.71 5.25 90) (layer "F.Fab") hide
        (effects (font (size 0.7 0.7) (thickness 0.15)) (justify left bottom))
    )
    (fp_rect (start -0.71 -0.36) (end 0.71 0.36)
      (stroke (width 0.05) (type solid)) (fill none) (layer "F.CrtYd"))
    (fp_rect (start -0.3 -0.15) (end 0.298 0.148)
      (stroke (width 0.15) (type solid)) (fill none) (layer "F.Fab"))
    (pad "" smd roundrect (at -0.346 0 90) (size 0.318 0.36) (layers "F.Paste") (roundrect_rratio 0.25))
    (pad "" smd roundrect (at 0.344 0 90) (size 0.318 0.36) (layers "F.Paste") (roundrect_rratio 0.25))
    (pad "1" smd roundrect (at -0.32 0 90) (size 0.46 0.4) (layers "F.Cu" "F.Mask") (roundrect_rratio 0.25)
      (net 567 "/Ethernet/INT_ETH2_N") (pintype "passive"))
    (pad "2" smd roundrect (at 0.32 0 90) (size 0.46 0.4) (layers "F.Cu" "F.Mask") (roundrect_rratio 0.25)
      (net 827 "/Ethernet/ETH2_BP_N") (pintype "passive"))
  )

  (footprint "data-center-rdimm-ddr4-tester-footprints:C_0402_1005Metric" (layer "F.Cu")
    (at 256.18 80.181)
    (descr "Capacitor SMD 0402")
    (tags "capacitor SMD 0402")
    (property "Author" "Antmicro")
    (property "Dielectric" "X5R")
    (property "License" "Apache-2.0")
    (property "MPN" "GRM155R61H104KE14D")
    (property "Manufacturer" "Murata")
    (property "Sheetfile" "fmc_hpc.kicad_sch")
    (property "Sheetname" "FMC HPC")
    (property "Val" "100n")
    (property "Voltage" "50V")
    (property "ki_description" " ")
    (attr smd)
    (fp_text reference "C271" (at 0.74 0.339) (layer "F.SilkS")
        (effects (font (size 0.7 0.7) (thickness 0.15)) (justify left bottom))
    )
    (fp_text value "C_100n_0402" (at 0 1.4) (layer "F.Fab") hide
        (effects (font (size 0.7 0.7) (thickness 0.15)) (justify left bottom))
    )
    (fp_text user "Author: Antmicro" (at -0.932 4.17) (layer "F.Fab") hide
        (effects (font (size 0.7 0.7) (thickness 0.15)) (justify left bottom))
    )
    (fp_text user "${REFERENCE}" (at -0.932 3.168) (layer "F.Fab") hide
        (effects (font (size 0.7 0.7) (thickness 0.15)) (justify left bottom))
    )
    (fp_text user "License: Apache-2.0" (at -0.932 5.17) (layer "F.Fab") hide
        (effects (font (size 0.7 0.7) (thickness 0.15)) (justify left bottom))
    )
    (fp_rect (start -0.94 -0.47) (end 0.94 0.47)
      (stroke (width 0.05) (type solid)) (fill none) (layer "F.CrtYd"))
    (fp_rect (start -0.499 -0.249) (end 0.499 0.249)
      (stroke (width 0.15) (type solid)) (fill none) (layer "F.Fab"))
    (pad "1" smd roundrect (at -0.484 0) (size 0.59 0.64) (layers "F.Cu" "F.Paste" "F.Mask") (roundrect_rratio 0.25)
      (net 497 "/FMC HPC/GTX_TX6_C_P") (pintype "passive"))
    (pad "2" smd roundrect (at 0.484 0) (size 0.59 0.64) (layers "F.Cu" "F.Paste" "F.Mask") (roundrect_rratio 0.25)
      (net 498 "GTX_TX6_P") (pintype "passive"))
  )

  (footprint "data-center-rdimm-ddr4-tester-footprints:C_0402_1005Metric" (layer "F.Cu")
    (at 256.62 99.5)
    (descr "Capacitor SMD 0402")
    (tags "capacitor SMD 0402")
    (property "Author" "Antmicro")
    (property "Dielectric" "X5R")
    (property "License" "Apache-2.0")
    (property "MPN" "GRM155R61H104KE14D")
    (property "Manufacturer" "Murata")
    (property "Sheetfile" "pcie.kicad_sch")
    (property "Sheetname" "FPGA banks 115-116")
    (property "Val" "100n")
    (property "Voltage" "50V")
    (property "ki_description" " ")
    (attr smd)
    (fp_text reference "C198" (at -0.65 2.28) (layer "F.SilkS")
        (effects (font (size 0.7 0.7) (thickness 0.15)) (justify left bottom))
    )
    (fp_text value "C_100n_0402" (at 0 1.4) (layer "F.Fab") hide
        (effects (font (size 0.7 0.7) (thickness 0.15)) (justify left bottom))
    )
    (fp_text user "License: Apache-2.0" (at -0.932 5.17) (layer "F.Fab") hide
        (effects (font (size 0.7 0.7) (thickness 0.15)) (justify left bottom))
    )
    (fp_text user "Author: Antmicro" (at -0.932 4.17) (layer "F.Fab") hide
        (effects (font (size 0.7 0.7) (thickness 0.15)) (justify left bottom))
    )
    (fp_text user "${REFERENCE}" (at -0.932 3.168) (layer "F.Fab") hide
        (effects (font (size 0.7 0.7) (thickness 0.15)) (justify left bottom))
    )
    (fp_rect (start -0.94 -0.47) (end 0.94 0.47)
      (stroke (width 0.05) (type solid)) (fill none) (layer "F.CrtYd"))
    (fp_rect (start -0.499 -0.249) (end 0.499 0.249)
      (stroke (width 0.15) (type solid)) (fill none) (layer "F.Fab"))
    (pad "1" smd roundrect (at -0.484 0) (size 0.59 0.64) (layers "F.Cu" "F.Paste" "F.Mask") (roundrect_rratio 0.25)
      (net 892 "GTR_REFCLK1_C_N") (pintype "passive"))
    (pad "2" smd roundrect (at 0.484 0) (size 0.59 0.64) (layers "F.Cu" "F.Paste" "F.Mask") (roundrect_rratio 0.25)
      (net 884 "/FPGA banks 115-116/GTR_REFCLK1_N") (pintype "passive"))
  )

  (footprint "data-center-rdimm-ddr4-tester-footprints:NetTie-2_SMD_Pad0.127mm" (layer "F.Cu")
    (at 131.6 100.367 -90)
    (descr "Net tie, 2 pin, 0.127mm  SMD pads")
    (tags "net tie")
    (property "Author" "Antmicro")
    (property "License" "Apache-2.0")
    (property "MPN" "")
    (property "Manufacturer" "")
    (property "Sheetfile" "supply.kicad_sch")
    (property "Sheetname" "Supply")
    (property "ki_description" "Net tie, 2 pins")
    (property "ki_keywords" "net tie short")
    (attr through_hole exclude_from_pos_files)
    (net_tie_pad_groups "1, 2")
    (fp_text reference "NT7" (at -0.128 -1.345 -90) (layer "F.SilkS") hide
        (effects (font (size 0.7 0.7) (thickness 0.15)) (justify left bottom))
    )
    (fp_text value "Net-Tie_2" (at 0 1.199 -90) (layer "F.Fab") hide
        (effects (font (size 0.7 0.7) (thickness 0.15)) (justify left bottom))
    )
    (fp_text user "Author: Antmicro" (at -0.128 4.4 -90) (layer "F.Fab") hide
        (effects (font (size 0.7 0.7) (thickness 0.15)) (justify left bottom))
    )
    (fp_text user "${REFERENCE}" (at -0.128 3.2 -90) (layer "F.Fab") hide
        (effects (font (size 0.7 0.7) (thickness 0.15)) (justify left bottom))
    )
    (fp_text user "License: Apache-2.0" (at -0.128 5.6 -90) (layer "F.Fab") hide
        (effects (font (size 0.7 0.7) (thickness 0.15)) (justify left bottom))
    )
    (fp_poly
      (pts
        (xy -0.0635 -0.0635)
        (xy 0.0625 -0.0635)
        (xy 0.0625 0.0635)
        (xy -0.0635 0.0635)
      )

      (stroke (width 0) (type solid)) (fill solid) (layer "F.Cu"))
    (pad "1" smd roundrect (at -0.127 0 90) (size 0.127 0.127) (layers "F.Cu") (roundrect_rratio 0.5)
      (chamfer_ratio 0) (chamfer top_left bottom_left)
      (net 838 "/Supply/5V0_SEN_+") (pinfunction "1") (pintype "passive"))
    (pad "2" smd roundrect (at 0.126 0 270) (size 0.127 0.127) (layers "F.Cu") (roundrect_rratio 0.5)
      (chamfer_ratio 0) (chamfer top_left bottom_left)
      (net 104 "VCC5V0") (pinfunction "2") (pintype "passive"))
  )

  (footprint "data-center-rdimm-ddr4-tester-footprints:R_0402_1005Metric" (layer "F.Cu")
    (at 254.7 100.5)
    (descr "Resistor SMD 0402")
    (tags "resistor SMD 0402")
    (property "Author" "Antmicro")
    (property "License" "Apache-2.0")
    (property "MPN" "CR0402-FX-33R0GLF")
    (property "Manufacturer" "Bourns")
    (property "Sheetfile" "fmc_hpc.kicad_sch")
    (property "Sheetname" "FMC HPC")
    (property "Tolerance" "1%")
    (property "Val" "33R")
    (property "ki_description" "33R resistor in 0402 package with 1% tolerance")
    (attr smd)
    (fp_text reference "R148" (at -1.74 2.35) (layer "F.SilkS")
        (effects (font (size 0.7 0.7) (thickness 0.15)) (justify left bottom))
    )
    (fp_text value "R_33R_0402" (at 0 1.4) (layer "F.Fab") hide
        (effects (font (size 0.7 0.7) (thickness 0.15)) (justify left bottom))
    )
    (fp_text user "Author: Antmicro" (at -0.95 4.169) (layer "F.Fab") hide
        (effects (font (size 0.7 0.7) (thickness 0.15)) (justify left bottom))
    )
    (fp_text user "${REFERENCE}" (at -0.95 3.168) (layer "F.Fab") hide
        (effects (font (size 0.7 0.7) (thickness 0.15)) (justify left bottom))
    )
    (fp_text user "License: Apache-2.0" (at -0.95 5.169) (layer "F.Fab") hide
        (effects (font (size 0.7 0.7) (thickness 0.15)) (justify left bottom))
    )
    (fp_rect (start -0.93 -0.47) (end 0.93 0.47)
      (stroke (width 0.05) (type solid)) (fill none) (layer "F.CrtYd"))
    (fp_rect (start -0.5 -0.25) (end 0.5 0.25)
      (stroke (width 0.15) (type solid)) (fill none) (layer "F.Fab"))
    (pad "1" smd roundrect (at -0.485 0) (size 0.59 0.64) (layers "F.Cu" "F.Paste" "F.Mask") (roundrect_rratio 0.25)
      (net 897 "/FMC HPC/GTR_REFCLK1_R_P") (pintype "passive"))
    (pad "2" smd roundrect (at 0.485 0) (size 0.59 0.64) (layers "F.Cu" "F.Paste" "F.Mask") (roundrect_rratio 0.25)
      (net 891 "GTR_REFCLK1_C_P") (pintype "passive"))
  )

  (footprint "data-center-rdimm-ddr4-tester-footprints:R_1206_3216Metric" (layer "F.Cu")
    (at 143.9 83.7)
    (property "Author" "Antmicro")
    (property "License" "Apache-2.0")
    (property "MPN" "RL1206FR-7W0R01L")
    (property "Manufacturer" "Yaego")
    (property "Sheetfile" "supply.kicad_sch")
    (property "Sheetname" "Supply")
    (property "Tolerance" "1%")
    (property "Val" "0R01")
    (property "ki_description" "0R01 resistor in 1206 package with unspecified tolerance")
    (attr smd)
    (fp_text reference "R204" (at -0.75 1.9) (layer "F.SilkS")
        (effects (font (size 0.7 0.7) (thickness 0.15)) (justify left bottom))
    )
    (fp_text value "R_0R01_1206" (at 0 2) (layer "F.Fab") hide
        (effects (font (size 0.7 0.7) (thickness 0.15)) (justify left bottom))
    )
    (fp_text user "License: Apache-2.0" (at -2.401 6.3) (layer "F.Fab") hide
        (effects (font (size 0.7 0.7) (thickness 0.15)) (justify left bottom))
    )
    (fp_text user "Author: Antmicro" (at -2.401 4.899) (layer "F.Fab") hide
        (effects (font (size 0.7 0.7) (thickness 0.15)) (justify left bottom))
    )
    (fp_text user "${REFERENCE}" (at -2.401 3.5) (layer "F.Fab") hide
        (effects (font (size 0.7 0.7) (thickness 0.15)) (justify left bottom))
    )
    (fp_line (start 0 -0.902) (end -0.5 -0.902)
      (stroke (width 0.15) (type solid)) (layer "F.SilkS"))
    (fp_line (start 0 -0.902) (end 0.498 -0.902)
      (stroke (width 0.15) (type solid)) (layer "F.SilkS"))
    (fp_line (start 0 0.9) (end -0.5 0.9)
      (stroke (width 0.15) (type solid)) (layer "F.SilkS"))
    (fp_line (start 0 0.9) (end 0.498 0.9)
      (stroke (width 0.15) (type solid)) (layer "F.SilkS"))
    (fp_rect (start -2.25 -1.05) (end 2.25 1.05)
      (stroke (width 0.05) (type solid)) (fill none) (layer "F.CrtYd"))
    (fp_line (start -1.601 -0.802) (end -1.601 0.8)
      (stroke (width 0.15) (type solid)) (layer "F.Fab"))
    (fp_line (start -1.601 -0.802) (end 1.6 -0.802)
      (stroke (width 0.15) (type solid)) (layer "F.Fab"))
    (fp_line (start -1.601 0.8) (end 1.6 0.8)
      (stroke (width 0.15) (type solid)) (layer "F.Fab"))
    (fp_line (start 1.6 -0.802) (end 1.6 0.8)
      (stroke (width 0.15) (type solid)) (layer "F.Fab"))
    (pad "1" smd roundrect (at -1.5 0) (size 1.2 1.8) (layers "F.Cu" "F.Paste" "F.Mask") (roundrect_rratio 0.15)
      (net 300 "VCC1V0") (pintype "passive"))
    (pad "2" smd roundrect (at 1.499 0) (size 1.2 1.8) (layers "F.Cu" "F.Paste" "F.Mask") (roundrect_rratio 0.15)
      (net 147 "1V0_SYS") (pintype "passive"))
  )

  (footprint "data-center-rdimm-ddr4-tester-footprints:R_0201" (layer "F.Cu")
    (at 154.54 104.29 -90)
    (descr "Resistor SMD 0201")
    (tags "resistor SMD 0201")
    (property "Author" "Antmicro")
    (property "License" "Apache-2.0")
    (property "MPN" "CR0201-FX-0R00GLF")
    (property "Manufacturer" "Bourns")
    (property "Sheetfile" "ethernet.kicad_sch")
    (property "Sheetname" "Ethernet")
    (property "Tolerance" "1%")
    (property "Val" "0R")
    (property "ki_description" "0R resistor in 0201 package with 1% tolerance")
    (attr smd)
    (fp_text reference "R97" (at -0.62 -0.24 -90) (layer "F.SilkS")
        (effects (font (size 0.7 0.7) (thickness 0.15)) (justify left bottom))
    )
    (fp_text value "R_0R_0201" (at 0 1.25 -90) (layer "F.Fab") hide
        (effects (font (size 0.7 0.7) (thickness 0.15)) (justify left bottom))
    )
    (fp_text user "Author: Antmicro" (at -0.71 5.25 -90) (layer "F.Fab") hide
        (effects (font (size 0.7 0.7) (thickness 0.15)) (justify left bottom))
    )
    (fp_text user "License: Apache-2.0" (at -0.71 4.25 -90) (layer "F.Fab") hide
        (effects (font (size 0.7 0.7) (thickness 0.15)) (justify left bottom))
    )
    (fp_text user "${REFERENCE}" (at -0.71 3.25 -90) (layer "F.Fab") hide
        (effects (font (size 0.7 0.7) (thickness 0.15)) (justify left bottom))
    )
    (fp_rect (start -0.71 -0.36) (end 0.71 0.36)
      (stroke (width 0.05) (type solid)) (fill none) (layer "F.CrtYd"))
    (fp_rect (start -0.3 -0.15) (end 0.298 0.148)
      (stroke (width 0.15) (type solid)) (fill none) (layer "F.Fab"))
    (pad "" smd roundrect (at -0.346 0 270) (size 0.318 0.36) (layers "F.Paste") (roundrect_rratio 0.25))
    (pad "" smd roundrect (at 0.344 0 270) (size 0.318 0.36) (layers "F.Paste") (roundrect_rratio 0.25))
    (pad "1" smd roundrect (at -0.32 0 270) (size 0.46 0.4) (layers "F.Cu" "F.Mask") (roundrect_rratio 0.25)
      (net 170 "/Ethernet/ETH1_P") (pintype "passive"))
    (pad "2" smd roundrect (at 0.32 0 270) (size 0.46 0.4) (layers "F.Cu" "F.Mask") (roundrect_rratio 0.25)
      (net 824 "/Ethernet/ETH1_BP_P") (pintype "passive"))
  )

  (footprint "data-center-rdimm-ddr4-tester-footprints:PROBE_PAD_1206" (layer "F.Cu")
    (at 257.2 66.8 90)
    (property "Author" "Antmicro")
    (property "License" "Apache-2.0")
    (property "MPN" "RCW-0C")
    (property "Manufacturer" "TE Connectivity")
    (property "Sheetfile" "supply.kicad_sch")
    (property "Sheetname" "Supply")
    (property "ki_description" "SMD Circuit Probe Pad 1206")
    (attr smd)
    (fp_text reference "GND2" (at -1.5 -1.11 90) (layer "F.SilkS")
        (effects (font (size 0.7 0.7) (thickness 0.15)) (justify left bottom))
    )
    (fp_text value "TestPoint_Probe_1206_RCW-0C" (at 0 2.112 90) (layer "F.Fab") hide
        (effects (font (size 0.7 0.7) (thickness 0.15)) (justify left bottom))
    )
    (fp_text user "License: Apache-2.0" (at -1.95 6.512 90) (layer "F.Fab") hide
        (effects (font (size 0.7 0.7) (thickness 0.15)) (justify left bottom))
    )
    (fp_text user "${REFERENCE}" (at -1.95 4.112 90) (layer "F.Fab") hide
        (effects (font (size 0.7 0.7) (thickness 0.15)) (justify left bottom))
    )
    (fp_text user "Author: Antmicro" (at -1.95 5.312 90) (layer "F.Fab") hide
        (effects (font (size 0.7 0.7) (thickness 0.15)) (justify left bottom))
    )
    (fp_line (start -1.78 -0.92) (end -1.78 -0.419)
      (stroke (width 0.15) (type solid)) (layer "F.SilkS"))
    (fp_line (start -1.78 -0.92) (end -1.28 -0.92)
      (stroke (width 0.15) (type solid)) (layer "F.SilkS"))
    (fp_line (start -1.78 0.541) (end -1.78 1.04)
      (stroke (width 0.15) (type solid)) (layer "F.SilkS"))
    (fp_line (start -1.78 1.04) (end -1.28 1.04)
      (stroke (width 0.15) (type solid)) (layer "F.SilkS"))
    (fp_line (start 1.779 1.042) (end 1.28 1.042)
      (stroke (width 0.15) (type solid)) (layer "F.SilkS"))
    (fp_line (start 1.779 1.042) (end 1.779 0.542)
      (stroke (width 0.15) (type solid)) (layer "F.SilkS"))
    (fp_line (start 1.78 -0.92) (end 1.28 -0.92)
      (stroke (width 0.15) (type solid)) (layer "F.SilkS"))
    (fp_line (start 1.78 -0.92) (end 1.78 -0.419)
      (stroke (width 0.15) (type solid)) (layer "F.SilkS"))
    (fp_line (start -1.95 -1.08) (end -1.95 1.18)
      (stroke (width 0.05) (type solid)) (layer "F.CrtYd"))
    (fp_line (start 1.93 -1.08) (end -1.95 -1.08)
      (stroke (width 0.05) (type solid)) (layer "F.CrtYd"))
    (fp_line (start 1.93 -1.08) (end 1.93 1.18)
      (stroke (width 0.05) (type solid)) (layer "F.CrtYd"))
    (fp_line (start 1.93 1.18) (end -1.95 1.18)
      (stroke (width 0.05) (type solid)) (layer "F.CrtYd"))
    (fp_line (start -1.601 0.861) (end -1.601 -0.738)
      (stroke (width 0.15) (type solid)) (layer "F.Fab"))
    (fp_line (start 1.6 -0.738) (end -1.601 -0.738)
      (stroke (width 0.15) (type solid)) (layer "F.Fab"))
    (fp_line (start 1.6 0.861) (end -1.601 0.861)
      (stroke (width 0.15) (type solid)) (layer "F.Fab"))
    (fp_line (start 1.6 0.861) (end 1.6 -0.738)
      (stroke (width 0.15) (type solid)) (layer "F.Fab"))
    (pad "1" smd rect (at 0 0.061 90) (size 3.4 1.8) (layers "F.Cu" "F.Paste" "F.Mask")
      (net 9 "GND") (pinfunction "1") (pintype "passive"))
  )

  (footprint "data-center-rdimm-ddr4-tester-footprints:CONV_PDQE30-Q48-S5-D" (layer "F.Cu")
    (at 177.09 133.16 90)
    (property "Author" "Antmicro")
    (property "License" "Apache-2.0")
    (property "MPN" "PDQE30-Q48-S12-D")
    (property "Manufacturer" "CUI Inc")
    (property "Sheetfile" "ethernet.kicad_sch")
    (property "Sheetname" "Ethernet")
    (property "ki_description" "DC-DC CONVERTER, 48VDC input, 12VDC nom isolated output w/ trim option, 30W, 270kHz PWM mode")
    (property "ki_keywords" "dc converter step down 12v 48v isolated 30W poe")
    (attr through_hole)
    (fp_text reference "PS1" (at 23.21 20.76 180) (layer "F.SilkS")
        (effects (font (size 0.7 0.7) (thickness 0.15)) (justify left bottom))
    )
    (fp_text value "PDQE30-Q48-S12-D" (at 10.32 24.312 90) (layer "F.Fab")
        (effects (font (size 0.7 0.7) (thickness 0.15)) (justify left bottom))
    )
    (fp_text user "License: Apache-2.0" (at -3.912 27.51 90) (layer "F.Fab") hide
        (effects (font (size 0.7 0.7) (thickness 0.15)) (justify left bottom))
    )
    (fp_text user "${REFERENCE}" (at -3.912 28.711 90) (layer "F.Fab") hide
        (effects (font (size 0.7 0.7) (thickness 0.15)) (justify left bottom))
    )
    (fp_text user "Author: Antmicro" (at -3.912 26.312 90) (layer "F.Fab") hide
        (effects (font (size 0.7 0.7) (thickness 0.15)) (justify left bottom))
    )
    (fp_line (start -2.54 -2.54) (end 22.859 -2.54)
      (stroke (width 0.15) (type solid)) (layer "F.SilkS"))
    (fp_line (start -2.54 22.859) (end -2.54 -2.54)
      (stroke (width 0.15) (type solid)) (layer "F.SilkS"))
    (fp_line (start 22.859 -2.54) (end 22.859 22.859)
      (stroke (width 0.15) (type solid)) (layer "F.SilkS"))
    (fp_line (start 22.859 22.859) (end -2.54 22.859)
      (stroke (width 0.15) (type solid)) (layer "F.SilkS"))
    (fp_circle (center -2.921 0) (end -2.82 0)
      (stroke (width 0.15) (type solid)) (fill none) (layer "F.SilkS"))
    (fp_circle (center 0 -3.84) (end 0.05 -3.84)
      (stroke (width 0.15) (type solid)) (fill solid) (layer "F.SilkS"))
    (fp_circle (center 0 -3.84) (end 0.05 -3.84)
      (stroke (width 0.15) (type solid)) (fill solid) (layer "F.SilkS"))
    (fp_rect (start -2.667 -2.667) (end 22.987 22.987)
      (stroke (width 0.05) (type solid)) (fill none) (layer "F.CrtYd"))
    (fp_line (start -2.54 -2.54) (end 22.859 -2.54)
      (stroke (width 0.15) (type solid)) (layer "F.Fab"))
    (fp_line (start -2.54 22.859) (end -2.54 -2.54)
      (stroke (width 0.15) (type solid)) (layer "F.Fab"))
    (fp_line (start 22.859 -2.54) (end 22.859 22.859)
      (stroke (width 0.15) (type solid)) (layer "F.Fab"))
    (fp_line (start 22.859 22.859) (end -2.54 22.859)
      (stroke (width 0.15) (type solid)) (layer "F.Fab"))
    (fp_circle (center -2.921 0) (end -2.82 0)
      (stroke (width 0.15) (type solid)) (fill none) (layer "F.Fab"))
    (pad "1" thru_hole rect (at 0 0 90) (size 2.25 2.25) (drill 1.5) (layers "*.Cu" "*.Mask")
      (net 615 "/Ethernet/POE_ACTIVE") (pinfunction "CTRL") (pintype "input"))
    (pad "2" thru_hole circle (at 0 7.618 90) (size 2.25 2.25) (drill 1.5) (layers "*.Cu" "*.Mask")
      (net 604 "GNDD") (pinfunction "VIN-") (pintype "power_in"))
    (pad "3" thru_hole circle (at 0 12.698 90) (size 2.25 2.25) (drill 1.5) (layers "*.Cu" "*.Mask")
      (net 360 "/Ethernet/VDD") (pinfunction "VIN+") (pintype "power_in"))
    (pad "4" thru_hole circle (at 20.318 20.318 90) (size 2.25 2.25) (drill 1.5) (layers "*.Cu" "*.Mask")
      (net 864 "VIN_POE") (pinfunction "VOUT") (pintype "power_in"))
    (pad "5" thru_hole circle (at 20.318 10.159 90) (size 2.25 2.25) (drill 1.5) (layers "*.Cu" "*.Mask")
      (net 572 "unconnected-(PS1-TRIM-Pad5)") (pinfunction "TRIM") (pintype "passive+no_connect"))
    (pad "6" thru_hole circle (at 20.318 0 90) (size 2.25 2.25) (drill 1.5) (layers "*.Cu" "*.Mask")
      (net 9 "GND") (pinfunction "GND") (pintype "power_in"))
  )

  (footprint "data-center-rdimm-ddr4-tester-footprints:C_0402_1005Metric" (layer "F.Cu")
    (at 243.71 121.95)
    (descr "Capacitor SMD 0402")
    (tags "capacitor SMD 0402")
    (property "Author" "Antmicro")
    (property "Dielectric" "X5R")
    (property "License" "Apache-2.0")
    (property "MPN" "GRM155R61H104KE14D")
    (property "Manufacturer" "Murata")
    (property "Sheetfile" "pcie.kicad_sch")
    (property "Sheetname" "FPGA banks 115-116")
    (property "Val" "100n")
    (property "Voltage" "50V")
    (property "ki_description" " ")
    (attr smd)
    (fp_text reference "C318" (at -2.82 -1.475) (layer "F.SilkS")
        (effects (font (size 0.7 0.7) (thickness 0.15)) (justify left bottom))
    )
    (fp_text value "C_100n_0402" (at 0 1.4) (layer "F.Fab") hide
        (effects (font (size 0.7 0.7) (thickness 0.15)) (justify left bottom))
    )
    (fp_text user "Author: Antmicro" (at -0.932 4.17) (layer "F.Fab") hide
        (effects (font (size 0.7 0.7) (thickness 0.15)) (justify left bottom))
    )
    (fp_text user "License: Apache-2.0" (at -0.932 5.17) (layer "F.Fab") hide
        (effects (font (size 0.7 0.7) (thickness 0.15)) (justify left bottom))
    )
    (fp_text user "${REFERENCE}" (at -0.932 3.168) (layer "F.Fab") hide
        (effects (font (size 0.7 0.7) (thickness 0.15)) (justify left bottom))
    )
    (fp_rect (start -0.94 -0.47) (end 0.94 0.47)
      (stroke (width 0.05) (type solid)) (fill none) (layer "F.CrtYd"))
    (fp_rect (start -0.499 -0.249) (end 0.499 0.249)
      (stroke (width 0.15) (type solid)) (fill none) (layer "F.Fab"))
    (pad "1" smd roundrect (at -0.484 0) (size 0.59 0.64) (layers "F.Cu" "F.Paste" "F.Mask") (roundrect_rratio 0.25)
      (net 888 "/FPGA banks 115-116/GTR_REFCLK3_N") (pintype "passive"))
    (pad "2" smd roundrect (at 0.484 0) (size 0.59 0.64) (layers "F.Cu" "F.Paste" "F.Mask") (roundrect_rratio 0.25)
      (net 896 "GTR_REFCLK3_C_N") (pintype "passive"))
  )

  (footprint "data-center-rdimm-ddr4-tester-footprints:QFN-56-1EP_8x8mm_P0.5mm" (layer "F.Cu")
    (at 140.78 107.12 90)
    (descr "QFN 56 Pin")
    (tags "QFN")
    (property "Author" "Antmicro")
    (property "License" "Apache-2.0")
    (property "MPN" "FT4232H-56Q-REEL")
    (property "Manufacturer" "FTDI Chip")
    (property "Sheetfile" "interfaces.kicad_sch")
    (property "Sheetname" "Interfaces")
    (property "ki_description" "Interface Bridges, USB to UART, MPSSE, 1.62 V, 1.98 V, VQFN, 56 Pins, -40 °C")
    (property "ki_keywords" "SMT, INTERFACE, IC, CONTROLLER, USB, UART, I2C, SPI, JTAG")
    (attr smd)
    (fp_text reference "U7" (at 4.25 -4.89 180) (layer "F.SilkS")
        (effects (font (size 0.7 0.7) (thickness 0.15)) (justify left bottom))
    )
    (fp_text value "FT4232H_VQFN" (at 0 5.32 90) (layer "F.Fab")
        (effects (font (size 0.7 0.7) (thickness 0.15)) (justify left bottom))
    )
    (fp_text user "Author: Antmicro" (at -4.4 8.519 90) (layer "F.Fab") hide
        (effects (font (size 0.7 0.7) (thickness 0.15)) (justify left bottom))
    )
    (fp_text user "${REFERENCE}" (at -4.4 7.32 90) (layer "F.Fab") hide
        (effects (font (size 0.7 0.7) (thickness 0.15)) (justify left bottom))
    )
    (fp_text user "License: Apache-2.0" (at -4.4 9.719 90) (layer "F.Fab") hide
        (effects (font (size 0.7 0.7) (thickness 0.15)) (justify left bottom))
    )
    (fp_line (start -4.111 -3.635) (end -4.111 -4.111)
      (stroke (width 0.15) (type solid)) (layer "F.SilkS"))
    (fp_line (start -4.111 4.11) (end -4.111 3.634)
      (stroke (width 0.15) (type solid)) (layer "F.SilkS"))
    (fp_line (start -3.635 -4.111) (end -4.111 -4.111)
      (stroke (width 0.15) (type solid)) (layer "F.SilkS"))
    (fp_line (start -3.635 4.11) (end -4.111 4.11)
      (stroke (width 0.15) (type solid)) (layer "F.SilkS"))
    (fp_line (start 3.634 -4.111) (end 4.11 -4.111)
      (stroke (width 0.15) (type solid)) (layer "F.SilkS"))
    (fp_line (start 3.634 4.11) (end 4.11 4.11)
      (stroke (width 0.15) (type solid)) (layer "F.SilkS"))
    (fp_line (start 4.11 -4.111) (end 4.11 -3.635)
      (stroke (width 0.15) (type solid)) (layer "F.SilkS"))
    (fp_line (start 4.11 4.11) (end 4.11 3.634)
      (stroke (width 0.15) (type solid)) (layer "F.SilkS"))
    (fp_circle (center -4.35 -3.6) (end -4.3 -3.6)
      (stroke (width 0.15) (type solid)) (fill solid) (layer "F.SilkS"))
    (fp_rect (start 4.4 4.4) (end -4.4 -4.4)
      (stroke (width 0.05) (type solid)) (fill none) (layer "F.CrtYd"))
    (fp_line (start -4 -3) (end -3 -4)
      (stroke (width 0.15) (type solid)) (layer "F.Fab"))
    (fp_rect (start 4 4) (end -4 -4)
      (stroke (width 0.15) (type solid)) (fill none) (layer "F.Fab"))
    (pad "" smd roundrect (at -2.101 -2.101 90) (size 1.13 1.13) (layers "F.Paste") (roundrect_rratio 0.221239))
    (pad "" smd roundrect (at -2.101 -0.7 90) (size 1.13 1.13) (layers "F.Paste") (roundrect_rratio 0.221239))
    (pad "" smd roundrect (at -2.101 0.699 90) (size 1.13 1.13) (layers "F.Paste") (roundrect_rratio 0.221239))
    (pad "" smd roundrect (at -2.101 2.1 90) (size 1.13 1.13) (layers "F.Paste") (roundrect_rratio 0.221239))
    (pad "" smd roundrect (at -0.7 -2.101 90) (size 1.13 1.13) (layers "F.Paste") (roundrect_rratio 0.221239))
    (pad "" smd roundrect (at -0.7 -0.7 90) (size 1.13 1.13) (layers "F.Paste") (roundrect_rratio 0.221239))
    (pad "" smd roundrect (at -0.7 0.699 90) (size 1.13 1.13) (layers "F.Paste") (roundrect_rratio 0.221239))
    (pad "" smd roundrect (at -0.7 2.1 90) (size 1.13 1.13) (layers "F.Paste") (roundrect_rratio 0.221239))
    (pad "" smd roundrect (at 0.699 -2.101 90) (size 1.13 1.13) (layers "F.Paste") (roundrect_rratio 0.221239))
    (pad "" smd roundrect (at 0.699 -0.7 90) (size 1.13 1.13) (layers "F.Paste") (roundrect_rratio 0.221239))
    (pad "" smd roundrect (at 0.699 0.699 90) (size 1.13 1.13) (layers "F.Paste") (roundrect_rratio 0.221239))
    (pad "" smd roundrect (at 0.699 2.1 90) (size 1.13 1.13) (layers "F.Paste") (roundrect_rratio 0.221239))
    (pad "" smd roundrect (at 2.1 -2.101 90) (size 1.13 1.13) (layers "F.Paste") (roundrect_rratio 0.221239))
    (pad "" smd roundrect (at 2.1 -0.7 90) (size 1.13 1.13) (layers "F.Paste") (roundrect_rratio 0.221239))
    (pad "" smd roundrect (at 2.1 0.699 90) (size 1.13 1.13) (layers "F.Paste") (roundrect_rratio 0.221239))
    (pad "" smd roundrect (at 2.1 2.1 90) (size 1.13 1.13) (layers "F.Paste") (roundrect_rratio 0.221239))
    (pad "1" smd roundrect (at -3.938 -3.25 90) (size 0.875 0.3) (layers "F.Cu" "F.Paste" "F.Mask") (roundrect_rratio 0.25)
      (net 673 "unconnected-(U7-EECS-Pad1)") (pinfunction "EECS") (pintype "bidirectional+no_connect"))
    (pad "2" smd roundrect (at -3.938 -2.75 90) (size 0.875 0.3) (layers "F.Cu" "F.Paste" "F.Mask") (roundrect_rratio 0.25)
      (net 145 "1V8_FT") (pinfunction "V_{CORE}") (pintype "power_in"))
    (pad "3" smd roundrect (at -3.938 -2.25 90) (size 0.875 0.3) (layers "F.Cu" "F.Paste" "F.Mask") (roundrect_rratio 0.25)
      (net 80 "Net-(U7-OSCI)") (pinfunction "OSCI") (pintype "input"))
    (pad "4" smd roundrect (at -3.938 -1.75 90) (size 0.875 0.3) (layers "F.Cu" "F.Paste" "F.Mask") (roundrect_rratio 0.25)
      (net 81 "Net-(U7-OSCO)") (pinfunction "OSCO") (pintype "output"))
    (pad "5" smd roundrect (at -3.938 -1.25 90) (size 0.875 0.3) (layers "F.Cu" "F.Paste" "F.Mask") (roundrect_rratio 0.25)
      (net 76 "Net-(U7-V_{PHY})") (pinfunction "V_{PHY}") (pintype "power_in"))
    (pad "6" smd roundrect (at -3.938 -0.75 90) (size 0.875 0.3) (layers "F.Cu" "F.Paste" "F.Mask") (roundrect_rratio 0.25)
      (net 654 "Net-(U7-REF)") (pinfunction "REF") (pintype "input"))
    (pad "7" smd roundrect (at -3.938 -0.25 90) (size 0.875 0.3) (layers "F.Cu" "F.Paste" "F.Mask") (roundrect_rratio 0.25)
      (net 11 "DBG_USB_N") (pinfunction "D-") (pintype "bidirectional"))
    (pad "8" smd roundrect (at -3.938 0.249 90) (size 0.875 0.3) (layers "F.Cu" "F.Paste" "F.Mask") (roundrect_rratio 0.25)
      (net 10 "DBG_USB_P") (pinfunction "D+") (pintype "bidirectional"))
    (pad "9" smd roundrect (at -3.938 0.749 90) (size 0.875 0.3) (layers "F.Cu" "F.Paste" "F.Mask") (roundrect_rratio 0.25)
      (net 75 "Net-(U7-V_{PLL})") (pinfunction "V_{PLL}") (pintype "power_in"))
    (pad "10" smd roundrect (at -3.938 1.249 90) (size 0.875 0.3) (layers "F.Cu" "F.Paste" "F.Mask") (roundrect_rratio 0.25)
      (net 9 "GND") (pinfunction "TEST") (pintype "input"))
    (pad "11" smd roundrect (at -3.938 1.749 90) (size 0.875 0.3) (layers "F.Cu" "F.Paste" "F.Mask") (roundrect_rratio 0.25)
      (net 657 "Net-(U7-~{RESET})") (pinfunction "~{RESET}") (pintype "input"))
    (pad "12" smd roundrect (at -3.938 2.249 90) (size 0.875 0.3) (layers "F.Cu" "F.Paste" "F.Mask") (roundrect_rratio 0.25)
      (net 593 "Net-(U7-ADBUS0)") (pinfunction "ADBUS0") (pintype "bidirectional"))
    (pad "13" smd roundrect (at -3.938 2.749 90) (size 0.875 0.3) (layers "F.Cu" "F.Paste" "F.Mask") (roundrect_rratio 0.25)
      (net 594 "Net-(U7-ADBUS1)") (pinfunction "ADBUS1") (pintype "bidirectional"))
    (pad "14" smd roundrect (at -3.938 3.249 90) (size 0.875 0.3) (layers "F.Cu" "F.Paste" "F.Mask") (roundrect_rratio 0.25)
      (net 595 "Net-(U7-ADBUS2)") (pinfunction "ADBUS2") (pintype "bidirectional"))
    (pad "15" smd roundrect (at -3.25 3.937 180) (size 0.875 0.3) (layers "F.Cu" "F.Paste" "F.Mask") (roundrect_rratio 0.25)
      (net 598 "Net-(U7-ADBUS3)") (pinfunction "ADBUS3") (pintype "bidirectional"))
    (pad "16" smd roundrect (at -2.75 3.937 180) (size 0.875 0.3) (layers "F.Cu" "F.Paste" "F.Mask") (roundrect_rratio 0.25)
      (net 143 "3V3_SYS") (pinfunction "V_{CCIO}") (pintype "power_in"))
    (pad "17" smd roundrect (at -2.25 3.937 180) (size 0.875 0.3) (layers "F.Cu" "F.Paste" "F.Mask") (roundrect_rratio 0.25)
      (net 674 "unconnected-(U7-ADBUS4-Pad17)") (pinfunction "ADBUS4") (pintype "bidirectional+no_connect"))
    (pad "18" smd roundrect (at -1.75 3.937 180) (size 0.875 0.3) (layers "F.Cu" "F.Paste" "F.Mask") (roundrect_rratio 0.25)
      (net 665 "Net-(U7-ADBUS5)") (pinfunction "ADBUS5") (pintype "bidirectional"))
    (pad "19" smd roundrect (at -1.25 3.937 180) (size 0.875 0.3) (layers "F.Cu" "F.Paste" "F.Mask") (roundrect_rratio 0.25)
      (net 675 "unconnected-(U7-ADBUS6-Pad19)") (pinfunction "ADBUS6") (pintype "bidirectional+no_connect"))
    (pad "20" smd roundrect (at -0.75 3.937 180) (size 0.875 0.3) (layers "F.Cu" "F.Paste" "F.Mask") (roundrect_rratio 0.25)
      (net 676 "unconnected-(U7-ADBUS7-Pad20)") (pinfunction "ADBUS7") (pintype "bidirectional+no_connect"))
    (pad "21" smd roundrect (at -0.25 3.937 180) (size 0.875 0.3) (layers "F.Cu" "F.Paste" "F.Mask") (roundrect_rratio 0.25)
      (net 9 "GND") (pinfunction "GND") (pintype "power_in"))
    (pad "22" smd roundrect (at 0.249 3.937 180) (size 0.875 0.3) (layers "F.Cu" "F.Paste" "F.Mask") (roundrect_rratio 0.25)
      (net 585 "Net-(U7-BDBUS0)") (pinfunction "BDBUS0") (pintype "bidirectional"))
    (pad "23" smd roundrect (at 0.749 3.937 180) (size 0.875 0.3) (layers "F.Cu" "F.Paste" "F.Mask") (roundrect_rratio 0.25)
      (net 586 "Net-(U7-BDBUS1)") (pinfunction "BDBUS1") (pintype "bidirectional"))
    (pad "24" smd roundrect (at 1.249 3.937 180) (size 0.875 0.3) (layers "F.Cu" "F.Paste" "F.Mask") (roundrect_rratio 0.25)
      (net 587 "Net-(U7-BDBUS2)") (pinfunction "BDBUS2") (pintype "bidirectional"))
    (pad "25" smd roundrect (at 1.749 3.937 180) (size 0.875 0.3) (layers "F.Cu" "F.Paste" "F.Mask") (roundrect_rratio 0.25)
      (net 588 "Net-(U7-BDBUS3)") (pinfunction "BDBUS3") (pintype "bidirectional"))
    (pad "26" smd roundrect (at 2.249 3.937 180) (size 0.875 0.3) (layers "F.Cu" "F.Paste" "F.Mask") (roundrect_rratio 0.25)
      (net 677 "unconnected-(U7-BDBUS4-Pad26)") (pinfunction "BDBUS4") (pintype "bidirectional+no_connect"))
    (pad "27" smd roundrect (at 2.749 3.937 180) (size 0.875 0.3) (layers "F.Cu" "F.Paste" "F.Mask") (roundrect_rratio 0.25)
      (net 589 "Net-(U7-BDBUS5)") (pinfunction "BDBUS5") (pintype "bidirectional"))
    (pad "28" smd roundrect (at 3.249 3.937 180) (size 0.875 0.3) (layers "F.Cu" "F.Paste" "F.Mask") (roundrect_rratio 0.25)
      (net 678 "unconnected-(U7-BDBUS6-Pad28)") (pinfunction "BDBUS6") (pintype "bidirectional+no_connect"))
    (pad "29" smd roundrect (at 3.937 3.249 90) (size 0.875 0.3) (layers "F.Cu" "F.Paste" "F.Mask") (roundrect_rratio 0.25)
      (net 679 "unconnected-(U7-BDBUS7-Pad29)") (pinfunction "BDBUS7") (pintype "bidirectional+no_connect"))
    (pad "30" smd roundrect (at 3.937 2.749 90) (size 0.875 0.3) (layers "F.Cu" "F.Paste" "F.Mask") (roundrect_rratio 0.25)
      (net 680 "unconnected-(U7-~{SUSPEND}-Pad30)") (pinfunction "~{SUSPEND}") (pintype "output+no_connect"))
    (pad "31" smd roundrect (at 3.937 2.249 90) (size 0.875 0.3) (layers "F.Cu" "F.Paste" "F.Mask") (roundrect_rratio 0.25)
      (net 145 "1V8_FT") (pinfunction "V_{CORE}") (pintype "passive"))
    (pad "32" smd roundrect (at 3.937 1.749 90) (size 0.875 0.3) (layers "F.Cu" "F.Paste" "F.Mask") (roundrect_rratio 0.25)
      (net 590 "Net-(U7-CDBUS0)") (pinfunction "CDBUS0") (pintype "bidirectional"))
    (pad "33" smd roundrect (at 3.937 1.249 90) (size 0.875 0.3) (layers "F.Cu" "F.Paste" "F.Mask") (roundrect_rratio 0.25)
      (net 591 "Net-(U7-CDBUS1)") (pinfunction "CDBUS1") (pintype "bidirectional"))
    (pad "34" smd roundrect (at 3.937 0.749 90) (size 0.875 0.3) (layers "F.Cu" "F.Paste" "F.Mask") (roundrect_rratio 0.25)
      (net 681 "unconnected-(U7-CDBUS2-Pad34)") (pinfunction "CDBUS2") (pintype "bidirectional+no_connect"))
    (pad "35" smd roundrect (at 3.937 0.249 90) (size 0.875 0.3) (layers "F.Cu" "F.Paste" "F.Mask") (roundrect_rratio 0.25)
      (net 682 "unconnected-(U7-CDBUS3-Pad35)") (pinfunction "CDBUS3") (pintype "bidirectional+no_connect"))
    (pad "36" smd roundrect (at 3.937 -0.25 90) (size 0.875 0.3) (layers "F.Cu" "F.Paste" "F.Mask") (roundrect_rratio 0.25)
      (net 143 "3V3_SYS") (pinfunction "V_{CCIO}") (pintype "passive"))
    (pad "37" smd roundrect (at 3.937 -0.75 90) (size 0.875 0.3) (layers "F.Cu" "F.Paste" "F.Mask") (roundrect_rratio 0.25)
      (net 683 "unconnected-(U7-CDBUS4-Pad37)") (pinfunction "CDBUS4") (pintype "bidirectional+no_connect"))
    (pad "38" smd roundrect (at 3.937 -1.25 90) (size 0.875 0.3) (layers "F.Cu" "F.Paste" "F.Mask") (roundrect_rratio 0.25)
      (net 684 "unconnected-(U7-CDBUS5-Pad38)") (pinfunction "CDBUS5") (pintype "bidirectional+no_connect"))
    (pad "39" smd roundrect (at 3.937 -1.75 90) (size 0.875 0.3) (layers "F.Cu" "F.Paste" "F.Mask") (roundrect_rratio 0.25)
      (net 685 "unconnected-(U7-CDBUS6-Pad39)") (pinfunction "CDBUS6") (pintype "bidirectional+no_connect"))
    (pad "40" smd roundrect (at 3.937 -2.25 90) (size 0.875 0.3) (layers "F.Cu" "F.Paste" "F.Mask") (roundrect_rratio 0.25)
      (net 686 "unconnected-(U7-CDBUS7-Pad40)") (pinfunction "CDBUS7") (pintype "bidirectional+no_connect"))
    (pad "41" smd roundrect (at 3.937 -2.75 90) (size 0.875 0.3) (layers "F.Cu" "F.Paste" "F.Mask") (roundrect_rratio 0.25)
      (net 9 "GND") (pinfunction "GND") (pintype "passive"))
    (pad "42" smd roundrect (at 3.937 -3.25 90) (size 0.875 0.3) (layers "F.Cu" "F.Paste" "F.Mask") (roundrect_rratio 0.25)
      (net 592 "Net-(U7-DDBUS0)") (pinfunction "DDBUS0") (pintype "bidirectional"))
    (pad "43" smd roundrect (at 3.249 -3.938 180) (size 0.875 0.3) (layers "F.Cu" "F.Paste" "F.Mask") (roundrect_rratio 0.25)
      (net 145 "1V8_FT") (pinfunction "V_{REGOUT}") (pintype "power_out"))
    (pad "44" smd roundrect (at 2.749 -3.938 180) (size 0.875 0.3) (layers "F.Cu" "F.Paste" "F.Mask") (roundrect_rratio 0.25)
      (net 143 "3V3_SYS") (pinfunction "V_{REGIN}") (pintype "power_in"))
    (pad "45" smd roundrect (at 2.249 -3.938 180) (size 0.875 0.3) (layers "F.Cu" "F.Paste" "F.Mask") (roundrect_rratio 0.25)
      (net 9 "GND") (pinfunction "GND") (pintype "passive"))
    (pad "46" smd roundrect (at 1.749 -3.938 180) (size 0.875 0.3) (layers "F.Cu" "F.Paste" "F.Mask") (roundrect_rratio 0.25)
      (net 602 "Net-(U7-DDBUS1)") (pinfunction "DDBUS1") (pintype "bidirectional"))
    (pad "47" smd roundrect (at 1.249 -3.938 180) (size 0.875 0.3) (layers "F.Cu" "F.Paste" "F.Mask") (roundrect_rratio 0.25)
      (net 687 "unconnected-(U7-DDBUS2-Pad47)") (pinfunction "DDBUS2") (pintype "bidirectional+no_connect"))
    (pad "48" smd roundrect (at 0.749 -3.938 180) (size 0.875 0.3) (layers "F.Cu" "F.Paste" "F.Mask") (roundrect_rratio 0.25)
      (net 688 "unconnected-(U7-DDBUS3-Pad48)") (pinfunction "DDBUS3") (pintype "bidirectional+no_connect"))
    (pad "49" smd roundrect (at 0.249 -3.938 180) (size 0.875 0.3) (layers "F.Cu" "F.Paste" "F.Mask") (roundrect_rratio 0.25)
      (net 689 "unconnected-(U7-DDBUS4-Pad49)") (pinfunction "DDBUS4") (pintype "bidirectional+no_connect"))
    (pad "50" smd roundrect (at -0.25 -3.938 180) (size 0.875 0.3) (layers "F.Cu" "F.Paste" "F.Mask") (roundrect_rratio 0.25)
      (net 143 "3V3_SYS") (pinfunction "V_{CCIO}") (pintype "passive"))
    (pad "51" smd roundrect (at -0.75 -3.938 180) (size 0.875 0.3) (layers "F.Cu" "F.Paste" "F.Mask") (roundrect_rratio 0.25)
      (net 690 "unconnected-(U7-DDBUS5-Pad51)") (pinfunction "DDBUS5") (pintype "bidirectional+no_connect"))
    (pad "52" smd roundrect (at -1.25 -3.938 180) (size 0.875 0.3) (layers "F.Cu" "F.Paste" "F.Mask") (roundrect_rratio 0.25)
      (net 691 "unconnected-(U7-DDBUS6-Pad52)") (pinfunction "DDBUS6") (pintype "bidirectional+no_connect"))
    (pad "53" smd roundrect (at -1.75 -3.938 180) (size 0.875 0.3) (layers "F.Cu" "F.Paste" "F.Mask") (roundrect_rratio 0.25)
      (net 692 "unconnected-(U7-DDBUS7-Pad53)") (pinfunction "DDBUS7") (pintype "bidirectional+no_connect"))
    (pad "54" smd roundrect (at -2.25 -3.938 180) (size 0.875 0.3) (layers "F.Cu" "F.Paste" "F.Mask") (roundrect_rratio 0.25)
      (net 693 "unconnected-(U7-~{PWR_{EN}}-Pad54)") (pinfunction "~{PWR_{EN}}") (pintype "output+no_connect"))
    (pad "55" smd roundrect (at -2.75 -3.938 180) (size 0.875 0.3) (layers "F.Cu" "F.Paste" "F.Mask") (roundrect_rratio 0.25)
      (net 694 "unconnected-(U7-EEDATA-Pad55)") (pinfunction "EEDATA") (pintype "bidirectional+no_connect"))
    (pad "56" smd roundrect (at -3.25 -3.938 180) (size 0.875 0.3) (layers "F.Cu" "F.Paste" "F.Mask") (roundrect_rratio 0.25)
      (net 695 "unconnected-(U7-EECLK-Pad56)") (pinfunction "EECLK") (pintype "output+no_connect"))
    (pad "57" smd rect (at 0 0 90) (size 5.9 5.9) (layers "F.Cu" "F.Mask")
      (net 9 "GND") (pinfunction "GND") (pintype "passive"))
  )

  (footprint "data-center-rdimm-ddr4-tester-footprints:R_1206_3216Metric" (layer "F.Cu")
    (at 112.45 91.5 90)
    (property "Author" "Antmicro")
    (property "License" "Apache-2.0")
    (property "MPN" "RL1206FR-7W0R01L")
    (property "Manufacturer" "Yaego")
    (property "Sheetfile" "supply.kicad_sch")
    (property "Sheetname" "Supply")
    (property "Tolerance" "1%")
    (property "Val" "0R01")
    (property "ki_description" "0R01 resistor in 1206 package with unspecified tolerance")
    (attr smd)
    (fp_text reference "R200" (at -1.36 -1.05 90) (layer "F.SilkS")
        (effects (font (size 0.7 0.7) (thickness 0.15)) (justify left bottom))
    )
    (fp_text value "R_0R01_1206" (at 0 2 90) (layer "F.Fab") hide
        (effects (font (size 0.7 0.7) (thickness 0.15)) (justify left bottom))
    )
    (fp_text user "Author: Antmicro" (at -2.401 4.899 90) (layer "F.Fab") hide
        (effects (font (size 0.7 0.7) (thickness 0.15)) (justify left bottom))
    )
    (fp_text user "License: Apache-2.0" (at -2.401 6.3 90) (layer "F.Fab") hide
        (effects (font (size 0.7 0.7) (thickness 0.15)) (justify left bottom))
    )
    (fp_text user "${REFERENCE}" (at -2.401 3.5 90) (layer "F.Fab") hide
        (effects (font (size 0.7 0.7) (thickness 0.15)) (justify left bottom))
    )
    (fp_line (start 0 -0.902) (end -0.5 -0.902)
      (stroke (width 0.15) (type solid)) (layer "F.SilkS"))
    (fp_line (start 0 -0.902) (end 0.498 -0.902)
      (stroke (width 0.15) (type solid)) (layer "F.SilkS"))
    (fp_line (start 0 0.9) (end -0.5 0.9)
      (stroke (width 0.15) (type solid)) (layer "F.SilkS"))
    (fp_line (start 0 0.9) (end 0.498 0.9)
      (stroke (width 0.15) (type solid)) (layer "F.SilkS"))
    (fp_rect (start -2.25 -1.05) (end 2.25 1.05)
      (stroke (width 0.05) (type solid)) (fill none) (layer "F.CrtYd"))
    (fp_line (start -1.601 -0.802) (end -1.601 0.8)
      (stroke (width 0.15) (type solid)) (layer "F.Fab"))
    (fp_line (start -1.601 -0.802) (end 1.6 -0.802)
      (stroke (width 0.15) (type solid)) (layer "F.Fab"))
    (fp_line (start -1.601 0.8) (end 1.6 0.8)
      (stroke (width 0.15) (type solid)) (layer "F.Fab"))
    (fp_line (start 1.6 -0.802) (end 1.6 0.8)
      (stroke (width 0.15) (type solid)) (layer "F.Fab"))
    (pad "1" smd roundrect (at -1.5 0 90) (size 1.2 1.8) (layers "F.Cu" "F.Paste" "F.Mask") (roundrect_rratio 0.15)
      (net 299 "VCC0V6") (pintype "passive"))
    (pad "2" smd roundrect (at 1.499 0 90) (size 1.2 1.8) (layers "F.Cu" "F.Paste" "F.Mask") (roundrect_rratio 0.15)
      (net 186 "VTT") (pintype "passive"))
  )

  (footprint "data-center-rdimm-ddr4-tester-footprints:R_0402_1005Metric" (layer "B.Cu")
    (at 140.25 118.507)
    (descr "Resistor SMD 0402")
    (tags "resistor SMD 0402")
    (property "Author" "Antmicro")
    (property "License" "Apache-2.0")
    (property "MPN" "CR0402-FX-2002GLF")
    (property "Manufacturer" "Bourns")
    (property "Sheetfile" "interfaces.kicad_sch")
    (property "Sheetname" "Interfaces")
    (property "Tolerance" "1%")
    (property "Val" "20k")
    (property "ki_description" "20k resistor in 0402 package with 1% tolerance")
    (attr smd)
    (fp_text reference "R131" (at 1.33 -1.517 180) (layer "B.SilkS")
        (effects (font (size 0.7 0.7) (thickness 0.15)) (justify left bottom mirror))
    )
    (fp_text value "R_20k_0402" (at 0 -1.4 180) (layer "B.Fab") hide
        (effects (font (size 0.7 0.7) (thickness 0.15)) (justify left bottom mirror))
    )
    (fp_text user "${REFERENCE}" (at -0.95 -3.168 180) (layer "B.Fab") hide
        (effects (font (size 0.7 0.7) (thickness 0.15)) (justify left bottom mirror))
    )
    (fp_text user "License: Apache-2.0" (at -0.95 -5.169 180) (layer "B.Fab") hide
        (effects (font (size 0.7 0.7) (thickness 0.15)) (justify left bottom mirror))
    )
    (fp_text user "Author: Antmicro" (at -0.95 -4.169 180) (layer "B.Fab") hide
        (effects (font (size 0.7 0.7) (thickness 0.15)) (justify left bottom mirror))
    )
    (fp_rect (start -0.93 0.47) (end 0.93 -0.47)
      (stroke (width 0.05) (type solid)) (fill none) (layer "B.CrtYd"))
    (fp_rect (start -0.5 0.25) (end 0.5 -0.25)
      (stroke (width 0.15) (type solid)) (fill none) (layer "B.Fab"))
    (pad "1" smd roundrect (at -0.485 0) (size 0.59 0.64) (layers "B.Cu" "B.Paste" "B.Mask") (roundrect_rratio 0.25)
      (net 143 "3V3_SYS") (pintype "passive"))
    (pad "2" smd roundrect (at 0.485 0) (size 0.59 0.64) (layers "B.Cu" "B.Paste" "B.Mask") (roundrect_rratio 0.25)
      (net 88 "SD_CD") (pintype "passive"))
  )

  (footprint "data-center-rdimm-ddr4-tester-footprints:R_0402_1005Metric" (layer "B.Cu")
    (at 140.25 119.65 180)
    (descr "Resistor SMD 0402")
    (tags "resistor SMD 0402")
    (property "Author" "Antmicro")
    (property "License" "Apache-2.0")
    (property "MPN" "CR0402-FX-2200GLF")
    (property "Manufacturer" "Bourns")
    (property "Sheetfile" "interfaces.kicad_sch")
    (property "Sheetname" "Interfaces")
    (property "Tolerance" "1%")
    (property "Val" "220R")
    (property "ki_description" "220R resistor in 0402 package with 1% tolerance")
    (attr smd)
    (fp_text reference "R136" (at -1.3 1.73) (layer "B.SilkS")
        (effects (font (size 0.7 0.7) (thickness 0.15)) (justify left bottom mirror))
    )
    (fp_text value "R_220R_0402" (at 0 -1.4) (layer "B.Fab") hide
        (effects (font (size 0.7 0.7) (thickness 0.15)) (justify left bottom mirror))
    )
    (fp_text user "${REFERENCE}" (at -0.95 -3.168) (layer "B.Fab") hide
        (effects (font (size 0.7 0.7) (thickness 0.15)) (justify left bottom mirror))
    )
    (fp_text user "Author: Antmicro" (at -0.95 -4.169) (layer "B.Fab") hide
        (effects (font (size 0.7 0.7) (thickness 0.15)) (justify left bottom mirror))
    )
    (fp_text user "License: Apache-2.0" (at -0.95 -5.169) (layer "B.Fab") hide
        (effects (font (size 0.7 0.7) (thickness 0.15)) (justify left bottom mirror))
    )
    (fp_rect (start -0.93 0.47) (end 0.93 -0.47)
      (stroke (width 0.05) (type solid)) (fill none) (layer "B.CrtYd"))
    (fp_rect (start -0.5 0.25) (end 0.5 -0.25)
      (stroke (width 0.15) (type solid)) (fill none) (layer "B.Fab"))
    (pad "1" smd roundrect (at -0.485 0 180) (size 0.59 0.64) (layers "B.Cu" "B.Paste" "B.Mask") (roundrect_rratio 0.25)
      (net 88 "SD_CD") (pintype "passive"))
    (pad "2" smd roundrect (at 0.485 0 180) (size 0.59 0.64) (layers "B.Cu" "B.Paste" "B.Mask") (roundrect_rratio 0.25)
      (net 564 "Net-(J7-CD_SW1)") (pintype "passive"))
  )

  (footprint "data-center-rdimm-ddr4-tester-footprints:R_0402_1005Metric" (layer "B.Cu")
    (at 140.536328 92.370008 -90)
    (descr "Resistor SMD 0402")
    (tags "resistor SMD 0402")
    (property "Author" "Antmicro")
    (property "License" "Apache-2.0")
    (property "MPN" "CR0402-FX-1002GLF")
    (property "Manufacturer" "Bourns")
    (property "Sheetfile" "supply.kicad_sch")
    (property "Sheetname" "Supply")
    (property "Tolerance" "1%")
    (property "Val" "10k")
    (property "ki_description" "10k resistor in 0402 package with 1% tolerance")
    (attr smd)
    (fp_text reference "R86" (at -2.990008 -0.413672 90) (layer "B.SilkS")
        (effects (font (size 0.7 0.7) (thickness 0.15)) (justify left bottom mirror))
    )
    (fp_text value "R_10k_0402" (at 0 -1.4 90) (layer "B.Fab") hide
        (effects (font (size 0.7 0.7) (thickness 0.15)) (justify left bottom mirror))
    )
    (fp_text user "Author: Antmicro" (at -0.95 -4.169 90) (layer "B.Fab") hide
        (effects (font (size 0.7 0.7) (thickness 0.15)) (justify left bottom mirror))
    )
    (fp_text user "License: Apache-2.0" (at -0.95 -5.169 90) (layer "B.Fab") hide
        (effects (font (size 0.7 0.7) (thickness 0.15)) (justify left bottom mirror))
    )
    (fp_text user "${REFERENCE}" (at -0.95 -3.168 90) (layer "B.Fab") hide
        (effects (font (size 0.7 0.7) (thickness 0.15)) (justify left bottom mirror))
    )
    (fp_rect (start -0.93 0.47) (end 0.93 -0.47)
      (stroke (width 0.05) (type solid)) (fill none) (layer "B.CrtYd"))
    (fp_rect (start -0.5 0.25) (end 0.5 -0.25)
      (stroke (width 0.15) (type solid)) (fill none) (layer "B.Fab"))
    (pad "1" smd roundrect (at -0.485 0 270) (size 0.59 0.64) (layers "B.Cu" "B.Paste" "B.Mask") (roundrect_rratio 0.25)
      (net 307 "5V0_SYS") (pintype "passive"))
    (pad "2" smd roundrect (at 0.485 0 270) (size 0.59 0.64) (layers "B.Cu" "B.Paste" "B.Mask") (roundrect_rratio 0.25)
      (net 151 "/Supply/VCC_INT_EN") (pintype "passive"))
  )

  (footprint "data-center-rdimm-ddr4-tester-footprints:R_0402_1005Metric" (layer "B.Cu")
    (at 141.536328 92.370008 -90)
    (descr "Resistor SMD 0402")
    (tags "resistor SMD 0402")
    (property "Author" "Antmicro")
    (property "License" "Apache-2.0")
    (property "MPN" "CR0402-FX-1002GLF")
    (property "Manufacturer" "Bourns")
    (property "Sheetfile" "supply.kicad_sch")
    (property "Sheetname" "Supply")
    (property "Tolerance" "1%")
    (property "Val" "10k")
    (property "ki_description" "10k resistor in 0402 package with 1% tolerance")
    (attr smd)
    (fp_text reference "R87" (at -2.990008 -0.413672 90) (layer "B.SilkS")
        (effects (font (size 0.7 0.7) (thickness 0.15)) (justify left bottom mirror))
    )
    (fp_text value "R_10k_0402" (at 0 -1.4 90) (layer "B.Fab") hide
        (effects (font (size 0.7 0.7) (thickness 0.15)) (justify left bottom mirror))
    )
    (fp_text user "License: Apache-2.0" (at -0.95 -5.169 90) (layer "B.Fab") hide
        (effects (font (size 0.7 0.7) (thickness 0.15)) (justify left bottom mirror))
    )
    (fp_text user "${REFERENCE}" (at -0.95 -3.168 90) (layer "B.Fab") hide
        (effects (font (size 0.7 0.7) (thickness 0.15)) (justify left bottom mirror))
    )
    (fp_text user "Author: Antmicro" (at -0.95 -4.169 90) (layer "B.Fab") hide
        (effects (font (size 0.7 0.7) (thickness 0.15)) (justify left bottom mirror))
    )
    (fp_rect (start -0.93 0.47) (end 0.93 -0.47)
      (stroke (width 0.05) (type solid)) (fill none) (layer "B.CrtYd"))
    (fp_rect (start -0.5 0.25) (end 0.5 -0.25)
      (stroke (width 0.15) (type solid)) (fill none) (layer "B.Fab"))
    (pad "1" smd roundrect (at -0.485 0 270) (size 0.59 0.64) (layers "B.Cu" "B.Paste" "B.Mask") (roundrect_rratio 0.25)
      (net 307 "5V0_SYS") (pintype "passive"))
    (pad "2" smd roundrect (at 0.485 0 270) (size 0.59 0.64) (layers "B.Cu" "B.Paste" "B.Mask") (roundrect_rratio 0.25)
      (net 152 "/Supply/VCC_AUX_EN") (pintype "passive"))
  )

  (footprint "data-center-rdimm-ddr4-tester-footprints:R_0402_1005Metric" (layer "B.Cu")
    (at 142.536328 92.370008 -90)
    (descr "Resistor SMD 0402")
    (tags "resistor SMD 0402")
    (property "Author" "Antmicro")
    (property "License" "Apache-2.0")
    (property "MPN" "CR0402-FX-1002GLF")
    (property "Manufacturer" "Bourns")
    (property "Sheetfile" "supply.kicad_sch")
    (property "Sheetname" "Supply")
    (property "Tolerance" "1%")
    (property "Val" "10k")
    (property "ki_description" "10k resistor in 0402 package with 1% tolerance")
    (attr smd)
    (fp_text reference "R88" (at -2.990008 -0.413672 90) (layer "B.SilkS")
        (effects (font (size 0.7 0.7) (thickness 0.15)) (justify left bottom mirror))
    )
    (fp_text value "R_10k_0402" (at 0 -1.4 90) (layer "B.Fab") hide
        (effects (font (size 0.7 0.7) (thickness 0.15)) (justify left bottom mirror))
    )
    (fp_text user "License: Apache-2.0" (at -0.95 -5.169 90) (layer "B.Fab") hide
        (effects (font (size 0.7 0.7) (thickness 0.15)) (justify left bottom mirror))
    )
    (fp_text user "Author: Antmicro" (at -0.95 -4.169 90) (layer "B.Fab") hide
        (effects (font (size 0.7 0.7) (thickness 0.15)) (justify left bottom mirror))
    )
    (fp_text user "${REFERENCE}" (at -0.95 -3.168 90) (layer "B.Fab") hide
        (effects (font (size 0.7 0.7) (thickness 0.15)) (justify left bottom mirror))
    )
    (fp_rect (start -0.93 0.47) (end 0.93 -0.47)
      (stroke (width 0.05) (type solid)) (fill none) (layer "B.CrtYd"))
    (fp_rect (start -0.5 0.25) (end 0.5 -0.25)
      (stroke (width 0.15) (type solid)) (fill none) (layer "B.Fab"))
    (pad "1" smd roundrect (at -0.485 0 270) (size 0.59 0.64) (layers "B.Cu" "B.Paste" "B.Mask") (roundrect_rratio 0.25)
      (net 307 "5V0_SYS") (pintype "passive"))
    (pad "2" smd roundrect (at 0.485 0 270) (size 0.59 0.64) (layers "B.Cu" "B.Paste" "B.Mask") (roundrect_rratio 0.25)
      (net 153 "/Supply/VCC_IO_EN") (pintype "passive"))
  )

  (footprint "data-center-rdimm-ddr4-tester-footprints:R_0402_1005Metric" (layer "B.Cu")
    (at 241.1 121.2 180)
    (descr "Resistor SMD 0402")
    (tags "resistor SMD 0402")
    (property "Author" "Antmicro")
    (property "License" "Apache-2.0")
    (property "MPN" "CR0402-FX-3300GLF")
    (property "Manufacturer" "Bourns")
    (property "Sheetfile" "supply.kicad_sch")
    (property "Sheetname" "Supply")
    (property "Tolerance" "1%")
    (property "Val" "330R")
    (property "ki_description" "330R resistor in 0402 package with 1% tolerance")
    (attr smd)
    (fp_text reference "R119" (at 0.87 -0.37) (layer "B.SilkS")
        (effects (font (size 0.7 0.7) (thickness 0.15)) (justify left bottom mirror))
    )
    (fp_text value "R_330R_0402" (at 0 -1.4) (layer "B.Fab") hide
        (effects (font (size 0.7 0.7) (thickness 0.15)) (justify left bottom mirror))
    )
    (fp_text user "License: Apache-2.0" (at -0.95 -5.169) (layer "B.Fab") hide
        (effects (font (size 0.7 0.7) (thickness 0.15)) (justify left bottom mirror))
    )
    (fp_text user "Author: Antmicro" (at -0.95 -4.169) (layer "B.Fab") hide
        (effects (font (size 0.7 0.7) (thickness 0.15)) (justify left bottom mirror))
    )
    (fp_text user "${REFERENCE}" (at -0.95 -3.168) (layer "B.Fab") hide
        (effects (font (size 0.7 0.7) (thickness 0.15)) (justify left bottom mirror))
    )
    (fp_rect (start -0.93 0.47) (end 0.93 -0.47)
      (stroke (width 0.05) (type solid)) (fill none) (layer "B.CrtYd"))
    (fp_rect (start -0.5 0.25) (end 0.5 -0.25)
      (stroke (width 0.15) (type solid)) (fill none) (layer "B.Fab"))
    (pad "1" smd roundrect (at -0.485 0 180) (size 0.59 0.64) (layers "B.Cu" "B.Paste" "B.Mask") (roundrect_rratio 0.25)
      (net 115 "Net-(PWR1-Pad2)") (pintype "passive"))
    (pad "2" smd roundrect (at 0.485 0 180) (size 0.59 0.64) (layers "B.Cu" "B.Paste" "B.Mask") (roundrect_rratio 0.25)
      (net 9 "GND") (pintype "passive"))
  )

  (footprint "data-center-rdimm-ddr4-tester-footprints:R_0402_1005Metric" (layer "B.Cu")
    (at 197.386328 92.810008 90)
    (descr "Resistor SMD 0402")
    (tags "resistor SMD 0402")
    (property "Author" "Antmicro")
    (property "Current" "1A")
    (property "License" "Apache-2.0")
    (property "MPN" "ERJ2GE0R00X")
    (property "Manufacturer" "Panasonic")
    (property "Sheetfile" "config-spi.kicad_sch")
    (property "Sheetname" "Config SPI flash")
    (property "Tolerance" "")
    (property "Val" "0R")
    (property "ki_description" "0R resistor in 0402 package with unspecified tolerance")
    (attr smd)
    (fp_text reference "R58" (at 1.020008 2.383672 270) (layer "B.SilkS")
        (effects (font (size 0.7 0.7) (thickness 0.15)) (justify left bottom mirror))
    )
    (fp_text value "R_0R_0402" (at 0 -1.4 270) (layer "B.Fab") hide
        (effects (font (size 0.7 0.7) (thickness 0.15)) (justify left bottom mirror))
    )
    (fp_text user "License: Apache-2.0" (at -0.95 -5.169 270) (layer "B.Fab") hide
        (effects (font (size 0.7 0.7) (thickness 0.15)) (justify left bottom mirror))
    )
    (fp_text user "${REFERENCE}" (at -0.95 -3.168 270) (layer "B.Fab") hide
        (effects (font (size 0.7 0.7) (thickness 0.15)) (justify left bottom mirror))
    )
    (fp_text user "Author: Antmicro" (at -0.95 -4.169 270) (layer "B.Fab") hide
        (effects (font (size 0.7 0.7) (thickness 0.15)) (justify left bottom mirror))
    )
    (fp_rect (start -0.93 0.47) (end 0.93 -0.47)
      (stroke (width 0.05) (type solid)) (fill none) (layer "B.CrtYd"))
    (fp_rect (start -0.5 0.25) (end 0.5 -0.25)
      (stroke (width 0.15) (type solid)) (fill none) (layer "B.Fab"))
    (pad "1" smd roundrect (at -0.485 0 90) (size 0.59 0.64) (layers "B.Cu" "B.Paste" "B.Mask") (roundrect_rratio 0.25)
      (net 143 "3V3_SYS") (pintype "passive"))
    (pad "2" smd roundrect (at 0.485 0 90) (size 0.59 0.64) (layers "B.Cu" "B.Paste" "B.Mask") (roundrect_rratio 0.25)
      (net 100 "CFGBVS") (pintype "passive"))
  )

  (footprint "data-center-rdimm-ddr4-tester-footprints:R_0402_1005Metric" (layer "B.Cu")
    (at 157.686328 86.320008 90)
    (descr "Resistor SMD 0402")
    (tags "resistor SMD 0402")
    (property "Author" "Antmicro")
    (property "DNP" "DNP")
    (property "License" "Apache-2.0")
    (property "MPN" "CR0402-FX-1002GLF")
    (property "Manufacturer" "Bourns")
    (property "Sheetfile" "ethernet.kicad_sch")
    (property "Sheetname" "Ethernet")
    (property "Tolerance" "1%")
    (property "Val" "10k")
    (property "dnp" "")
    (property "exclude_from_bom" "")
    (property "ki_description" "10k resistor in 0402 package with 1% tolerance")
    (attr exclude_from_pos_files exclude_from_bom)
    (fp_text reference "R70" (at 1.170008 8.103672 270) (layer "B.SilkS")
        (effects (font (size 0.7 0.7) (thickness 0.15)) (justify left bottom mirror))
    )
    (fp_text value "R_10k_0402" (at 0 -1.4 270) (layer "B.Fab") hide
        (effects (font (size 0.7 0.7) (thickness 0.15)) (justify left bottom mirror))
    )
    (fp_text user "Author: Antmicro" (at -0.95 -4.169 270) (layer "B.Fab") hide
        (effects (font (size 0.7 0.7) (thickness 0.15)) (justify left bottom mirror))
    )
    (fp_text user "License: Apache-2.0" (at -0.95 -5.169 270) (layer "B.Fab") hide
        (effects (font (size 0.7 0.7) (thickness 0.15)) (justify left bottom mirror))
    )
    (fp_text user "${REFERENCE}" (at -0.95 -3.168 270) (layer "B.Fab") hide
        (effects (font (size 0.7 0.7) (thickness 0.15)) (justify left bottom mirror))
    )
    (fp_rect (start -0.93 0.47) (end 0.93 -0.47)
      (stroke (width 0.05) (type solid)) (fill none) (layer "B.CrtYd"))
    (fp_rect (start -0.5 0.25) (end 0.5 -0.25)
      (stroke (width 0.15) (type solid)) (fill none) (layer "B.Fab"))
    (pad "1" smd roundrect (at -0.485 0 90) (size 0.59 0.64) (layers "B.Cu" "B.Paste" "B.Mask") (roundrect_rratio 0.25)
      (net 26 "ETH_RXD0") (pintype "passive"))
    (pad "2" smd roundrect (at 0.485 0 90) (size 0.59 0.64) (layers "B.Cu" "B.Paste" "B.Mask") (roundrect_rratio 0.25)
      (net 143 "3V3_SYS") (pintype "passive"))
  )

  (footprint "data-center-rdimm-ddr4-tester-footprints:R_0402_1005Metric" (layer "B.Cu")
    (at 158.686328 86.770008 90)
    (descr "Resistor SMD 0402")
    (tags "resistor SMD 0402")
    (property "Author" "Antmicro")
    (property "DNP" "DNP")
    (property "License" "Apache-2.0")
    (property "MPN" "CR0402-FX-1002GLF")
    (property "Manufacturer" "Bourns")
    (property "Sheetfile" "ethernet.kicad_sch")
    (property "Sheetname" "Ethernet")
    (property "Tolerance" "1%")
    (property "Val" "10k")
    (property "dnp" "")
    (property "exclude_from_bom" "")
    (property "ki_description" "10k resistor in 0402 package with 1% tolerance")
    (attr exclude_from_pos_files exclude_from_bom)
    (fp_text reference "R71" (at 1.170008 8.103672 270) (layer "B.SilkS")
        (effects (font (size 0.7 0.7) (thickness 0.15)) (justify left bottom mirror))
    )
    (fp_text value "R_10k_0402" (at 0 -1.4 270) (layer "B.Fab") hide
        (effects (font (size 0.7 0.7) (thickness 0.15)) (justify left bottom mirror))
    )
    (fp_text user "${REFERENCE}" (at -0.95 -3.168 270) (layer "B.Fab") hide
        (effects (font (size 0.7 0.7) (thickness 0.15)) (justify left bottom mirror))
    )
    (fp_text user "License: Apache-2.0" (at -0.95 -5.169 270) (layer "B.Fab") hide
        (effects (font (size 0.7 0.7) (thickness 0.15)) (justify left bottom mirror))
    )
    (fp_text user "Author: Antmicro" (at -0.95 -4.169 270) (layer "B.Fab") hide
        (effects (font (size 0.7 0.7) (thickness 0.15)) (justify left bottom mirror))
    )
    (fp_rect (start -0.93 0.47) (end 0.93 -0.47)
      (stroke (width 0.05) (type solid)) (fill none) (layer "B.CrtYd"))
    (fp_rect (start -0.5 0.25) (end 0.5 -0.25)
      (stroke (width 0.15) (type solid)) (fill none) (layer "B.Fab"))
    (pad "1" smd roundrect (at -0.485 0 90) (size 0.59 0.64) (layers "B.Cu" "B.Paste" "B.Mask") (roundrect_rratio 0.25)
      (net 27 "ETH_RXD1") (pintype "passive"))
    (pad "2" smd roundrect (at 0.485 0 90) (size 0.59 0.64) (layers "B.Cu" "B.Paste" "B.Mask") (roundrect_rratio 0.25)
      (net 143 "3V3_SYS") (pintype "passive"))
  )

  (footprint "data-center-rdimm-ddr4-tester-footprints:R_0402_1005Metric" (layer "B.Cu")
    (at 155.936328 90.460008 180)
    (descr "Resistor SMD 0402")
    (tags "resistor SMD 0402")
    (property "Author" "Antmicro")
    (property "DNP" "DNP")
    (property "License" "Apache-2.0")
    (property "MPN" "CR0402-FX-1002GLF")
    (property "Manufacturer" "Bourns")
    (property "Sheetfile" "ethernet.kicad_sch")
    (property "Sheetname" "Ethernet")
    (property "Tolerance" "1%")
    (property "Val" "10k")
    (property "dnp" "")
    (property "exclude_from_bom" "")
    (property "ki_description" "10k resistor in 0402 package with 1% tolerance")
    (attr exclude_from_pos_files exclude_from_bom)
    (fp_text reference "R74" (at -8.673672 -0.389992) (layer "B.SilkS")
        (effects (font (size 0.7 0.7) (thickness 0.15)) (justify left bottom mirror))
    )
    (fp_text value "R_10k_0402" (at 0 -1.4) (layer "B.Fab") hide
        (effects (font (size 0.7 0.7) (thickness 0.15)) (justify left bottom mirror))
    )
    (fp_text user "License: Apache-2.0" (at -0.95 -5.169) (layer "B.Fab") hide
        (effects (font (size 0.7 0.7) (thickness 0.15)) (justify left bottom mirror))
    )
    (fp_text user "${REFERENCE}" (at -0.95 -3.168) (layer "B.Fab") hide
        (effects (font (size 0.7 0.7) (thickness 0.15)) (justify left bottom mirror))
    )
    (fp_text user "Author: Antmicro" (at -0.95 -4.169) (layer "B.Fab") hide
        (effects (font (size 0.7 0.7) (thickness 0.15)) (justify left bottom mirror))
    )
    (fp_rect (start -0.93 0.47) (end 0.93 -0.47)
      (stroke (width 0.05) (type solid)) (fill none) (layer "B.CrtYd"))
    (fp_rect (start -0.5 0.25) (end 0.5 -0.25)
      (stroke (width 0.15) (type solid)) (fill none) (layer "B.Fab"))
    (pad "1" smd roundrect (at -0.485 0 180) (size 0.59 0.64) (layers "B.Cu" "B.Paste" "B.Mask") (roundrect_rratio 0.25)
      (net 38 "ETH_RX_DV") (pintype "passive"))
    (pad "2" smd roundrect (at 0.485 0 180) (size 0.59 0.64) (layers "B.Cu" "B.Paste" "B.Mask") (roundrect_rratio 0.25)
      (net 143 "3V3_SYS") (pintype "passive"))
  )

  (footprint "data-center-rdimm-ddr4-tester-footprints:R_0402_1005Metric" (layer "B.Cu")
    (at 156.186328 85.610008 90)
    (descr "Resistor SMD 0402")
    (tags "resistor SMD 0402")
    (property "Author" "Antmicro")
    (property "DNP" "DNP")
    (property "License" "Apache-2.0")
    (property "MPN" "CR0402-FX-1002GLF")
    (property "Manufacturer" "Bourns")
    (property "Sheetfile" "ethernet.kicad_sch")
    (property "Sheetname" "Ethernet")
    (property "Tolerance" "1%")
    (property "Val" "10k")
    (property "dnp" "")
    (property "exclude_from_bom" "")
    (property "ki_description" "10k resistor in 0402 package with 1% tolerance")
    (attr exclude_from_pos_files exclude_from_bom)
    (fp_text reference "R75" (at 1.170008 8.103672 270) (layer "B.SilkS")
        (effects (font (size 0.7 0.7) (thickness 0.15)) (justify left bottom mirror))
    )
    (fp_text value "R_10k_0402" (at 0 -1.4 270) (layer "B.Fab") hide
        (effects (font (size 0.7 0.7) (thickness 0.15)) (justify left bottom mirror))
    )
    (fp_text user "Author: Antmicro" (at -0.95 -4.169 270) (layer "B.Fab") hide
        (effects (font (size 0.7 0.7) (thickness 0.15)) (justify left bottom mirror))
    )
    (fp_text user "License: Apache-2.0" (at -0.95 -5.169 270) (layer "B.Fab") hide
        (effects (font (size 0.7 0.7) (thickness 0.15)) (justify left bottom mirror))
    )
    (fp_text user "${REFERENCE}" (at -0.95 -3.168 270) (layer "B.Fab") hide
        (effects (font (size 0.7 0.7) (thickness 0.15)) (justify left bottom mirror))
    )
    (fp_rect (start -0.93 0.47) (end 0.93 -0.47)
      (stroke (width 0.05) (type solid)) (fill none) (layer "B.CrtYd"))
    (fp_rect (start -0.5 0.25) (end 0.5 -0.25)
      (stroke (width 0.15) (type solid)) (fill none) (layer "B.Fab"))
    (pad "1" smd roundrect (at -0.485 0 90) (size 0.59 0.64) (layers "B.Cu" "B.Paste" "B.Mask") (roundrect_rratio 0.25)
      (net 40 "ETH_RX_CLK") (pintype "passive"))
    (pad "2" smd roundrect (at 0.485 0 90) (size 0.59 0.64) (layers "B.Cu" "B.Paste" "B.Mask") (roundrect_rratio 0.25)
      (net 143 "3V3_SYS") (pintype "passive"))
  )

  (footprint "data-center-rdimm-ddr4-tester-footprints:R_0402_1005Metric" (layer "B.Cu")
    (at 156.376328 96.390008 -90)
    (descr "Resistor SMD 0402")
    (tags "resistor SMD 0402")
    (property "Author" "Antmicro")
    (property "License" "Apache-2.0")
    (property "MPN" "CR0402-FX-1002GLF")
    (property "Manufacturer" "Bourns")
    (property "Sheetfile" "ethernet.kicad_sch")
    (property "Sheetname" "Ethernet")
    (property "Tolerance" "1%")
    (property "Val" "10k")
    (property "ki_description" "10k resistor in 0402 package with 1% tolerance")
    (attr smd)
    (fp_text reference "R76" (at -1.020008 -1.293672 90) (layer "B.SilkS")
        (effects (font (size 0.7 0.7) (thickness 0.15)) (justify left bottom mirror))
    )
    (fp_text value "R_10k_0402" (at 0 -1.4 90) (layer "B.Fab") hide
        (effects (font (size 0.7 0.7) (thickness 0.15)) (justify left bottom mirror))
    )
    (fp_text user "License: Apache-2.0" (at -0.95 -5.169 90) (layer "B.Fab") hide
        (effects (font (size 0.7 0.7) (thickness 0.15)) (justify left bottom mirror))
    )
    (fp_text user "Author: Antmicro" (at -0.95 -4.169 90) (layer "B.Fab") hide
        (effects (font (size 0.7 0.7) (thickness 0.15)) (justify left bottom mirror))
    )
    (fp_text user "${REFERENCE}" (at -0.95 -3.168 90) (layer "B.Fab") hide
        (effects (font (size 0.7 0.7) (thickness 0.15)) (justify left bottom mirror))
    )
    (fp_rect (start -0.93 0.47) (end 0.93 -0.47)
      (stroke (width 0.05) (type solid)) (fill none) (layer "B.CrtYd"))
    (fp_rect (start -0.5 0.25) (end 0.5 -0.25)
      (stroke (width 0.15) (type solid)) (fill none) (layer "B.Fab"))
    (pad "1" smd roundrect (at -0.485 0 270) (size 0.59 0.64) (layers "B.Cu" "B.Paste" "B.Mask") (roundrect_rratio 0.25)
      (net 30 "ETH_REF_CLK") (pintype "passive"))
    (pad "2" smd roundrect (at 0.485 0 270) (size 0.59 0.64) (layers "B.Cu" "B.Paste" "B.Mask") (roundrect_rratio 0.25)
      (net 143 "3V3_SYS") (pintype "passive"))
  )

  (footprint "data-center-rdimm-ddr4-tester-footprints:R_0402_1005Metric" (layer "B.Cu")
    (at 154.886328 96.320008)
    (descr "Resistor SMD 0402")
    (tags "resistor SMD 0402")
    (property "Author" "Antmicro")
    (property "License" "Apache-2.0")
    (property "MPN" "CR0402-FX-1002GLF")
    (property "Manufacturer" "Bourns")
    (property "Sheetfile" "ethernet.kicad_sch")
    (property "Sheetname" "Ethernet")
    (property "Tolerance" "1%")
    (property "Val" "10k")
    (property "ki_description" "10k resistor in 0402 package with 1% tolerance")
    (attr smd)
    (fp_text reference "R79" (at 1.073672 1.309992 180) (layer "B.SilkS")
        (effects (font (size 0.7 0.7) (thickness 0.15)) (justify left bottom mirror))
    )
    (fp_text value "R_10k_0402" (at 0 -1.4 180) (layer "B.Fab") hide
        (effects (font (size 0.7 0.7) (thickness 0.15)) (justify left bottom mirror))
    )
    (fp_text user "License: Apache-2.0" (at -0.95 -5.169 180) (layer "B.Fab") hide
        (effects (font (size 0.7 0.7) (thickness 0.15)) (justify left bottom mirror))
    )
    (fp_text user "${REFERENCE}" (at -0.95 -3.168 180) (layer "B.Fab") hide
        (effects (font (size 0.7 0.7) (thickness 0.15)) (justify left bottom mirror))
    )
    (fp_text user "Author: Antmicro" (at -0.95 -4.169 180) (layer "B.Fab") hide
        (effects (font (size 0.7 0.7) (thickness 0.15)) (justify left bottom mirror))
    )
    (fp_rect (start -0.93 0.47) (end 0.93 -0.47)
      (stroke (width 0.05) (type solid)) (fill none) (layer "B.CrtYd"))
    (fp_rect (start -0.5 0.25) (end 0.5 -0.25)
      (stroke (width 0.15) (type solid)) (fill none) (layer "B.Fab"))
    (pad "1" smd roundrect (at -0.485 0) (size 0.59 0.64) (layers "B.Cu" "B.Paste" "B.Mask") (roundrect_rratio 0.25)
      (net 28 "ETH_RSTN") (pintype "passive"))
    (pad "2" smd roundrect (at 0.485 0) (size 0.59 0.64) (layers "B.Cu" "B.Paste" "B.Mask") (roundrect_rratio 0.25)
      (net 143 "3V3_SYS") (pintype "passive"))
  )

  (footprint "data-center-rdimm-ddr4-tester-footprints:R_0402_1005Metric" (layer "B.Cu")
    (at 166.786328 98.020008)
    (descr "Resistor SMD 0402")
    (tags "resistor SMD 0402")
    (property "Author" "Antmicro")
    (property "License" "Apache-2.0")
    (property "MPN" "CR0402-FX-1002GLF")
    (property "Manufacturer" "Bourns")
    (property "Sheetfile" "ethernet.kicad_sch")
    (property "Sheetname" "Ethernet")
    (property "Tolerance" "1%")
    (property "Val" "10k")
    (property "ki_description" "10k resistor in 0402 package with 1% tolerance")
    (attr smd)
    (fp_text reference "R80" (at 3.013672 0.399992 180) (layer "B.SilkS")
        (effects (font (size 0.7 0.7) (thickness 0.15)) (justify left bottom mirror))
    )
    (fp_text value "R_10k_0402" (at 0 -1.4 180) (layer "B.Fab") hide
        (effects (font (size 0.7 0.7) (thickness 0.15)) (justify left bottom mirror))
    )
    (fp_text user "License: Apache-2.0" (at -0.95 -5.169 180) (layer "B.Fab") hide
        (effects (font (size 0.7 0.7) (thickness 0.15)) (justify left bottom mirror))
    )
    (fp_text user "Author: Antmicro" (at -0.95 -4.169 180) (layer "B.Fab") hide
        (effects (font (size 0.7 0.7) (thickness 0.15)) (justify left bottom mirror))
    )
    (fp_text user "${REFERENCE}" (at -0.95 -3.168 180) (layer "B.Fab") hide
        (effects (font (size 0.7 0.7) (thickness 0.15)) (justify left bottom mirror))
    )
    (fp_rect (start -0.93 0.47) (end 0.93 -0.47)
      (stroke (width 0.05) (type solid)) (fill none) (layer "B.CrtYd"))
    (fp_rect (start -0.5 0.25) (end 0.5 -0.25)
      (stroke (width 0.15) (type solid)) (fill none) (layer "B.Fab"))
    (pad "1" smd roundrect (at -0.485 0) (size 0.59 0.64) (layers "B.Cu" "B.Paste" "B.Mask") (roundrect_rratio 0.25)
      (net 17 "LED_SPD") (pintype "passive"))
    (pad "2" smd roundrect (at 0.485 0) (size 0.59 0.64) (layers "B.Cu" "B.Paste" "B.Mask") (roundrect_rratio 0.25)
      (net 143 "3V3_SYS") (pintype "passive"))
  )

  (footprint "data-center-rdimm-ddr4-tester-footprints:R_0402_1005Metric" (layer "B.Cu")
    (at 166.786328 96.520008)
    (descr "Resistor SMD 0402")
    (tags "resistor SMD 0402")
    (property "Author" "Antmicro")
    (property "License" "Apache-2.0")
    (property "MPN" "CR0402-FX-1002GLF")
    (property "Manufacturer" "Bourns")
    (property "Sheetfile" "ethernet.kicad_sch")
    (property "Sheetname" "Ethernet")
    (property "Tolerance" "1%")
    (property "Val" "10k")
    (property "ki_description" "10k resistor in 0402 package with 1% tolerance")
    (attr smd)
    (fp_text reference "R81" (at 3.053672 0.349992 180) (layer "B.SilkS")
        (effects (font (size 0.7 0.7) (thickness 0.15)) (justify left bottom mirror))
    )
    (fp_text value "R_10k_0402" (at 0 -1.4 180) (layer "B.Fab") hide
        (effects (font (size 0.7 0.7) (thickness 0.15)) (justify left bottom mirror))
    )
    (fp_text user "Author: Antmicro" (at -0.95 -4.169 180) (layer "B.Fab") hide
        (effects (font (size 0.7 0.7) (thickness 0.15)) (justify left bottom mirror))
    )
    (fp_text user "${REFERENCE}" (at -0.95 -3.168 180) (layer "B.Fab") hide
        (effects (font (size 0.7 0.7) (thickness 0.15)) (justify left bottom mirror))
    )
    (fp_text user "License: Apache-2.0" (at -0.95 -5.169 180) (layer "B.Fab") hide
        (effects (font (size 0.7 0.7) (thickness 0.15)) (justify left bottom mirror))
    )
    (fp_rect (start -0.93 0.47) (end 0.93 -0.47)
      (stroke (width 0.05) (type solid)) (fill none) (layer "B.CrtYd"))
    (fp_rect (start -0.5 0.25) (end 0.5 -0.25)
      (stroke (width 0.15) (type solid)) (fill none) (layer "B.Fab"))
    (pad "1" smd roundrect (at -0.485 0) (size 0.59 0.64) (layers "B.Cu" "B.Paste" "B.Mask") (roundrect_rratio 0.25)
      (net 16 "LED_LINK") (pintype "passive"))
    (pad "2" smd roundrect (at 0.485 0) (size 0.59 0.64) (layers "B.Cu" "B.Paste" "B.Mask") (roundrect_rratio 0.25)
      (net 143 "3V3_SYS") (pintype "passive"))
  )

  (footprint "data-center-rdimm-ddr4-tester-footprints:C_0402_1005Metric" (layer "B.Cu")
    (at 157.1 98.5 90)
    (descr "Capacitor SMD 0402")
    (tags "capacitor SMD 0402")
    (property "Author" "Antmicro")
    (property "Dielectric" "")
    (property "License" "Apache-2.0")
    (property "MPN" "GRM155R61A475MEAAD")
    (property "Manufacturer" "Murata")
    (property "Sheetfile" "ethernet.kicad_sch")
    (property "Sheetname" "Ethernet")
    (property "Val" "4u7")
    (property "Voltage" "")
    (property "ki_description" " ")
    (attr smd)
    (fp_text reference "C121" (at 0.79 -0.44 270) (layer "B.SilkS")
        (effects (font (size 0.7 0.7) (thickness 0.15)) (justify left bottom mirror))
    )
    (fp_text value "C_4u7_0402" (at 0 -1.4 270) (layer "B.Fab") hide
        (effects (font (size 0.7 0.7) (thickness 0.15)) (justify left bottom mirror))
    )
    (fp_text user "${REFERENCE}" (at -0.932 -3.168 270) (layer "B.Fab") hide
        (effects (font (size 0.7 0.7) (thickness 0.15)) (justify left bottom mirror))
    )
    (fp_text user "Author: Antmicro" (at -0.932 -4.17 270) (layer "B.Fab") hide
        (effects (font (size 0.7 0.7) (thickness 0.15)) (justify left bottom mirror))
    )
    (fp_text user "License: Apache-2.0" (at -0.932 -5.17 270) (layer "B.Fab") hide
        (effects (font (size 0.7 0.7) (thickness 0.15)) (justify left bottom mirror))
    )
    (fp_rect (start -0.94 0.47) (end 0.94 -0.47)
      (stroke (width 0.05) (type solid)) (fill none) (layer "B.CrtYd"))
    (fp_rect (start -0.499 0.249) (end 0.499 -0.249)
      (stroke (width 0.15) (type solid)) (fill none) (layer "B.Fab"))
    (pad "1" smd roundrect (at -0.484 0 90) (size 0.59 0.64) (layers "B.Cu" "B.Paste" "B.Mask") (roundrect_rratio 0.25)
      (net 177 "/Ethernet/AVDDL") (pintype "passive"))
    (pad "2" smd roundrect (at 0.484 0 90) (size 0.59 0.64) (layers "B.Cu" "B.Paste" "B.Mask") (roundrect_rratio 0.25)
      (net 9 "GND") (pintype "passive"))
  )

  (footprint "data-center-rdimm-ddr4-tester-footprints:C_0402_1005Metric" (layer "B.Cu")
    (at 157.486328 93.020008 -90)
    (descr "Capacitor SMD 0402")
    (tags "capacitor SMD 0402")
    (property "Author" "Antmicro")
    (property "Dielectric" "")
    (property "License" "Apache-2.0")
    (property "MPN" "C1005X5R1E474M050BB")
    (property "Manufacturer" "TDK")
    (property "Sheetfile" "ethernet.kicad_sch")
    (property "Sheetname" "Ethernet")
    (property "Val" "470n")
    (property "Voltage" "")
    (property "ki_description" " ")
    (attr smd)
    (fp_text reference "C122" (at -1.449008 -6.503672 90) (layer "B.SilkS")
        (effects (font (size 0.7 0.7) (thickness 0.15)) (justify left bottom mirror))
    )
    (fp_text value "C_470n_0402" (at 0 -1.4 90) (layer "B.Fab") hide
        (effects (font (size 0.7 0.7) (thickness 0.15)) (justify left bottom mirror))
    )
    (fp_text user "Author: Antmicro" (at -0.932 -4.17 90) (layer "B.Fab") hide
        (effects (font (size 0.7 0.7) (thickness 0.15)) (justify left bottom mirror))
    )
    (fp_text user "License: Apache-2.0" (at -0.932 -5.17 90) (layer "B.Fab") hide
        (effects (font (size 0.7 0.7) (thickness 0.15)) (justify left bottom mirror))
    )
    (fp_text user "${REFERENCE}" (at -0.932 -3.168 90) (layer "B.Fab") hide
        (effects (font (size 0.7 0.7) (thickness 0.15)) (justify left bottom mirror))
    )
    (fp_rect (start -0.94 0.47) (end 0.94 -0.47)
      (stroke (width 0.05) (type solid)) (fill none) (layer "B.CrtYd"))
    (fp_rect (start -0.499 0.249) (end 0.499 -0.249)
      (stroke (width 0.15) (type solid)) (fill none) (layer "B.Fab"))
    (pad "1" smd roundrect (at -0.484 0 270) (size 0.59 0.64) (layers "B.Cu" "B.Paste" "B.Mask") (roundrect_rratio 0.25)
      (net 306 "1V2_SYS") (pintype "passive"))
    (pad "2" smd roundrect (at 0.484 0 270) (size 0.59 0.64) (layers "B.Cu" "B.Paste" "B.Mask") (roundrect_rratio 0.25)
      (net 9 "GND") (pintype "passive"))
  )

  (footprint "data-center-rdimm-ddr4-tester-footprints:C_0402_1005Metric" (layer "B.Cu")
    (at 155.486328 93.020008 -90)
    (descr "Capacitor SMD 0402")
    (tags "capacitor SMD 0402")
    (property "Author" "Antmicro")
    (property "Dielectric" "")
    (property "License" "Apache-2.0")
    (property "MPN" "GRM155R61A475MEAAD")
    (property "Manufacturer" "Murata")
    (property "Sheetfile" "ethernet.kicad_sch")
    (property "Sheetname" "Ethernet")
    (property "Val" "4u7")
    (property "Voltage" "")
    (property "ki_description" " ")
    (attr smd)
    (fp_text reference "C123" (at -1.449008 -6.503672 90) (layer "B.SilkS")
        (effects (font (size 0.7 0.7) (thickness 0.15)) (justify left bottom mirror))
    )
    (fp_text value "C_4u7_0402" (at 0 -1.4 90) (layer "B.Fab") hide
        (effects (font (size 0.7 0.7) (thickness 0.15)) (justify left bottom mirror))
    )
    (fp_text user "License: Apache-2.0" (at -0.932 -5.17 90) (layer "B.Fab") hide
        (effects (font (size 0.7 0.7) (thickness 0.15)) (justify left bottom mirror))
    )
    (fp_text user "Author: Antmicro" (at -0.932 -4.17 90) (layer "B.Fab") hide
        (effects (font (size 0.7 0.7) (thickness 0.15)) (justify left bottom mirror))
    )
    (fp_text user "${REFERENCE}" (at -0.932 -3.168 90) (layer "B.Fab") hide
        (effects (font (size 0.7 0.7) (thickness 0.15)) (justify left bottom mirror))
    )
    (fp_rect (start -0.94 0.47) (end 0.94 -0.47)
      (stroke (width 0.05) (type solid)) (fill none) (layer "B.CrtYd"))
    (fp_rect (start -0.499 0.249) (end 0.499 -0.249)
      (stroke (width 0.15) (type solid)) (fill none) (layer "B.Fab"))
    (pad "1" smd roundrect (at -0.484 0 270) (size 0.59 0.64) (layers "B.Cu" "B.Paste" "B.Mask") (roundrect_rratio 0.25)
      (net 143 "3V3_SYS") (pintype "passive"))
    (pad "2" smd roundrect (at 0.484 0 270) (size 0.59 0.64) (layers "B.Cu" "B.Paste" "B.Mask") (roundrect_rratio 0.25)
      (net 9 "GND") (pintype "passive"))
  )

  (footprint "data-center-rdimm-ddr4-tester-footprints:C_0402_1005Metric" (layer "B.Cu")
    (at 158.95 100.55 -90)
    (descr "Capacitor SMD 0402")
    (tags "capacitor SMD 0402")
    (property "Author" "Antmicro")
    (property "Dielectric" "")
    (property "License" "Apache-2.0")
    (property "MPN" "C1005X5R1E474M050BB")
    (property "Manufacturer" "TDK")
    (property "Sheetfile" "ethernet.kicad_sch")
    (property "Sheetname" "Ethernet")
    (property "Val" "470n")
    (property "Voltage" "")
    (property "ki_description" " ")
    (attr smd)
    (fp_text reference "C125" (at -0.04 1.52 90) (layer "B.SilkS")
        (effects (font (size 0.7 0.7) (thickness 0.15)) (justify left bottom mirror))
    )
    (fp_text value "C_470n_0402" (at 0 -1.4 90) (layer "B.Fab") hide
        (effects (font (size 0.7 0.7) (thickness 0.15)) (justify left bottom mirror))
    )
    (fp_text user "${REFERENCE}" (at -0.932 -3.168 90) (layer "B.Fab") hide
        (effects (font (size 0.7 0.7) (thickness 0.15)) (justify left bottom mirror))
    )
    (fp_text user "License: Apache-2.0" (at -0.932 -5.17 90) (layer "B.Fab") hide
        (effects (font (size 0.7 0.7) (thickness 0.15)) (justify left bottom mirror))
    )
    (fp_text user "Author: Antmicro" (at -0.932 -4.17 90) (layer "B.Fab") hide
        (effects (font (size 0.7 0.7) (thickness 0.15)) (justify left bottom mirror))
    )
    (fp_rect (start -0.94 0.47) (end 0.94 -0.47)
      (stroke (width 0.05) (type solid)) (fill none) (layer "B.CrtYd"))
    (fp_rect (start -0.499 0.249) (end 0.499 -0.249)
      (stroke (width 0.15) (type solid)) (fill none) (layer "B.Fab"))
    (pad "1" smd roundrect (at -0.484 0 270) (size 0.59 0.64) (layers "B.Cu" "B.Paste" "B.Mask") (roundrect_rratio 0.25)
      (net 177 "/Ethernet/AVDDL") (pintype "passive"))
    (pad "2" smd roundrect (at 0.484 0 270) (size 0.59 0.64) (layers "B.Cu" "B.Paste" "B.Mask") (roundrect_rratio 0.25)
      (net 9 "GND") (pintype "passive"))
  )

  (footprint "data-center-rdimm-ddr4-tester-footprints:C_0402_1005Metric" (layer "B.Cu")
    (at 159.586328 93.020008 -90)
    (descr "Capacitor SMD 0402")
    (tags "capacitor SMD 0402")
    (property "Author" "Antmicro")
    (property "Dielectric" "")
    (property "License" "Apache-2.0")
    (property "MPN" "C1005X5R1E474M050BB")
    (property "Manufacturer" "TDK")
    (property "Sheetfile" "ethernet.kicad_sch")
    (property "Sheetname" "Ethernet")
    (property "Val" "470n")
    (property "Voltage" "")
    (property "ki_description" " ")
    (attr smd)
    (fp_text reference "C126" (at -1.449008 -6.503672 90) (layer "B.SilkS")
        (effects (font (size 0.7 0.7) (thickness 0.15)) (justify left bottom mirror))
    )
    (fp_text value "C_470n_0402" (at 0 -1.4 90) (layer "B.Fab") hide
        (effects (font (size 0.7 0.7) (thickness 0.15)) (justify left bottom mirror))
    )
    (fp_text user "License: Apache-2.0" (at -0.932 -5.17 90) (layer "B.Fab") hide
        (effects (font (size 0.7 0.7) (thickness 0.15)) (justify left bottom mirror))
    )
    (fp_text user "Author: Antmicro" (at -0.932 -4.17 90) (layer "B.Fab") hide
        (effects (font (size 0.7 0.7) (thickness 0.15)) (justify left bottom mirror))
    )
    (fp_text user "${REFERENCE}" (at -0.932 -3.168 90) (layer "B.Fab") hide
        (effects (font (size 0.7 0.7) (thickness 0.15)) (justify left bottom mirror))
    )
    (fp_rect (start -0.94 0.47) (end 0.94 -0.47)
      (stroke (width 0.05) (type solid)) (fill none) (layer "B.CrtYd"))
    (fp_rect (start -0.499 0.249) (end 0.499 -0.249)
      (stroke (width 0.15) (type solid)) (fill none) (layer "B.Fab"))
    (pad "1" smd roundrect (at -0.484 0 270) (size 0.59 0.64) (layers "B.Cu" "B.Paste" "B.Mask") (roundrect_rratio 0.25)
      (net 306 "1V2_SYS") (pintype "passive"))
    (pad "2" smd roundrect (at 0.484 0 270) (size 0.59 0.64) (layers "B.Cu" "B.Paste" "B.Mask") (roundrect_rratio 0.25)
      (net 9 "GND") (pintype "passive"))
  )

  (footprint "data-center-rdimm-ddr4-tester-footprints:C_0402_1005Metric" (layer "B.Cu")
    (at 157.925 100.55 -90)
    (descr "Capacitor SMD 0402")
    (tags "capacitor SMD 0402")
    (property "Author" "Antmicro")
    (property "Dielectric" "X7R")
    (property "License" "Apache-2.0")
    (property "MPN" "GRM155R71H103KA88D")
    (property "Manufacturer" "Murata")
    (property "Sheetfile" "ethernet.kicad_sch")
    (property "Sheetname" "Ethernet")
    (property "Val" "10n")
    (property "Voltage" "50V")
    (property "ki_description" " ")
    (attr smd)
    (fp_text reference "C129" (at -0.04 1.52 90) (layer "B.SilkS")
        (effects (font (size 0.7 0.7) (thickness 0.15)) (justify left bottom mirror))
    )
    (fp_text value "C_10n_0402" (at 0 -1.4 90) (layer "B.Fab") hide
        (effects (font (size 0.7 0.7) (thickness 0.15)) (justify left bottom mirror))
    )
    (fp_text user "Author: Antmicro" (at -0.932 -4.17 90) (layer "B.Fab") hide
        (effects (font (size 0.7 0.7) (thickness 0.15)) (justify left bottom mirror))
    )
    (fp_text user "License: Apache-2.0" (at -0.932 -5.17 90) (layer "B.Fab") hide
        (effects (font (size 0.7 0.7) (thickness 0.15)) (justify left bottom mirror))
    )
    (fp_text user "${REFERENCE}" (at -0.932 -3.168 90) (layer "B.Fab") hide
        (effects (font (size 0.7 0.7) (thickness 0.15)) (justify left bottom mirror))
    )
    (fp_rect (start -0.94 0.47) (end 0.94 -0.47)
      (stroke (width 0.05) (type solid)) (fill none) (layer "B.CrtYd"))
    (fp_rect (start -0.499 0.249) (end 0.499 -0.249)
      (stroke (width 0.15) (type solid)) (fill none) (layer "B.Fab"))
    (pad "1" smd roundrect (at -0.484 0 270) (size 0.59 0.64) (layers "B.Cu" "B.Paste" "B.Mask") (roundrect_rratio 0.25)
      (net 177 "/Ethernet/AVDDL") (pintype "passive"))
    (pad "2" smd roundrect (at 0.484 0 270) (size 0.59 0.64) (layers "B.Cu" "B.Paste" "B.Mask") (roundrect_rratio 0.25)
      (net 9 "GND") (pintype "passive"))
  )

  (footprint "data-center-rdimm-ddr4-tester-footprints:C_0402_1005Metric" (layer "B.Cu")
    (at 156.486328 93.020008 -90)
    (descr "Capacitor SMD 0402")
    (tags "capacitor SMD 0402")
    (property "Author" "Antmicro")
    (property "Dielectric" "X7R")
    (property "License" "Apache-2.0")
    (property "MPN" "GRM155R71H103KA88D")
    (property "Manufacturer" "Murata")
    (property "Sheetfile" "ethernet.kicad_sch")
    (property "Sheetname" "Ethernet")
    (property "Val" "10n")
    (property "Voltage" "50V")
    (property "ki_description" " ")
    (attr smd)
    (fp_text reference "C131" (at -1.449008 -6.503672 90) (layer "B.SilkS")
        (effects (font (size 0.7 0.7) (thickness 0.15)) (justify left bottom mirror))
    )
    (fp_text value "C_10n_0402" (at 0 -1.4 90) (layer "B.Fab") hide
        (effects (font (size 0.7 0.7) (thickness 0.15)) (justify left bottom mirror))
    )
    (fp_text user "${REFERENCE}" (at -0.932 -3.168 90) (layer "B.Fab") hide
        (effects (font (size 0.7 0.7) (thickness 0.15)) (justify left bottom mirror))
    )
    (fp_text user "License: Apache-2.0" (at -0.932 -5.17 90) (layer "B.Fab") hide
        (effects (font (size 0.7 0.7) (thickness 0.15)) (justify left bottom mirror))
    )
    (fp_text user "Author: Antmicro" (at -0.932 -4.17 90) (layer "B.Fab") hide
        (effects (font (size 0.7 0.7) (thickness 0.15)) (justify left bottom mirror))
    )
    (fp_rect (start -0.94 0.47) (end 0.94 -0.47)
      (stroke (width 0.05) (type solid)) (fill none) (layer "B.CrtYd"))
    (fp_rect (start -0.499 0.249) (end 0.499 -0.249)
      (stroke (width 0.15) (type solid)) (fill none) (layer "B.Fab"))
    (pad "1" smd roundrect (at -0.484 0 270) (size 0.59 0.64) (layers "B.Cu" "B.Paste" "B.Mask") (roundrect_rratio 0.25)
      (net 143 "3V3_SYS") (pintype "passive"))
    (pad "2" smd roundrect (at 0.484 0 270) (size 0.59 0.64) (layers "B.Cu" "B.Paste" "B.Mask") (roundrect_rratio 0.25)
      (net 9 "GND") (pintype "passive"))
  )

  (footprint "data-center-rdimm-ddr4-tester-footprints:C_0402_1005Metric" (layer "B.Cu")
    (at 154.1 100.025 180)
    (descr "Capacitor SMD 0402")
    (tags "capacitor SMD 0402")
    (property "Author" "Antmicro")
    (property "Dielectric" "")
    (property "License" "Apache-2.0")
    (property "MPN" "GRM155R61A475MEAAD")
    (property "Manufacturer" "Murata")
    (property "Sheetfile" "ethernet.kicad_sch")
    (property "Sheetname" "Ethernet")
    (property "Val" "4u7")
    (property "Voltage" "")
    (property "ki_description" " ")
    (attr smd)
    (fp_text reference "C132" (at 1.02 -0.345) (layer "B.SilkS")
        (effects (font (size 0.7 0.7) (thickness 0.15)) (justify left bottom mirror))
    )
    (fp_text value "C_4u7_0402" (at 0 -1.4) (layer "B.Fab") hide
        (effects (font (size 0.7 0.7) (thickness 0.15)) (justify left bottom mirror))
    )
    (fp_text user "Author: Antmicro" (at -0.932 -4.17) (layer "B.Fab") hide
        (effects (font (size 0.7 0.7) (thickness 0.15)) (justify left bottom mirror))
    )
    (fp_text user "License: Apache-2.0" (at -0.932 -5.17) (layer "B.Fab") hide
        (effects (font (size 0.7 0.7) (thickness 0.15)) (justify left bottom mirror))
    )
    (fp_text user "${REFERENCE}" (at -0.932 -3.168) (layer "B.Fab") hide
        (effects (font (size 0.7 0.7) (thickness 0.15)) (justify left bottom mirror))
    )
    (fp_rect (start -0.94 0.47) (end 0.94 -0.47)
      (stroke (width 0.05) (type solid)) (fill none) (layer "B.CrtYd"))
    (fp_rect (start -0.499 0.249) (end 0.499 -0.249)
      (stroke (width 0.15) (type solid)) (fill none) (layer "B.Fab"))
    (pad "1" smd roundrect (at -0.484 0 180) (size 0.59 0.64) (layers "B.Cu" "B.Paste" "B.Mask") (roundrect_rratio 0.25)
      (net 179 "/Ethernet/AVDDH") (pintype "passive"))
    (pad "2" smd roundrect (at 0.484 0 180) (size 0.59 0.64) (layers "B.Cu" "B.Paste" "B.Mask") (roundrect_rratio 0.25)
      (net 9 "GND") (pintype "passive"))
  )

  (footprint "data-center-rdimm-ddr4-tester-footprints:C_0402_1005Metric" (layer "B.Cu")
    (at 160.75 99.575)
    (descr "Capacitor SMD 0402")
    (tags "capacitor SMD 0402")
    (property "Author" "Antmicro")
    (property "Dielectric" "X7R")
    (property "License" "Apache-2.0")
    (property "MPN" "GRM155R71H103KA88D")
    (property "Manufacturer" "Murata")
    (property "Sheetfile" "ethernet.kicad_sch")
    (property "Sheetname" "Ethernet")
    (property "Val" "10n")
    (property "Voltage" "50V")
    (property "ki_description" " ")
    (attr smd)
    (fp_text reference "C134" (at 3.69 0.355 180) (layer "B.SilkS")
        (effects (font (size 0.7 0.7) (thickness 0.15)) (justify left bottom mirror))
    )
    (fp_text value "C_10n_0402" (at 0 -1.4 180) (layer "B.Fab") hide
        (effects (font (size 0.7 0.7) (thickness 0.15)) (justify left bottom mirror))
    )
    (fp_text user "${REFERENCE}" (at -0.932 -3.168 180) (layer "B.Fab") hide
        (effects (font (size 0.7 0.7) (thickness 0.15)) (justify left bottom mirror))
    )
    (fp_text user "Author: Antmicro" (at -0.932 -4.17 180) (layer "B.Fab") hide
        (effects (font (size 0.7 0.7) (thickness 0.15)) (justify left bottom mirror))
    )
    (fp_text user "License: Apache-2.0" (at -0.932 -5.17 180) (layer "B.Fab") hide
        (effects (font (size 0.7 0.7) (thickness 0.15)) (justify left bottom mirror))
    )
    (fp_rect (start -0.94 0.47) (end 0.94 -0.47)
      (stroke (width 0.05) (type solid)) (fill none) (layer "B.CrtYd"))
    (fp_rect (start -0.499 0.249) (end 0.499 -0.249)
      (stroke (width 0.15) (type solid)) (fill none) (layer "B.Fab"))
    (pad "1" smd roundrect (at -0.484 0) (size 0.59 0.64) (layers "B.Cu" "B.Paste" "B.Mask") (roundrect_rratio 0.25)
      (net 177 "/Ethernet/AVDDL") (pintype "passive"))
    (pad "2" smd roundrect (at 0.484 0) (size 0.59 0.64) (layers "B.Cu" "B.Paste" "B.Mask") (roundrect_rratio 0.25)
      (net 9 "GND") (pintype "passive"))
  )

  (footprint "data-center-rdimm-ddr4-tester-footprints:C_0402_1005Metric" (layer "B.Cu")
    (at 152.786328 95.520008 -90)
    (descr "Capacitor SMD 0402")
    (tags "capacitor SMD 0402")
    (property "Author" "Antmicro")
    (property "Dielectric" "X7R")
    (property "License" "Apache-2.0")
    (property "MPN" "GRM155R71H103KA88D")
    (property "Manufacturer" "Murata")
    (property "Sheetfile" "ethernet.kicad_sch")
    (property "Sheetname" "Ethernet")
    (property "Val" "10n")
    (property "Voltage" "50V")
    (property "ki_description" " ")
    (attr smd)
    (fp_text reference "C136" (at -1.400008 0.516328 90) (layer "B.SilkS")
        (effects (font (size 0.7 0.7) (thickness 0.15)) (justify left bottom mirror))
    )
    (fp_text value "C_10n_0402" (at 0 -1.4 90) (layer "B.Fab") hide
        (effects (font (size 0.7 0.7) (thickness 0.15)) (justify left bottom mirror))
    )
    (fp_text user "${REFERENCE}" (at -0.932 -3.168 90) (layer "B.Fab") hide
        (effects (font (size 0.7 0.7) (thickness 0.15)) (justify left bottom mirror))
    )
    (fp_text user "Author: Antmicro" (at -0.932 -4.17 90) (layer "B.Fab") hide
        (effects (font (size 0.7 0.7) (thickness 0.15)) (justify left bottom mirror))
    )
    (fp_text user "License: Apache-2.0" (at -0.932 -5.17 90) (layer "B.Fab") hide
        (effects (font (size 0.7 0.7) (thickness 0.15)) (justify left bottom mirror))
    )
    (fp_rect (start -0.94 0.47) (end 0.94 -0.47)
      (stroke (width 0.05) (type solid)) (fill none) (layer "B.CrtYd"))
    (fp_rect (start -0.499 0.249) (end 0.499 -0.249)
      (stroke (width 0.15) (type solid)) (fill none) (layer "B.Fab"))
    (pad "1" smd roundrect (at -0.484 0 270) (size 0.59 0.64) (layers "B.Cu" "B.Paste" "B.Mask") (roundrect_rratio 0.25)
      (net 143 "3V3_SYS") (pintype "passive"))
    (pad "2" smd roundrect (at 0.484 0 270) (size 0.59 0.64) (layers "B.Cu" "B.Paste" "B.Mask") (roundrect_rratio 0.25)
      (net 9 "GND") (pintype "passive"))
  )

  (footprint "data-center-rdimm-ddr4-tester-footprints:C_0402_1005Metric" (layer "B.Cu")
    (at 161.9 101.2 -90)
    (descr "Capacitor SMD 0402")
    (tags "capacitor SMD 0402")
    (property "Author" "Antmicro")
    (property "Dielectric" "")
    (property "License" "Apache-2.0")
    (property "MPN" "GRM155R61A475MEAAD")
    (property "Manufacturer" "Murata")
    (property "Sheetfile" "ethernet.kicad_sch")
    (property "Sheetname" "Ethernet")
    (property "Val" "4u7")
    (property "Voltage" "")
    (property "ki_description" " ")
    (attr smd)
    (fp_text reference "C137" (at -0.55 1.57 90) (layer "B.SilkS")
        (effects (font (size 0.7 0.7) (thickness 0.15)) (justify left bottom mirror))
    )
    (fp_text value "C_4u7_0402" (at 0 -1.4 90) (layer "B.Fab") hide
        (effects (font (size 0.7 0.7) (thickness 0.15)) (justify left bottom mirror))
    )
    (fp_text user "License: Apache-2.0" (at -0.932 -5.17 90) (layer "B.Fab") hide
        (effects (font (size 0.7 0.7) (thickness 0.15)) (justify left bottom mirror))
    )
    (fp_text user "${REFERENCE}" (at -0.932 -3.168 90) (layer "B.Fab") hide
        (effects (font (size 0.7 0.7) (thickness 0.15)) (justify left bottom mirror))
    )
    (fp_text user "Author: Antmicro" (at -0.932 -4.17 90) (layer "B.Fab") hide
        (effects (font (size 0.7 0.7) (thickness 0.15)) (justify left bottom mirror))
    )
    (fp_rect (start -0.94 0.47) (end 0.94 -0.47)
      (stroke (width 0.05) (type solid)) (fill none) (layer "B.CrtYd"))
    (fp_rect (start -0.499 0.249) (end 0.499 -0.249)
      (stroke (width 0.15) (type solid)) (fill none) (layer "B.Fab"))
    (pad "1" smd roundrect (at -0.484 0 270) (size 0.59 0.64) (layers "B.Cu" "B.Paste" "B.Mask") (roundrect_rratio 0.25)
      (net 179 "/Ethernet/AVDDH") (pintype "passive"))
    (pad "2" smd roundrect (at 0.484 0 270) (size 0.59 0.64) (layers "B.Cu" "B.Paste" "B.Mask") (roundrect_rratio 0.25)
      (net 9 "GND") (pintype "passive"))
  )

  (footprint "data-center-rdimm-ddr4-tester-footprints:C_0402_1005Metric" (layer "B.Cu")
    (at 158.486328 93.020008 -90)
    (descr "Capacitor SMD 0402")
    (tags "capacitor SMD 0402")
    (property "Author" "Antmicro")
    (property "Dielectric" "X7R")
    (property "License" "Apache-2.0")
    (property "MPN" "GRM155R71H103KA88D")
    (property "Manufacturer" "Murata")
    (property "Sheetfile" "ethernet.kicad_sch")
    (property "Sheetname" "Ethernet")
    (property "Val" "10n")
    (property "Voltage" "50V")
    (property "ki_description" " ")
    (attr smd)
    (fp_text reference "C138" (at -1.449008 -6.503672 90) (layer "B.SilkS")
        (effects (font (size 0.7 0.7) (thickness 0.15)) (justify left bottom mirror))
    )
    (fp_text value "C_10n_0402" (at 0 -1.4 90) (layer "B.Fab") hide
        (effects (font (size 0.7 0.7) (thickness 0.15)) (justify left bottom mirror))
    )
    (fp_text user "License: Apache-2.0" (at -0.932 -5.17 90) (layer "B.Fab") hide
        (effects (font (size 0.7 0.7) (thickness 0.15)) (justify left bottom mirror))
    )
    (fp_text user "${REFERENCE}" (at -0.932 -3.168 90) (layer "B.Fab") hide
        (effects (font (size 0.7 0.7) (thickness 0.15)) (justify left bottom mirror))
    )
    (fp_text user "Author: Antmicro" (at -0.932 -4.17 90) (layer "B.Fab") hide
        (effects (font (size 0.7 0.7) (thickness 0.15)) (justify left bottom mirror))
    )
    (fp_rect (start -0.94 0.47) (end 0.94 -0.47)
      (stroke (width 0.05) (type solid)) (fill none) (layer "B.CrtYd"))
    (fp_rect (start -0.499 0.249) (end 0.499 -0.249)
      (stroke (width 0.15) (type solid)) (fill none) (layer "B.Fab"))
    (pad "1" smd roundrect (at -0.484 0 270) (size 0.59 0.64) (layers "B.Cu" "B.Paste" "B.Mask") (roundrect_rratio 0.25)
      (net 306 "1V2_SYS") (pintype "passive"))
    (pad "2" smd roundrect (at 0.484 0 270) (size 0.59 0.64) (layers "B.Cu" "B.Paste" "B.Mask") (roundrect_rratio 0.25)
      (net 9 "GND") (pintype "passive"))
  )

  (footprint "data-center-rdimm-ddr4-tester-footprints:C_0402_1005Metric" (layer "B.Cu")
    (at 162.9 101.2 -90)
    (descr "Capacitor SMD 0402")
    (tags "capacitor SMD 0402")
    (property "Author" "Antmicro")
    (property "Dielectric" "")
    (property "License" "Apache-2.0")
    (property "MPN" "GRM155R61A475MEAAD")
    (property "Manufacturer" "Murata")
    (property "Sheetfile" "ethernet.kicad_sch")
    (property "Sheetname" "Ethernet")
    (property "Val" "4u7")
    (property "Voltage" "")
    (property "ki_description" " ")
    (attr smd)
    (fp_text reference "C140" (at -0.55 1.57 90) (layer "B.SilkS")
        (effects (font (size 0.7 0.7) (thickness 0.15)) (justify left bottom mirror))
    )
    (fp_text value "C_4u7_0402" (at 0 -1.4 90) (layer "B.Fab") hide
        (effects (font (size 0.7 0.7) (thickness 0.15)) (justify left bottom mirror))
    )
    (fp_text user "License: Apache-2.0" (at -0.932 -5.17 90) (layer "B.Fab") hide
        (effects (font (size 0.7 0.7) (thickness 0.15)) (justify left bottom mirror))
    )
    (fp_text user "Author: Antmicro" (at -0.932 -4.17 90) (layer "B.Fab") hide
        (effects (font (size 0.7 0.7) (thickness 0.15)) (justify left bottom mirror))
    )
    (fp_text user "${REFERENCE}" (at -0.932 -3.168 90) (layer "B.Fab") hide
        (effects (font (size 0.7 0.7) (thickness 0.15)) (justify left bottom mirror))
    )
    (fp_rect (start -0.94 0.47) (end 0.94 -0.47)
      (stroke (width 0.05) (type solid)) (fill none) (layer "B.CrtYd"))
    (fp_rect (start -0.499 0.249) (end 0.499 -0.249)
      (stroke (width 0.15) (type solid)) (fill none) (layer "B.Fab"))
    (pad "1" smd roundrect (at -0.484 0 270) (size 0.59 0.64) (layers "B.Cu" "B.Paste" "B.Mask") (roundrect_rratio 0.25)
      (net 179 "/Ethernet/AVDDH") (pintype "passive"))
    (pad "2" smd roundrect (at 0.484 0 270) (size 0.59 0.64) (layers "B.Cu" "B.Paste" "B.Mask") (roundrect_rratio 0.25)
      (net 9 "GND") (pintype "passive"))
  )

  (footprint "data-center-rdimm-ddr4-tester-footprints:C_0402_1005Metric" (layer "B.Cu")
    (at 160.686328 93.020008 -90)
    (descr "Capacitor SMD 0402")
    (tags "capacitor SMD 0402")
    (property "Author" "Antmicro")
    (property "Dielectric" "X7R")
    (property "License" "Apache-2.0")
    (property "MPN" "GRM155R71H103KA88D")
    (property "Manufacturer" "Murata")
    (property "Sheetfile" "ethernet.kicad_sch")
    (property "Sheetname" "Ethernet")
    (property "Val" "10n")
    (property "Voltage" "50V")
    (property "ki_description" " ")
    (attr smd)
    (fp_text reference "C141" (at -1.449008 -6.503672 90) (layer "B.SilkS")
        (effects (font (size 0.7 0.7) (thickness 0.15)) (justify left bottom mirror))
    )
    (fp_text value "C_10n_0402" (at 0 -1.4 90) (layer "B.Fab") hide
        (effects (font (size 0.7 0.7) (thickness 0.15)) (justify left bottom mirror))
    )
    (fp_text user "${REFERENCE}" (at -0.932 -3.168 90) (layer "B.Fab") hide
        (effects (font (size 0.7 0.7) (thickness 0.15)) (justify left bottom mirror))
    )
    (fp_text user "Author: Antmicro" (at -0.932 -4.17 90) (layer "B.Fab") hide
        (effects (font (size 0.7 0.7) (thickness 0.15)) (justify left bottom mirror))
    )
    (fp_text user "License: Apache-2.0" (at -0.932 -5.17 90) (layer "B.Fab") hide
        (effects (font (size 0.7 0.7) (thickness 0.15)) (justify left bottom mirror))
    )
    (fp_rect (start -0.94 0.47) (end 0.94 -0.47)
      (stroke (width 0.05) (type solid)) (fill none) (layer "B.CrtYd"))
    (fp_rect (start -0.499 0.249) (end 0.499 -0.249)
      (stroke (width 0.15) (type solid)) (fill none) (layer "B.Fab"))
    (pad "1" smd roundrect (at -0.484 0 270) (size 0.59 0.64) (layers "B.Cu" "B.Paste" "B.Mask") (roundrect_rratio 0.25)
      (net 306 "1V2_SYS") (pintype "passive"))
    (pad "2" smd roundrect (at 0.484 0 270) (size 0.59 0.64) (layers "B.Cu" "B.Paste" "B.Mask") (roundrect_rratio 0.25)
      (net 9 "GND") (pintype "passive"))
  )

  (footprint "data-center-rdimm-ddr4-tester-footprints:FB_0603_1608Metric" (layer "B.Cu")
    (at 153.786328 101.274306)
    (property "Author" "Antmicro")
    (property "License" "Apache-2.0")
    (property "MPN" "BLM18PG121SN1D")
    (property "Manufacturer" "Murata")
    (property "Sheetfile" "ethernet.kicad_sch")
    (property "Sheetname" "Ethernet")
    (property "ki_description" "Ferrite Beads WE-TMSB Suppression 240Ohm 200mA ")
    (property "ki_keywords" " Multilayer Suppression Beads ")
    (attr smd)
    (fp_text reference "FB1" (at -1.436328 0.375694 180) (layer "B.SilkS")
        (effects (font (size 0.7 0.7) (thickness 0.15)) (justify left bottom mirror))
    )
    (fp_text value "FB_120Z_2A_0603" (at 0 -1.7 180) (layer "B.Fab") hide
        (effects (font (size 0.7 0.7) (thickness 0.15)) (justify left bottom mirror))
    )
    (fp_text user "License: Apache-2.0" (at -1.653 -5.9 180) (layer "B.Fab") hide
        (effects (font (size 0.7 0.7) (thickness 0.15)) (justify left bottom mirror))
    )
    (fp_text user "Author: Antmicro" (at -1.653 -3.162 180) (layer "B.Fab") hide
        (effects (font (size 0.7 0.7) (thickness 0.15)) (justify left bottom mirror))
    )
    (fp_text user "${REFERENCE}" (at -1.653 -4.6 180) (layer "B.Fab") hide
        (effects (font (size 0.7 0.7) (thickness 0.15)) (justify left bottom mirror))
    )
    (fp_line (start -0.196 -0.406) (end 0.193 -0.406)
      (stroke (width 0.15) (type solid)) (layer "B.SilkS"))
    (fp_line (start -0.196 0.408) (end 0.193 0.408)
      (stroke (width 0.15) (type solid)) (layer "B.SilkS"))
    (fp_rect (start -1.3 0.6) (end 1.3 -0.6)
      (stroke (width 0.05) (type solid)) (fill none) (layer "B.CrtYd"))
    (fp_line (start -0.803 -0.406) (end -0.803 0.408)
      (stroke (width 0.15) (type solid)) (layer "B.Fab"))
    (fp_line (start 0.8 -0.406) (end -0.803 -0.406)
      (stroke (width 0.15) (type solid)) (layer "B.Fab"))
    (fp_line (start 0.8 0.408) (end -0.803 0.408)
      (stroke (width 0.15) (type solid)) (layer "B.Fab"))
    (fp_line (start 0.8 0.408) (end 0.8 -0.406)
      (stroke (width 0.15) (type solid)) (layer "B.Fab"))
    (pad "1" smd roundrect (at -0.891 0) (size 0.762 1.09) (layers "B.Cu" "B.Paste" "B.Mask") (roundrect_rratio 0.15)
      (net 143 "3V3_SYS") (pintype "passive"))
    (pad "2" smd roundrect (at 0.888 0) (size 0.762 1.09) (layers "B.Cu" "B.Paste" "B.Mask") (roundrect_rratio 0.15)
      (net 179 "/Ethernet/AVDDH") (pintype "passive"))
  )

  (footprint "data-center-rdimm-ddr4-tester-footprints:FB_0603_1608Metric" (layer "B.Cu")
    (at 158.9 98.275)
    (property "Author" "Antmicro")
    (property "License" "Apache-2.0")
    (property "MPN" "BLM18PG121SN1D")
    (property "Manufacturer" "Murata")
    (property "Sheetfile" "ethernet.kicad_sch")
    (property "Sheetname" "Ethernet")
    (property "ki_description" "Ferrite Beads WE-TMSB Suppression 240Ohm 200mA ")
    (property "ki_keywords" " Multilayer Suppression Beads ")
    (attr smd)
    (fp_text reference "FB3" (at 0.99 -0.795 180) (layer "B.SilkS")
        (effects (font (size 0.7 0.7) (thickness 0.15)) (justify left bottom mirror))
    )
    (fp_text value "FB_120Z_2A_0603" (at 0 -1.7 180) (layer "B.Fab") hide
        (effects (font (size 0.7 0.7) (thickness 0.15)) (justify left bottom mirror))
    )
    (fp_text user "License: Apache-2.0" (at -1.653 -5.9 180) (layer "B.Fab") hide
        (effects (font (size 0.7 0.7) (thickness 0.15)) (justify left bottom mirror))
    )
    (fp_text user "${REFERENCE}" (at -1.653 -4.6 180) (layer "B.Fab") hide
        (effects (font (size 0.7 0.7) (thickness 0.15)) (justify left bottom mirror))
    )
    (fp_text user "Author: Antmicro" (at -1.653 -3.162 180) (layer "B.Fab") hide
        (effects (font (size 0.7 0.7) (thickness 0.15)) (justify left bottom mirror))
    )
    (fp_line (start -0.196 -0.406) (end 0.193 -0.406)
      (stroke (width 0.15) (type solid)) (layer "B.SilkS"))
    (fp_line (start -0.196 0.408) (end 0.193 0.408)
      (stroke (width 0.15) (type solid)) (layer "B.SilkS"))
    (fp_rect (start -1.3 0.6) (end 1.3 -0.6)
      (stroke (width 0.05) (type solid)) (fill none) (layer "B.CrtYd"))
    (fp_line (start -0.803 -0.406) (end -0.803 0.408)
      (stroke (width 0.15) (type solid)) (layer "B.Fab"))
    (fp_line (start 0.8 -0.406) (end -0.803 -0.406)
      (stroke (width 0.15) (type solid)) (layer "B.Fab"))
    (fp_line (start 0.8 0.408) (end -0.803 0.408)
      (stroke (width 0.15) (type solid)) (layer "B.Fab"))
    (fp_line (start 0.8 0.408) (end 0.8 -0.406)
      (stroke (width 0.15) (type solid)) (layer "B.Fab"))
    (pad "1" smd roundrect (at -0.891 0) (size 0.762 1.09) (layers "B.Cu" "B.Paste" "B.Mask") (roundrect_rratio 0.15)
      (net 177 "/Ethernet/AVDDL") (pintype "passive"))
    (pad "2" smd roundrect (at 0.888 0) (size 0.762 1.09) (layers "B.Cu" "B.Paste" "B.Mask") (roundrect_rratio 0.15)
      (net 306 "1V2_SYS") (pintype "passive"))
  )

  (footprint "data-center-rdimm-ddr4-tester-footprints:R_0402_1005Metric" (layer "B.Cu")
    (at 166.423925 131.05 180)
    (descr "Resistor SMD 0402")
    (tags "resistor SMD 0402")
    (property "Author" "Antmicro")
    (property "License" "Apache-2.0")
    (property "MPN" "CR0402-FX-2200GLF")
    (property "Manufacturer" "Bourns")
    (property "Sheetfile" "ethernet.kicad_sch")
    (property "Sheetname" "Ethernet")
    (property "Tolerance" "1%")
    (property "Val" "220R")
    (property "ki_description" "220R resistor in 0402 package with 1% tolerance")
    (attr smd)
    (fp_text reference "R62" (at -1.096075 0.59) (layer "B.SilkS")
        (effects (font (size 0.7 0.7) (thickness 0.15)) (justify left bottom mirror))
    )
    (fp_text value "R_220R_0402" (at 0 -1.4) (layer "B.Fab") hide
        (effects (font (size 0.7 0.7) (thickness 0.15)) (justify left bottom mirror))
    )
    (fp_text user "${REFERENCE}" (at -0.95 -3.168) (layer "B.Fab") hide
        (effects (font (size 0.7 0.7) (thickness 0.15)) (justify left bottom mirror))
    )
    (fp_text user "License: Apache-2.0" (at -0.95 -5.169) (layer "B.Fab") hide
        (effects (font (size 0.7 0.7) (thickness 0.15)) (justify left bottom mirror))
    )
    (fp_text user "Author: Antmicro" (at -0.95 -4.169) (layer "B.Fab") hide
        (effects (font (size 0.7 0.7) (thickness 0.15)) (justify left bottom mirror))
    )
    (fp_rect (start -0.93 0.47) (end 0.93 -0.47)
      (stroke (width 0.05) (type solid)) (fill none) (layer "B.CrtYd"))
    (fp_rect (start -0.5 0.25) (end 0.5 -0.25)
      (stroke (width 0.15) (type solid)) (fill none) (layer "B.Fab"))
    (pad "1" smd roundrect (at -0.485 0 180) (size 0.59 0.64) (layers "B.Cu" "B.Paste" "B.Mask") (roundrect_rratio 0.25)
      (net 113 "Net-(J2-LED_YEL+)") (pintype "passive"))
    (pad "2" smd roundrect (at 0.485 0 180) (size 0.59 0.64) (layers "B.Cu" "B.Paste" "B.Mask") (roundrect_rratio 0.25)
      (net 143 "3V3_SYS") (pintype "passive"))
  )

  (footprint "data-center-rdimm-ddr4-tester-footprints:R_0402_1005Metric" (layer "B.Cu")
    (at 156.072849 131.076396 180)
    (descr "Resistor SMD 0402")
    (tags "resistor SMD 0402")
    (property "Author" "Antmicro")
    (property "License" "Apache-2.0")
    (property "MPN" "CR0402-FX-2200GLF")
    (property "Manufacturer" "Bourns")
    (property "Sheetfile" "ethernet.kicad_sch")
    (property "Sheetname" "Ethernet")
    (property "Tolerance" "1%")
    (property "Val" "220R")
    (property "ki_description" "220R resistor in 0402 package with 1% tolerance")
    (attr smd)
    (fp_text reference "R67" (at -0.957151 0.596396) (layer "B.SilkS")
        (effects (font (size 0.7 0.7) (thickness 0.15)) (justify left bottom mirror))
    )
    (fp_text value "R_220R_0402" (at 0 -1.4) (layer "B.Fab") hide
        (effects (font (size 0.7 0.7) (thickness 0.15)) (justify left bottom mirror))
    )
    (fp_text user "Author: Antmicro" (at -0.95 -4.169) (layer "B.Fab") hide
        (effects (font (size 0.7 0.7) (thickness 0.15)) (justify left bottom mirror))
    )
    (fp_text user "${REFERENCE}" (at -0.95 -3.168) (layer "B.Fab") hide
        (effects (font (size 0.7 0.7) (thickness 0.15)) (justify left bottom mirror))
    )
    (fp_text user "License: Apache-2.0" (at -0.95 -5.169) (layer "B.Fab") hide
        (effects (font (size 0.7 0.7) (thickness 0.15)) (justify left bottom mirror))
    )
    (fp_rect (start -0.93 0.47) (end 0.93 -0.47)
      (stroke (width 0.05) (type solid)) (fill none) (layer "B.CrtYd"))
    (fp_rect (start -0.5 0.25) (end 0.5 -0.25)
      (stroke (width 0.15) (type solid)) (fill none) (layer "B.Fab"))
    (pad "1" smd roundrect (at -0.485 0 180) (size 0.59 0.64) (layers "B.Cu" "B.Paste" "B.Mask") (roundrect_rratio 0.25)
      (net 112 "Net-(J2-LED_GRN+)") (pintype "passive"))
    (pad "2" smd roundrect (at 0.485 0 180) (size 0.59 0.64) (layers "B.Cu" "B.Paste" "B.Mask") (roundrect_rratio 0.25)
      (net 143 "3V3_SYS") (pintype "passive"))
  )

  (footprint "data-center-rdimm-ddr4-tester-footprints:R_0402_1005Metric" (layer "B.Cu")
    (at 157.671328 88.645008 -90)
    (descr "Resistor SMD 0402")
    (tags "resistor SMD 0402")
    (property "Author" "Antmicro")
    (property "License" "Apache-2.0")
    (property "MPN" "CR0402-FX-2201GLF")
    (property "Manufacturer" "Bourns")
    (property "Sheetfile" "ethernet.kicad_sch")
    (property "Sheetname" "Ethernet")
    (property "Tolerance" "1%")
    (property "Val" "2k2")
    (property "ki_description" "2k2 resistor in 0402 package with 1% tolerance")
    (attr smd)
    (fp_text reference "R77" (at -1.165008 -7.958672 90) (layer "B.SilkS")
        (effects (font (size 0.7 0.7) (thickness 0.15)) (justify left bottom mirror))
    )
    (fp_text value "R_2k2_0402" (at 0 -1.4 90) (layer "B.Fab") hide
        (effects (font (size 0.7 0.7) (thickness 0.15)) (justify left bottom mirror))
    )
    (fp_text user "License: Apache-2.0" (at -0.95 -5.169 90) (layer "B.Fab") hide
        (effects (font (size 0.7 0.7) (thickness 0.15)) (justify left bottom mirror))
    )
    (fp_text user "${REFERENCE}" (at -0.95 -3.168 90) (layer "B.Fab") hide
        (effects (font (size 0.7 0.7) (thickness 0.15)) (justify left bottom mirror))
    )
    (fp_text user "Author: Antmicro" (at -0.95 -4.169 90) (layer "B.Fab") hide
        (effects (font (size 0.7 0.7) (thickness 0.15)) (justify left bottom mirror))
    )
    (fp_rect (start -0.93 0.47) (end 0.93 -0.47)
      (stroke (width 0.05) (type solid)) (fill none) (layer "B.CrtYd"))
    (fp_rect (start -0.5 0.25) (end 0.5 -0.25)
      (stroke (width 0.15) (type solid)) (fill none) (layer "B.Fab"))
    (pad "1" smd roundrect (at -0.485 0 270) (size 0.59 0.64) (layers "B.Cu" "B.Paste" "B.Mask") (roundrect_rratio 0.25)
      (net 26 "ETH_RXD0") (pintype "passive"))
    (pad "2" smd roundrect (at 0.485 0 270) (size 0.59 0.64) (layers "B.Cu" "B.Paste" "B.Mask") (roundrect_rratio 0.25)
      (net 9 "GND") (pintype "passive"))
  )

  (footprint "data-center-rdimm-ddr4-tester-footprints:R_0402_1005Metric" (layer "B.Cu")
    (at 153.886328 92.520008)
    (descr "Resistor SMD 0402")
    (tags "resistor SMD 0402")
    (property "Author" "Antmicro")
    (property "License" "Apache-2.0")
    (property "MPN" "CR0402-FX-1001GLF")
    (property "Manufacturer" "Bourns")
    (property "Sheetfile" "ethernet.kicad_sch")
    (property "Sheetname" "Ethernet")
    (property "Tolerance" "1%")
    (property "Val" "1k")
    (property "ki_description" "1k resistor in 0402 package with 1% tolerance")
    (attr smd)
    (fp_text reference "R78" (at -0.946328 0.399992 180) (layer "B.SilkS")
        (effects (font (size 0.7 0.7) (thickness 0.15)) (justify left bottom mirror))
    )
    (fp_text value "R_1k_0402" (at 0 -1.4 180) (layer "B.Fab") hide
        (effects (font (size 0.7 0.7) (thickness 0.15)) (justify left bottom mirror))
    )
    (fp_text user "License: Apache-2.0" (at -0.95 -5.169 180) (layer "B.Fab") hide
        (effects (font (size 0.7 0.7) (thickness 0.15)) (justify left bottom mirror))
    )
    (fp_text user "Author: Antmicro" (at -0.95 -4.169 180) (layer "B.Fab") hide
        (effects (font (size 0.7 0.7) (thickness 0.15)) (justify left bottom mirror))
    )
    (fp_text user "${REFERENCE}" (at -0.95 -3.168 180) (layer "B.Fab") hide
        (effects (font (size 0.7 0.7) (thickness 0.15)) (justify left bottom mirror))
    )
    (fp_rect (start -0.93 0.47) (end 0.93 -0.47)
      (stroke (width 0.05) (type solid)) (fill none) (layer "B.CrtYd"))
    (fp_rect (start -0.5 0.25) (end 0.5 -0.25)
      (stroke (width 0.15) (type solid)) (fill none) (layer "B.Fab"))
    (pad "1" smd roundrect (at -0.485 0) (size 0.59 0.64) (layers "B.Cu" "B.Paste" "B.Mask") (roundrect_rratio 0.25)
      (net 29 "ETH_MDIO") (pintype "passive"))
    (pad "2" smd roundrect (at 0.485 0) (size 0.59 0.64) (layers "B.Cu" "B.Paste" "B.Mask") (roundrect_rratio 0.25)
      (net 143 "3V3_SYS") (pintype "passive"))
  )

  (footprint "data-center-rdimm-ddr4-tester-footprints:R_0402_1005Metric" (layer "B.Cu")
    (at 159.636328 89.580008 -90)
    (descr "Resistor SMD 0402")
    (tags "resistor SMD 0402")
    (property "Author" "Antmicro")
    (property "DNP" "DNP")
    (property "License" "Apache-2.0")
    (property "MPN" "CR0402-FX-2201GLF")
    (property "Manufacturer" "Bourns")
    (property "Sheetfile" "ethernet.kicad_sch")
    (property "Sheetname" "Ethernet")
    (property "Tolerance" "1%")
    (property "Val" "2k2")
    (property "dnp" "")
    (property "exclude_from_bom" "")
    (property "ki_description" "2k2 resistor in 0402 package with 1% tolerance")
    (attr exclude_from_pos_files exclude_from_bom)
    (fp_text reference "R90" (at -1.165008 -7.958672 90) (layer "B.SilkS")
        (effects (font (size 0.7 0.7) (thickness 0.15)) (justify left bottom mirror))
    )
    (fp_text value "R_2k2_0402" (at 0 -1.4 90) (layer "B.Fab") hide
        (effects (font (size 0.7 0.7) (thickness 0.15)) (justify left bottom mirror))
    )
    (fp_text user "Author: Antmicro" (at -0.95 -4.169 90) (layer "B.Fab") hide
        (effects (font (size 0.7 0.7) (thickness 0.15)) (justify left bottom mirror))
    )
    (fp_text user "License: Apache-2.0" (at -0.95 -5.169 90) (layer "B.Fab") hide
        (effects (font (size 0.7 0.7) (thickness 0.15)) (justify left bottom mirror))
    )
    (fp_text user "${REFERENCE}" (at -0.95 -3.168 90) (layer "B.Fab") hide
        (effects (font (size 0.7 0.7) (thickness 0.15)) (justify left bottom mirror))
    )
    (fp_rect (start -0.93 0.47) (end 0.93 -0.47)
      (stroke (width 0.05) (type solid)) (fill none) (layer "B.CrtYd"))
    (fp_rect (start -0.5 0.25) (end 0.5 -0.25)
      (stroke (width 0.15) (type solid)) (fill none) (layer "B.Fab"))
    (pad "1" smd roundrect (at -0.485 0 270) (size 0.59 0.64) (layers "B.Cu" "B.Paste" "B.Mask") (roundrect_rratio 0.25)
      (net 41 "ETH_RXD2") (pintype "passive"))
    (pad "2" smd roundrect (at 0.485 0 270) (size 0.59 0.64) (layers "B.Cu" "B.Paste" "B.Mask") (roundrect_rratio 0.25)
      (net 9 "GND") (pintype "passive"))
  )

  (footprint "data-center-rdimm-ddr4-tester-footprints:R_0402_1005Metric" (layer "B.Cu")
    (at 158.186328 90.460008)
    (descr "Resistor SMD 0402")
    (tags "resistor SMD 0402")
    (property "Author" "Antmicro")
    (property "License" "Apache-2.0")
    (property "MPN" "CR0402-FX-2201GLF")
    (property "Manufacturer" "Bourns")
    (property "Sheetfile" "ethernet.kicad_sch")
    (property "Sheetname" "Ethernet")
    (property "Tolerance" "1%")
    (property "Val" "2k2")
    (property "ki_description" "2k2 resistor in 0402 package with 1% tolerance")
    (attr smd)
    (fp_text reference "R92" (at 8.413672 0.379992 180) (layer "B.SilkS")
        (effects (font (size 0.7 0.7) (thickness 0.15)) (justify left bottom mirror))
    )
    (fp_text value "R_2k2_0402" (at 0 -1.4 180) (layer "B.Fab") hide
        (effects (font (size 0.7 0.7) (thickness 0.15)) (justify left bottom mirror))
    )
    (fp_text user "${REFERENCE}" (at -0.95 -3.168 180) (layer "B.Fab") hide
        (effects (font (size 0.7 0.7) (thickness 0.15)) (justify left bottom mirror))
    )
    (fp_text user "Author: Antmicro" (at -0.95 -4.169 180) (layer "B.Fab") hide
        (effects (font (size 0.7 0.7) (thickness 0.15)) (justify left bottom mirror))
    )
    (fp_text user "License: Apache-2.0" (at -0.95 -5.169 180) (layer "B.Fab") hide
        (effects (font (size 0.7 0.7) (thickness 0.15)) (justify left bottom mirror))
    )
    (fp_rect (start -0.93 0.47) (end 0.93 -0.47)
      (stroke (width 0.05) (type solid)) (fill none) (layer "B.CrtYd"))
    (fp_rect (start -0.5 0.25) (end 0.5 -0.25)
      (stroke (width 0.15) (type solid)) (fill none) (layer "B.Fab"))
    (pad "1" smd roundrect (at -0.485 0) (size 0.59 0.64) (layers "B.Cu" "B.Paste" "B.Mask") (roundrect_rratio 0.25)
      (net 38 "ETH_RX_DV") (pintype "passive"))
    (pad "2" smd roundrect (at 0.485 0) (size 0.59 0.64) (layers "B.Cu" "B.Paste" "B.Mask") (roundrect_rratio 0.25)
      (net 9 "GND") (pintype "passive"))
  )

  (footprint "data-center-rdimm-ddr4-tester-footprints:R_0402_1005Metric" (layer "B.Cu")
    (at 156.186328 87.810008 -90)
    (descr "Resistor SMD 0402")
    (tags "resistor SMD 0402")
    (property "Author" "Antmicro")
    (property "License" "Apache-2.0")
    (property "MPN" "CR0402-FX-2201GLF")
    (property "Manufacturer" "Bourns")
    (property "Sheetfile" "ethernet.kicad_sch")
    (property "Sheetname" "Ethernet")
    (property "Tolerance" "1%")
    (property "Val" "2k2")
    (property "ki_description" "2k2 resistor in 0402 package with 1% tolerance")
    (attr smd)
    (fp_text reference "R93" (at -1.130008 -8.063672 90) (layer "B.SilkS")
        (effects (font (size 0.7 0.7) (thickness 0.15)) (justify left bottom mirror))
    )
    (fp_text value "R_2k2_0402" (at 0 -1.4 90) (layer "B.Fab") hide
        (effects (font (size 0.7 0.7) (thickness 0.15)) (justify left bottom mirror))
    )
    (fp_text user "${REFERENCE}" (at -0.95 -3.168 90) (layer "B.Fab") hide
        (effects (font (size 0.7 0.7) (thickness 0.15)) (justify left bottom mirror))
    )
    (fp_text user "License: Apache-2.0" (at -0.95 -5.169 90) (layer "B.Fab") hide
        (effects (font (size 0.7 0.7) (thickness 0.15)) (justify left bottom mirror))
    )
    (fp_text user "Author: Antmicro" (at -0.95 -4.169 90) (layer "B.Fab") hide
        (effects (font (size 0.7 0.7) (thickness 0.15)) (justify left bottom mirror))
    )
    (fp_rect (start -0.93 0.47) (end 0.93 -0.47)
      (stroke (width 0.05) (type solid)) (fill none) (layer "B.CrtYd"))
    (fp_rect (start -0.5 0.25) (end 0.5 -0.25)
      (stroke (width 0.15) (type solid)) (fill none) (layer "B.Fab"))
    (pad "1" smd roundrect (at -0.485 0 270) (size 0.59 0.64) (layers "B.Cu" "B.Paste" "B.Mask") (roundrect_rratio 0.25)
      (net 40 "ETH_RX_CLK") (pintype "passive"))
    (pad "2" smd roundrect (at 0.485 0 270) (size 0.59 0.64) (layers "B.Cu" "B.Paste" "B.Mask") (roundrect_rratio 0.25)
      (net 9 "GND") (pintype "passive"))
  )

  (footprint "data-center-rdimm-ddr4-tester-footprints:R_0402_1005Metric" (layer "B.Cu")
    (at 156.376328 94.660008)
    (descr "Resistor SMD 0402")
    (tags "resistor SMD 0402")
    (property "Author" "Antmicro")
    (property "DNP" "DNP")
    (property "License" "Apache-2.0")
    (property "MPN" "CR0402-FX-2201GLF")
    (property "Manufacturer" "Bourns")
    (property "Sheetfile" "ethernet.kicad_sch")
    (property "Sheetname" "Ethernet")
    (property "Tolerance" "1%")
    (property "Val" "2k2")
    (property "dnp" "")
    (property "exclude_from_bom" "")
    (property "ki_description" "2k2 resistor in 0402 package with 1% tolerance")
    (attr exclude_from_pos_files exclude_from_bom)
    (fp_text reference "R94" (at 2.993672 0.349992 180) (layer "B.SilkS")
        (effects (font (size 0.7 0.7) (thickness 0.15)) (justify left bottom mirror))
    )
    (fp_text value "R_2k2_0402" (at 0 -1.4 180) (layer "B.Fab") hide
        (effects (font (size 0.7 0.7) (thickness 0.15)) (justify left bottom mirror))
    )
    (fp_text user "License: Apache-2.0" (at -0.95 -5.169 180) (layer "B.Fab") hide
        (effects (font (size 0.7 0.7) (thickness 0.15)) (justify left bottom mirror))
    )
    (fp_text user "Author: Antmicro" (at -0.95 -4.169 180) (layer "B.Fab") hide
        (effects (font (size 0.7 0.7) (thickness 0.15)) (justify left bottom mirror))
    )
    (fp_text user "${REFERENCE}" (at -0.95 -3.168 180) (layer "B.Fab") hide
        (effects (font (size 0.7 0.7) (thickness 0.15)) (justify left bottom mirror))
    )
    (fp_rect (start -0.93 0.47) (end 0.93 -0.47)
      (stroke (width 0.05) (type solid)) (fill none) (layer "B.CrtYd"))
    (fp_rect (start -0.5 0.25) (end 0.5 -0.25)
      (stroke (width 0.15) (type solid)) (fill none) (layer "B.Fab"))
    (pad "1" smd roundrect (at -0.485 0) (size 0.59 0.64) (layers "B.Cu" "B.Paste" "B.Mask") (roundrect_rratio 0.25)
      (net 30 "ETH_REF_CLK") (pintype "passive"))
    (pad "2" smd roundrect (at 0.485 0) (size 0.59 0.64) (layers "B.Cu" "B.Paste" "B.Mask") (roundrect_rratio 0.25)
      (net 9 "GND") (pintype "passive"))
  )

  (footprint "data-center-rdimm-ddr4-tester-footprints:R_0402_1005Metric" (layer "B.Cu")
    (at 166.306328 99.480008 -90)
    (descr "Resistor SMD 0402")
    (tags "resistor SMD 0402")
    (property "Author" "Antmicro")
    (property "DNP" "DNP")
    (property "License" "Apache-2.0")
    (property "MPN" "CR0402-FX-2201GLF")
    (property "Manufacturer" "Bourns")
    (property "Sheetfile" "ethernet.kicad_sch")
    (property "Sheetname" "Ethernet")
    (property "Tolerance" "1%")
    (property "Val" "2k2")
    (property "dnp" "")
    (property "exclude_from_bom" "")
    (property "ki_description" "2k2 resistor in 0402 package with 1% tolerance")
    (attr exclude_from_pos_files exclude_from_bom)
    (fp_text reference "R95" (at -1.070008 0.526328 90) (layer "B.SilkS")
        (effects (font (size 0.7 0.7) (thickness 0.15)) (justify left bottom mirror))
    )
    (fp_text value "R_2k2_0402" (at 0 -1.4 90) (layer "B.Fab") hide
        (effects (font (size 0.7 0.7) (thickness 0.15)) (justify left bottom mirror))
    )
    (fp_text user "${REFERENCE}" (at -0.95 -3.168 90) (layer "B.Fab") hide
        (effects (font (size 0.7 0.7) (thickness 0.15)) (justify left bottom mirror))
    )
    (fp_text user "License: Apache-2.0" (at -0.95 -5.169 90) (layer "B.Fab") hide
        (effects (font (size 0.7 0.7) (thickness 0.15)) (justify left bottom mirror))
    )
    (fp_text user "Author: Antmicro" (at -0.95 -4.169 90) (layer "B.Fab") hide
        (effects (font (size 0.7 0.7) (thickness 0.15)) (justify left bottom mirror))
    )
    (fp_rect (start -0.93 0.47) (end 0.93 -0.47)
      (stroke (width 0.05) (type solid)) (fill none) (layer "B.CrtYd"))
    (fp_rect (start -0.5 0.25) (end 0.5 -0.25)
      (stroke (width 0.15) (type solid)) (fill none) (layer "B.Fab"))
    (pad "1" smd roundrect (at -0.485 0 270) (size 0.59 0.64) (layers "B.Cu" "B.Paste" "B.Mask") (roundrect_rratio 0.25)
      (net 17 "LED_SPD") (pintype "passive"))
    (pad "2" smd roundrect (at 0.485 0 270) (size 0.59 0.64) (layers "B.Cu" "B.Paste" "B.Mask") (roundrect_rratio 0.25)
      (net 9 "GND") (pintype "passive"))
  )

  (footprint "data-center-rdimm-ddr4-tester-footprints:R_0402_1005Metric" (layer "B.Cu")
    (at 166.306328 95.070008 90)
    (descr "Resistor SMD 0402")
    (tags "resistor SMD 0402")
    (property "Author" "Antmicro")
    (property "DNP" "DNP")
    (property "License" "Apache-2.0")
    (property "MPN" "CR0402-FX-2201GLF")
    (property "Manufacturer" "Bourns")
    (property "Sheetfile" "ethernet.kicad_sch")
    (property "Sheetname" "Ethernet")
    (property "Tolerance" "1%")
    (property "Val" "2k2")
    (property "dnp" "")
    (property "exclude_from_bom" "")
    (property "ki_description" "2k2 resistor in 0402 package with 1% tolerance")
    (attr exclude_from_pos_files exclude_from_bom)
    (fp_text reference "R96" (at 0.830008 -0.586328 270) (layer "B.SilkS")
        (effects (font (size 0.7 0.7) (thickness 0.15)) (justify left bottom mirror))
    )
    (fp_text value "R_2k2_0402" (at 0 -1.4 270) (layer "B.Fab") hide
        (effects (font (size 0.7 0.7) (thickness 0.15)) (justify left bottom mirror))
    )
    (fp_text user "${REFERENCE}" (at -0.95 -3.168 270) (layer "B.Fab") hide
        (effects (font (size 0.7 0.7) (thickness 0.15)) (justify left bottom mirror))
    )
    (fp_text user "Author: Antmicro" (at -0.95 -4.169 270) (layer "B.Fab") hide
        (effects (font (size 0.7 0.7) (thickness 0.15)) (justify left bottom mirror))
    )
    (fp_text user "License: Apache-2.0" (at -0.95 -5.169 270) (layer "B.Fab") hide
        (effects (font (size 0.7 0.7) (thickness 0.15)) (justify left bottom mirror))
    )
    (fp_rect (start -0.93 0.47) (end 0.93 -0.47)
      (stroke (width 0.05) (type solid)) (fill none) (layer "B.CrtYd"))
    (fp_rect (start -0.5 0.25) (end 0.5 -0.25)
      (stroke (width 0.15) (type solid)) (fill none) (layer "B.Fab"))
    (pad "1" smd roundrect (at -0.485 0 90) (size 0.59 0.64) (layers "B.Cu" "B.Paste" "B.Mask") (roundrect_rratio 0.25)
      (net 16 "LED_LINK") (pintype "passive"))
    (pad "2" smd roundrect (at 0.485 0 90) (size 0.59 0.64) (layers "B.Cu" "B.Paste" "B.Mask") (roundrect_rratio 0.25)
      (net 9 "GND") (pintype "passive"))
  )

  (footprint "data-center-rdimm-ddr4-tester-footprints:R_0402_1005Metric" (layer "B.Cu")
    (at 237.65 126.065 -90)
    (descr "Resistor SMD 0402")
    (tags "resistor SMD 0402")
    (property "Author" "Antmicro")
    (property "License" "Apache-2.0")
    (property "MPN" "CR0402-FX-4701GLF")
    (property "Manufacturer" "Bourns")
    (property "Sheetfile" "config-spi.kicad_sch")
    (property "Sheetname" "Config SPI flash")
    (property "Tolerance" "1%")
    (property "Val" "4k7")
    (property "ki_description" "4k7 resistor in 0402 package with 1% tolerance")
    (attr smd)
    (fp_text reference "R28" (at -1.075 0.59 90) (layer "B.SilkS")
        (effects (font (size 0.7 0.7) (thickness 0.15)) (justify left bottom mirror))
    )
    (fp_text value "R_4k7_0402" (at 0 -1.4 90) (layer "B.Fab") hide
        (effects (font (size 0.7 0.7) (thickness 0.15)) (justify left bottom mirror))
    )
    (fp_text user "${REFERENCE}" (at -0.95 -3.168 90) (layer "B.Fab") hide
        (effects (font (size 0.7 0.7) (thickness 0.15)) (justify left bottom mirror))
    )
    (fp_text user "License: Apache-2.0" (at -0.95 -5.169 90) (layer "B.Fab") hide
        (effects (font (size 0.7 0.7) (thickness 0.15)) (justify left bottom mirror))
    )
    (fp_text user "Author: Antmicro" (at -0.95 -4.169 90) (layer "B.Fab") hide
        (effects (font (size 0.7 0.7) (thickness 0.15)) (justify left bottom mirror))
    )
    (fp_rect (start -0.93 0.47) (end 0.93 -0.47)
      (stroke (width 0.05) (type solid)) (fill none) (layer "B.CrtYd"))
    (fp_rect (start -0.5 0.25) (end 0.5 -0.25)
      (stroke (width 0.15) (type solid)) (fill none) (layer "B.Fab"))
    (pad "1" smd roundrect (at -0.485 0 270) (size 0.59 0.64) (layers "B.Cu" "B.Paste" "B.Mask") (roundrect_rratio 0.25)
      (net 143 "3V3_SYS") (pintype "passive"))
    (pad "2" smd roundrect (at 0.485 0 270) (size 0.59 0.64) (layers "B.Cu" "B.Paste" "B.Mask") (roundrect_rratio 0.25)
      (net 93 "INIT_B") (pintype "passive"))
  )

  (footprint "data-center-rdimm-ddr4-tester-footprints:R_0402_1005Metric" (layer "B.Cu")
    (at 241.5 97.8 180)
    (descr "Resistor SMD 0402")
    (tags "resistor SMD 0402")
    (property "Author" "Antmicro")
    (property "License" "Apache-2.0")
    (property "MPN" "CR0402-FX-3300GLF")
    (property "Manufacturer" "Bourns")
    (property "Sheetfile" "interfaces.kicad_sch")
    (property "Sheetname" "Interfaces")
    (property "Tolerance" "1%")
    (property "Val" "330R")
    (property "ki_description" "330R resistor in 0402 package with 1% tolerance")
    (attr smd)
    (fp_text reference "R50" (at -1.04 -1.27) (layer "B.SilkS")
        (effects (font (size 0.7 0.7) (thickness 0.15)) (justify left bottom mirror))
    )
    (fp_text value "R_330R_0402" (at 0 -1.4) (layer "B.Fab") hide
        (effects (font (size 0.7 0.7) (thickness 0.15)) (justify left bottom mirror))
    )
    (fp_text user "License: Apache-2.0" (at -0.95 -5.169) (layer "B.Fab") hide
        (effects (font (size 0.7 0.7) (thickness 0.15)) (justify left bottom mirror))
    )
    (fp_text user "${REFERENCE}" (at -0.95 -3.168) (layer "B.Fab") hide
        (effects (font (size 0.7 0.7) (thickness 0.15)) (justify left bottom mirror))
    )
    (fp_text user "Author: Antmicro" (at -0.95 -4.169) (layer "B.Fab") hide
        (effects (font (size 0.7 0.7) (thickness 0.15)) (justify left bottom mirror))
    )
    (fp_rect (start -0.93 0.47) (end 0.93 -0.47)
      (stroke (width 0.05) (type solid)) (fill none) (layer "B.CrtYd"))
    (fp_rect (start -0.5 0.25) (end 0.5 -0.25)
      (stroke (width 0.15) (type solid)) (fill none) (layer "B.Fab"))
    (pad "1" smd roundrect (at -0.485 0 180) (size 0.59 0.64) (layers "B.Cu" "B.Paste" "B.Mask") (roundrect_rratio 0.25)
      (net 63 "Net-(D5-Pad2)") (pintype "passive"))
    (pad "2" smd roundrect (at 0.485 0 180) (size 0.59 0.64) (layers "B.Cu" "B.Paste" "B.Mask") (roundrect_rratio 0.25)
      (net 574 "Net-(Q2-D)") (pintype "passive"))
  )

  (footprint "data-center-rdimm-ddr4-tester-footprints:R_0402_1005Metric" (layer "B.Cu")
    (at 241.5 92.6 180)
    (descr "Resistor SMD 0402")
    (tags "resistor SMD 0402")
    (property "Author" "Antmicro")
    (property "License" "Apache-2.0")
    (property "MPN" "CR0402-FX-3300GLF")
    (property "Manufacturer" "Bourns")
    (property "Sheetfile" "interfaces.kicad_sch")
    (property "Sheetname" "Interfaces")
    (property "Tolerance" "1%")
    (property "Val" "330R")
    (property "ki_description" "330R resistor in 0402 package with 1% tolerance")
    (attr smd)
    (fp_text reference "R51" (at -1.04 -1.27) (layer "B.SilkS")
        (effects (font (size 0.7 0.7) (thickness 0.15)) (justify left bottom mirror))
    )
    (fp_text value "R_330R_0402" (at 0 -1.4) (layer "B.Fab") hide
        (effects (font (size 0.7 0.7) (thickness 0.15)) (justify left bottom mirror))
    )
    (fp_text user "Author: Antmicro" (at -0.95 -4.169) (layer "B.Fab") hide
        (effects (font (size 0.7 0.7) (thickness 0.15)) (justify left bottom mirror))
    )
    (fp_text user "${REFERENCE}" (at -0.95 -3.168) (layer "B.Fab") hide
        (effects (font (size 0.7 0.7) (thickness 0.15)) (justify left bottom mirror))
    )
    (fp_text user "License: Apache-2.0" (at -0.95 -5.169) (layer "B.Fab") hide
        (effects (font (size 0.7 0.7) (thickness 0.15)) (justify left bottom mirror))
    )
    (fp_rect (start -0.93 0.47) (end 0.93 -0.47)
      (stroke (width 0.05) (type solid)) (fill none) (layer "B.CrtYd"))
    (fp_rect (start -0.5 0.25) (end 0.5 -0.25)
      (stroke (width 0.15) (type solid)) (fill none) (layer "B.Fab"))
    (pad "1" smd roundrect (at -0.485 0 180) (size 0.59 0.64) (layers "B.Cu" "B.Paste" "B.Mask") (roundrect_rratio 0.25)
      (net 64 "Net-(D6-Pad2)") (pintype "passive"))
    (pad "2" smd roundrect (at 0.485 0 180) (size 0.59 0.64) (layers "B.Cu" "B.Paste" "B.Mask") (roundrect_rratio 0.25)
      (net 575 "Net-(Q3-D)") (pintype "passive"))
  )

  (footprint "data-center-rdimm-ddr4-tester-footprints:R_0402_1005Metric" (layer "B.Cu")
    (at 241.5 95.35 180)
    (descr "Resistor SMD 0402")
    (tags "resistor SMD 0402")
    (property "Author" "Antmicro")
    (property "License" "Apache-2.0")
    (property "MPN" "CR0402-FX-3300GLF")
    (property "Manufacturer" "Bourns")
    (property "Sheetfile" "interfaces.kicad_sch")
    (property "Sheetname" "Interfaces")
    (property "Tolerance" "1%")
    (property "Val" "330R")
    (property "ki_description" "330R resistor in 0402 package with 1% tolerance")
    (attr smd)
    (fp_text reference "R52" (at -1.04 -1.27) (layer "B.SilkS")
        (effects (font (size 0.7 0.7) (thickness 0.15)) (justify left bottom mirror))
    )
    (fp_text value "R_330R_0402" (at 0 -1.4) (layer "B.Fab") hide
        (effects (font (size 0.7 0.7) (thickness 0.15)) (justify left bottom mirror))
    )
    (fp_text user "License: Apache-2.0" (at -0.95 -5.169) (layer "B.Fab") hide
        (effects (font (size 0.7 0.7) (thickness 0.15)) (justify left bottom mirror))
    )
    (fp_text user "Author: Antmicro" (at -0.95 -4.169) (layer "B.Fab") hide
        (effects (font (size 0.7 0.7) (thickness 0.15)) (justify left bottom mirror))
    )
    (fp_text user "${REFERENCE}" (at -0.95 -3.168) (layer "B.Fab") hide
        (effects (font (size 0.7 0.7) (thickness 0.15)) (justify left bottom mirror))
    )
    (fp_rect (start -0.93 0.47) (end 0.93 -0.47)
      (stroke (width 0.05) (type solid)) (fill none) (layer "B.CrtYd"))
    (fp_rect (start -0.5 0.25) (end 0.5 -0.25)
      (stroke (width 0.15) (type solid)) (fill none) (layer "B.Fab"))
    (pad "1" smd roundrect (at -0.485 0 180) (size 0.59 0.64) (layers "B.Cu" "B.Paste" "B.Mask") (roundrect_rratio 0.25)
      (net 65 "Net-(D7-Pad2)") (pintype "passive"))
    (pad "2" smd roundrect (at 0.485 0 180) (size 0.59 0.64) (layers "B.Cu" "B.Paste" "B.Mask") (roundrect_rratio 0.25)
      (net 576 "Net-(Q4-D)") (pintype "passive"))
  )

  (footprint "data-center-rdimm-ddr4-tester-footprints:R_0402_1005Metric" locked (layer "B.Cu")
    (at 241.5 89.9 180)
    (descr "Resistor SMD 0402")
    (tags "resistor SMD 0402")
    (property "Author" "Antmicro")
    (property "License" "Apache-2.0")
    (property "MPN" "CR0402-FX-3300GLF")
    (property "Manufacturer" "Bourns")
    (property "Sheetfile" "interfaces.kicad_sch")
    (property "Sheetname" "Interfaces")
    (property "Tolerance" "1%")
    (property "Val" "330R")
    (property "ki_description" "330R resistor in 0402 package with 1% tolerance")
    (attr smd)
    (fp_text reference "R53" (at -1.04 -1.27) (layer "B.SilkS")
        (effects (font (size 0.7 0.7) (thickness 0.15)) (justify left bottom mirror))
    )
    (fp_text value "R_330R_0402" (at 0 -1.4) (layer "B.Fab") hide
        (effects (font (size 0.7 0.7) (thickness 0.15)) (justify left bottom mirror))
    )
    (fp_text user "${REFERENCE}" (at -0.95 -3.168) (layer "B.Fab") hide
        (effects (font (size 0.7 0.7) (thickness 0.15)) (justify left bottom mirror))
    )
    (fp_text user "Author: Antmicro" (at -0.95 -4.169) (layer "B.Fab") hide
        (effects (font (size 0.7 0.7) (thickness 0.15)) (justify left bottom mirror))
    )
    (fp_text user "License: Apache-2.0" (at -0.95 -5.169) (layer "B.Fab") hide
        (effects (font (size 0.7 0.7) (thickness 0.15)) (justify left bottom mirror))
    )
    (fp_rect (start -0.93 0.47) (end 0.93 -0.47)
      (stroke (width 0.05) (type solid)) (fill none) (layer "B.CrtYd"))
    (fp_rect (start -0.5 0.25) (end 0.5 -0.25)
      (stroke (width 0.15) (type solid)) (fill none) (layer "B.Fab"))
    (pad "1" smd roundrect locked (at -0.485 0 180) (size 0.59 0.64) (layers "B.Cu" "B.Paste" "B.Mask") (roundrect_rratio 0.25)
      (net 66 "Net-(D8-Pad2)") (pintype "passive"))
    (pad "2" smd roundrect locked (at 0.485 0 180) (size 0.59 0.64) (layers "B.Cu" "B.Paste" "B.Mask") (roundrect_rratio 0.25)
      (net 577 "Net-(Q5-D)") (pintype "passive"))
  )

  (footprint "data-center-rdimm-ddr4-tester-footprints:R_0402_1005Metric" (layer "B.Cu")
    (at 241.5 84.5 180)
    (descr "Resistor SMD 0402")
    (tags "resistor SMD 0402")
    (property "Author" "Antmicro")
    (property "License" "Apache-2.0")
    (property "MPN" "CR0402-FX-3300GLF")
    (property "Manufacturer" "Bourns")
    (property "Sheetfile" "interfaces.kicad_sch")
    (property "Sheetname" "Interfaces")
    (property "Tolerance" "1%")
    (property "Val" "330R")
    (property "ki_description" "330R resistor in 0402 package with 1% tolerance")
    (attr smd)
    (fp_text reference "R54" (at -1.05 -1.36) (layer "B.SilkS")
        (effects (font (size 0.7 0.7) (thickness 0.15)) (justify left bottom mirror))
    )
    (fp_text value "R_330R_0402" (at 0 -1.4) (layer "B.Fab") hide
        (effects (font (size 0.7 0.7) (thickness 0.15)) (justify left bottom mirror))
    )
    (fp_text user "Author: Antmicro" (at -0.95 -4.169) (layer "B.Fab") hide
        (effects (font (size 0.7 0.7) (thickness 0.15)) (justify left bottom mirror))
    )
    (fp_text user "License: Apache-2.0" (at -0.95 -5.169) (layer "B.Fab") hide
        (effects (font (size 0.7 0.7) (thickness 0.15)) (justify left bottom mirror))
    )
    (fp_text user "${REFERENCE}" (at -0.95 -3.168) (layer "B.Fab") hide
        (effects (font (size 0.7 0.7) (thickness 0.15)) (justify left bottom mirror))
    )
    (fp_rect (start -0.93 0.47) (end 0.93 -0.47)
      (stroke (width 0.05) (type solid)) (fill none) (layer "B.CrtYd"))
    (fp_rect (start -0.5 0.25) (end 0.5 -0.25)
      (stroke (width 0.15) (type solid)) (fill none) (layer "B.Fab"))
    (pad "1" smd roundrect (at -0.485 0 180) (size 0.59 0.64) (layers "B.Cu" "B.Paste" "B.Mask") (roundrect_rratio 0.25)
      (net 78 "Net-(D9-Pad2)") (pintype "passive"))
    (pad "2" smd roundrect (at 0.485 0 180) (size 0.59 0.64) (layers "B.Cu" "B.Paste" "B.Mask") (roundrect_rratio 0.25)
      (net 578 "Net-(Q6-D)") (pintype "passive"))
  )

  (footprint "data-center-rdimm-ddr4-tester-footprints:SC70-3" (layer "B.Cu")
    (at 238.9 96.55)
    (property "Author" "Antmicro")
    (property "License" "Apache-2.0")
    (property "MPN" "BSS138PW")
    (property "Manufacturer" "Nexperia")
    (property "Sheetfile" "interfaces.kicad_sch")
    (property "Sheetname" "Interfaces")
    (property "ki_description" "60 V, 320 mA N-channel enhancement mode Trench MOSFET, SC-70-3 aka SOT-323 package")
    (property "ki_keywords" "n-channel enhancement mosfet sc70 sc-70 sot-323 sot323")
    (attr smd)
    (fp_text reference "Q2" (at -1.35 0.41 180) (layer "B.SilkS")
        (effects (font (size 0.7 0.7) (thickness 0.15)) (justify left bottom mirror))
    )
    (fp_text value "BSS138PW" (at 0 -2.3 180) (layer "B.Fab") hide
        (effects (font (size 0.7 0.7) (thickness 0.15)) (justify left bottom mirror))
    )
    (fp_text user "Author: Antmicro" (at -1.45 -5.782 180) (layer "B.Fab") hide
        (effects (font (size 0.7 0.7) (thickness 0.15)) (justify left bottom mirror))
    )
    (fp_text user "License: Apache-2.0" (at -1.45 -6.782 180) (layer "B.Fab") hide
        (effects (font (size 0.7 0.7) (thickness 0.15)) (justify left bottom mirror))
    )
    (fp_text user "${REFERENCE}" (at -1.45 -4.783 180) (layer "B.Fab") hide
        (effects (font (size 0.7 0.7) (thickness 0.15)) (justify left bottom mirror))
    )
    (fp_line (start -0.3 -1) (end 0.627 -1.001)
      (stroke (width 0.15) (type solid)) (layer "B.SilkS"))
    (fp_line (start -0.3 1) (end 0.627 0.999)
      (stroke (width 0.15) (type solid)) (layer "B.SilkS"))
    (fp_line (start 0.627 -0.6) (end 0.627 -1.001)
      (stroke (width 0.15) (type solid)) (layer "B.SilkS"))
    (fp_line (start 0.627 0.6) (end 0.627 0.999)
      (stroke (width 0.15) (type solid)) (layer "B.SilkS"))
    (fp_rect (start 1.4 -1.3) (end -1.4 1.3)
      (stroke (width 0.05) (type solid)) (fill none) (layer "B.CrtYd"))
    (fp_rect (start -0.623 0.999) (end 0.627 -1.001)
      (stroke (width 0.15) (type solid)) (fill none) (layer "B.Fab"))
    (pad "1" smd rect (at -0.95 0.65 270) (size 0.6 0.8) (layers "B.Cu" "B.Paste" "B.Mask")
      (net 67 "USR_LED1") (pinfunction "G") (pintype "bidirectional"))
    (pad "2" smd rect (at -0.95 -0.65 270) (size 0.6 0.8) (layers "B.Cu" "B.Paste" "B.Mask")
      (net 9 "GND") (pinfunction "S") (pintype "bidirectional"))
    (pad "3" smd rect (at 0.95 0 270) (size 0.6 0.8) (layers "B.Cu" "B.Paste" "B.Mask")
      (net 574 "Net-(Q2-D)") (pinfunction "D") (pintype "bidirectional"))
  )

  (footprint "data-center-rdimm-ddr4-tester-footprints:SC70-3" (layer "B.Cu")
    (at 238.9 91.2)
    (property "Author" "Antmicro")
    (property "License" "Apache-2.0")
    (property "MPN" "BSS138PW")
    (property "Manufacturer" "Nexperia")
    (property "Sheetfile" "interfaces.kicad_sch")
    (property "Sheetname" "Interfaces")
    (property "ki_description" "60 V, 320 mA N-channel enhancement mode Trench MOSFET, SC-70-3 aka SOT-323 package")
    (property "ki_keywords" "n-channel enhancement mosfet sc70 sc-70 sot-323 sot323")
    (attr smd)
    (fp_text reference "Q3" (at -1.35 0.41 180) (layer "B.SilkS")
        (effects (font (size 0.7 0.7) (thickness 0.15)) (justify left bottom mirror))
    )
    (fp_text value "BSS138PW" (at 0 -2.3 180) (layer "B.Fab") hide
        (effects (font (size 0.7 0.7) (thickness 0.15)) (justify left bottom mirror))
    )
    (fp_text user "License: Apache-2.0" (at -1.45 -6.782 180) (layer "B.Fab") hide
        (effects (font (size 0.7 0.7) (thickness 0.15)) (justify left bottom mirror))
    )
    (fp_text user "Author: Antmicro" (at -1.45 -5.782 180) (layer "B.Fab") hide
        (effects (font (size 0.7 0.7) (thickness 0.15)) (justify left bottom mirror))
    )
    (fp_text user "${REFERENCE}" (at -1.45 -4.783 180) (layer "B.Fab") hide
        (effects (font (size 0.7 0.7) (thickness 0.15)) (justify left bottom mirror))
    )
    (fp_line (start -0.3 -1) (end 0.627 -1.001)
      (stroke (width 0.15) (type solid)) (layer "B.SilkS"))
    (fp_line (start -0.3 1) (end 0.627 0.999)
      (stroke (width 0.15) (type solid)) (layer "B.SilkS"))
    (fp_line (start 0.627 -0.6) (end 0.627 -1.001)
      (stroke (width 0.15) (type solid)) (layer "B.SilkS"))
    (fp_line (start 0.627 0.6) (end 0.627 0.999)
      (stroke (width 0.15) (type solid)) (layer "B.SilkS"))
    (fp_rect (start 1.4 -1.3) (end -1.4 1.3)
      (stroke (width 0.05) (type solid)) (fill none) (layer "B.CrtYd"))
    (fp_rect (start -0.623 0.999) (end 0.627 -1.001)
      (stroke (width 0.15) (type solid)) (fill none) (layer "B.Fab"))
    (pad "1" smd rect (at -0.95 0.65 270) (size 0.6 0.8) (layers "B.Cu" "B.Paste" "B.Mask")
      (net 68 "USR_LED3") (pinfunction "G") (pintype "bidirectional"))
    (pad "2" smd rect (at -0.95 -0.65 270) (size 0.6 0.8) (layers "B.Cu" "B.Paste" "B.Mask")
      (net 9 "GND") (pinfunction "S") (pintype "bidirectional"))
    (pad "3" smd rect (at 0.95 0 270) (size 0.6 0.8) (layers "B.Cu" "B.Paste" "B.Mask")
      (net 575 "Net-(Q3-D)") (pinfunction "D") (pintype "bidirectional"))
  )

  (footprint "data-center-rdimm-ddr4-tester-footprints:SC70-3" (layer "B.Cu")
    (at 238.9 93.9)
    (property "Author" "Antmicro")
    (property "License" "Apache-2.0")
    (property "MPN" "BSS138PW")
    (property "Manufacturer" "Nexperia")
    (property "Sheetfile" "interfaces.kicad_sch")
    (property "Sheetname" "Interfaces")
    (property "ki_description" "60 V, 320 mA N-channel enhancement mode Trench MOSFET, SC-70-3 aka SOT-323 package")
    (property "ki_keywords" "n-channel enhancement mosfet sc70 sc-70 sot-323 sot323")
    (attr smd)
    (fp_text reference "Q4" (at -1.35 0.41 180) (layer "B.SilkS")
        (effects (font (size 0.7 0.7) (thickness 0.15)) (justify left bottom mirror))
    )
    (fp_text value "BSS138PW" (at 0 -2.3 180) (layer "B.Fab") hide
        (effects (font (size 0.7 0.7) (thickness 0.15)) (justify left bottom mirror))
    )
    (fp_text user "${REFERENCE}" (at -1.45 -4.783 180) (layer "B.Fab") hide
        (effects (font (size 0.7 0.7) (thickness 0.15)) (justify left bottom mirror))
    )
    (fp_text user "Author: Antmicro" (at -1.45 -5.782 180) (layer "B.Fab") hide
        (effects (font (size 0.7 0.7) (thickness 0.15)) (justify left bottom mirror))
    )
    (fp_text user "License: Apache-2.0" (at -1.45 -6.782 180) (layer "B.Fab") hide
        (effects (font (size 0.7 0.7) (thickness 0.15)) (justify left bottom mirror))
    )
    (fp_line (start -0.3 -1) (end 0.627 -1.001)
      (stroke (width 0.15) (type solid)) (layer "B.SilkS"))
    (fp_line (start -0.3 1) (end 0.627 0.999)
      (stroke (width 0.15) (type solid)) (layer "B.SilkS"))
    (fp_line (start 0.627 -0.6) (end 0.627 -1.001)
      (stroke (width 0.15) (type solid)) (layer "B.SilkS"))
    (fp_line (start 0.627 0.6) (end 0.627 0.999)
      (stroke (width 0.15) (type solid)) (layer "B.SilkS"))
    (fp_rect (start 1.4 -1.3) (end -1.4 1.3)
      (stroke (width 0.05) (type solid)) (fill none) (layer "B.CrtYd"))
    (fp_rect (start -0.623 0.999) (end 0.627 -1.001)
      (stroke (width 0.15) (type solid)) (fill none) (layer "B.Fab"))
    (pad "1" smd rect (at -0.95 0.65 270) (size 0.6 0.8) (layers "B.Cu" "B.Paste" "B.Mask")
      (net 70 "USR_LED2") (pinfunction "G") (pintype "bidirectional"))
    (pad "2" smd rect (at -0.95 -0.65 270) (size 0.6 0.8) (layers "B.Cu" "B.Paste" "B.Mask")
      (net 9 "GND") (pinfunction "S") (pintype "bidirectional"))
    (pad "3" smd rect (at 0.95 0 270) (size 0.6 0.8) (layers "B.Cu" "B.Paste" "B.Mask")
      (net 576 "Net-(Q4-D)") (pinfunction "D") (pintype "bidirectional"))
  )

  (footprint "data-center-rdimm-ddr4-tester-footprints:SC70-3" (layer "B.Cu")
    (at 238.94 88.5)
    (property "Author" "Antmicro")
    (property "License" "Apache-2.0")
    (property "MPN" "BSS138PW")
    (property "Manufacturer" "Nexperia")
    (property "Sheetfile" "interfaces.kicad_sch")
    (property "Sheetname" "Interfaces")
    (property "ki_description" "60 V, 320 mA N-channel enhancement mode Trench MOSFET, SC-70-3 aka SOT-323 package")
    (property "ki_keywords" "n-channel enhancement mosfet sc70 sc-70 sot-323 sot323")
    (attr smd)
    (fp_text reference "Q5" (at -1.35 0.41 180) (layer "B.SilkS")
        (effects (font (size 0.7 0.7) (thickness 0.15)) (justify left bottom mirror))
    )
    (fp_text value "BSS138PW" (at 0 -2.3 180) (layer "B.Fab") hide
        (effects (font (size 0.7 0.7) (thickness 0.15)) (justify left bottom mirror))
    )
    (fp_text user "Author: Antmicro" (at -1.45 -5.782 180) (layer "B.Fab") hide
        (effects (font (size 0.7 0.7) (thickness 0.15)) (justify left bottom mirror))
    )
    (fp_text user "License: Apache-2.0" (at -1.45 -6.782 180) (layer "B.Fab") hide
        (effects (font (size 0.7 0.7) (thickness 0.15)) (justify left bottom mirror))
    )
    (fp_text user "${REFERENCE}" (at -1.45 -4.783 180) (layer "B.Fab") hide
        (effects (font (size 0.7 0.7) (thickness 0.15)) (justify left bottom mirror))
    )
    (fp_line (start -0.3 -1) (end 0.627 -1.001)
      (stroke (width 0.15) (type solid)) (layer "B.SilkS"))
    (fp_line (start -0.3 1) (end 0.627 0.999)
      (stroke (width 0.15) (type solid)) (layer "B.SilkS"))
    (fp_line (start 0.627 -0.6) (end 0.627 -1.001)
      (stroke (width 0.15) (type solid)) (layer "B.SilkS"))
    (fp_line (start 0.627 0.6) (end 0.627 0.999)
      (stroke (width 0.15) (type solid)) (layer "B.SilkS"))
    (fp_rect (start 1.4 -1.3) (end -1.4 1.3)
      (stroke (width 0.05) (type solid)) (fill none) (layer "B.CrtYd"))
    (fp_rect (start -0.623 0.999) (end 0.627 -1.001)
      (stroke (width 0.15) (type solid)) (fill none) (layer "B.Fab"))
    (pad "1" smd rect (at -0.95 0.65 270) (size 0.6 0.8) (layers "B.Cu" "B.Paste" "B.Mask")
      (net 72 "USR_LED4") (pinfunction "G") (pintype "bidirectional"))
    (pad "2" smd rect (at -0.95 -0.65 270) (size 0.6 0.8) (layers "B.Cu" "B.Paste" "B.Mask")
      (net 9 "GND") (pinfunction "S") (pintype "bidirectional"))
    (pad "3" smd rect (at 0.95 0 270) (size 0.6 0.8) (layers "B.Cu" "B.Paste" "B.Mask")
      (net 577 "Net-(Q5-D)") (pinfunction "D") (pintype "bidirectional"))
  )

  (footprint "data-center-rdimm-ddr4-tester-footprints:SC70-3" (layer "B.Cu")
    (at 238.94 85.825)
    (property "Author" "Antmicro")
    (property "License" "Apache-2.0")
    (property "MPN" "BSS138PW")
    (property "Manufacturer" "Nexperia")
    (property "Sheetfile" "interfaces.kicad_sch")
    (property "Sheetname" "Interfaces")
    (property "ki_description" "60 V, 320 mA N-channel enhancement mode Trench MOSFET, SC-70-3 aka SOT-323 package")
    (property "ki_keywords" "n-channel enhancement mosfet sc70 sc-70 sot-323 sot323")
    (attr smd)
    (fp_text reference "Q6" (at -1.35 0.41 180) (layer "B.SilkS")
        (effects (font (size 0.7 0.7) (thickness 0.15)) (justify left bottom mirror))
    )
    (fp_text value "BSS138PW" (at 0 -2.3 180) (layer "B.Fab") hide
        (effects (font (size 0.7 0.7) (thickness 0.15)) (justify left bottom mirror))
    )
    (fp_text user "License: Apache-2.0" (at -1.45 -6.782 180) (layer "B.Fab") hide
        (effects (font (size 0.7 0.7) (thickness 0.15)) (justify left bottom mirror))
    )
    (fp_text user "${REFERENCE}" (at -1.45 -4.783 180) (layer "B.Fab") hide
        (effects (font (size 0.7 0.7) (thickness 0.15)) (justify left bottom mirror))
    )
    (fp_text user "Author: Antmicro" (at -1.45 -5.782 180) (layer "B.Fab") hide
        (effects (font (size 0.7 0.7) (thickness 0.15)) (justify left bottom mirror))
    )
    (fp_line (start -0.3 -1) (end 0.627 -1.001)
      (stroke (width 0.15) (type solid)) (layer "B.SilkS"))
    (fp_line (start -0.3 1) (end 0.627 0.999)
      (stroke (width 0.15) (type solid)) (layer "B.SilkS"))
    (fp_line (start 0.627 -0.6) (end 0.627 -1.001)
      (stroke (width 0.15) (type solid)) (layer "B.SilkS"))
    (fp_line (start 0.627 0.6) (end 0.627 0.999)
      (stroke (width 0.15) (type solid)) (layer "B.SilkS"))
    (fp_rect (start 1.4 -1.3) (end -1.4 1.3)
      (stroke (width 0.05) (type solid)) (fill none) (layer "B.CrtYd"))
    (fp_rect (start -0.623 0.999) (end 0.627 -1.001)
      (stroke (width 0.15) (type solid)) (fill none) (layer "B.Fab"))
    (pad "1" smd rect (at -0.95 0.65 270) (size 0.6 0.8) (layers "B.Cu" "B.Paste" "B.Mask")
      (net 74 "USR_LED5") (pinfunction "G") (pintype "bidirectional"))
    (pad "2" smd rect (at -0.95 -0.65 270) (size 0.6 0.8) (layers "B.Cu" "B.Paste" "B.Mask")
      (net 9 "GND") (pinfunction "S") (pintype "bidirectional"))
    (pad "3" smd rect (at 0.95 0 270) (size 0.6 0.8) (layers "B.Cu" "B.Paste" "B.Mask")
      (net 578 "Net-(Q6-D)") (pinfunction "D") (pintype "bidirectional"))
  )

  (footprint "data-center-rdimm-ddr4-tester-footprints:SC70-3" (layer "B.Cu")
    (at 239.6 125.865)
    (property "Author" "Antmicro")
    (property "License" "Apache-2.0")
    (property "MPN" "BSS138PW")
    (property "Manufacturer" "Nexperia")
    (property "Sheetfile" "config-spi.kicad_sch")
    (property "Sheetname" "Config SPI flash")
    (property "ki_description" "60 V, 320 mA N-channel enhancement mode Trench MOSFET, SC-70-3 aka SOT-323 package")
    (property "ki_keywords" "n-channel enhancement mosfet sc70 sc-70 sot-323 sot323")
    (attr smd)
    (fp_text reference "Q8" (at 0.95 1.915 180) (layer "B.SilkS")
        (effects (font (size 0.7 0.7) (thickness 0.15)) (justify left bottom mirror))
    )
    (fp_text value "BSS138PW" (at 0 -2.3 180) (layer "B.Fab") hide
        (effects (font (size 0.7 0.7) (thickness 0.15)) (justify left bottom mirror))
    )
    (fp_text user "${REFERENCE}" (at -1.45 -4.783 180) (layer "B.Fab") hide
        (effects (font (size 0.7 0.7) (thickness 0.15)) (justify left bottom mirror))
    )
    (fp_text user "License: Apache-2.0" (at -1.45 -6.782 180) (layer "B.Fab") hide
        (effects (font (size 0.7 0.7) (thickness 0.15)) (justify left bottom mirror))
    )
    (fp_text user "Author: Antmicro" (at -1.45 -5.782 180) (layer "B.Fab") hide
        (effects (font (size 0.7 0.7) (thickness 0.15)) (justify left bottom mirror))
    )
    (fp_line (start -0.3 -1) (end 0.627 -1.001)
      (stroke (width 0.15) (type solid)) (layer "B.SilkS"))
    (fp_line (start -0.3 1) (end 0.627 0.999)
      (stroke (width 0.15) (type solid)) (layer "B.SilkS"))
    (fp_line (start 0.627 -0.6) (end 0.627 -1.001)
      (stroke (width 0.15) (type solid)) (layer "B.SilkS"))
    (fp_line (start 0.627 0.6) (end 0.627 0.999)
      (stroke (width 0.15) (type solid)) (layer "B.SilkS"))
    (fp_rect (start 1.4 -1.3) (end -1.4 1.3)
      (stroke (width 0.05) (type solid)) (fill none) (layer "B.CrtYd"))
    (fp_rect (start -0.623 0.999) (end 0.627 -1.001)
      (stroke (width 0.15) (type solid)) (fill none) (layer "B.Fab"))
    (pad "1" smd rect (at -0.95 0.65 270) (size 0.6 0.8) (layers "B.Cu" "B.Paste" "B.Mask")
      (net 93 "INIT_B") (pinfunction "G") (pintype "bidirectional"))
    (pad "2" smd rect (at -0.95 -0.65 270) (size 0.6 0.8) (layers "B.Cu" "B.Paste" "B.Mask")
      (net 9 "GND") (pinfunction "S") (pintype "bidirectional"))
    (pad "3" smd rect (at 0.95 0 270) (size 0.6 0.8) (layers "B.Cu" "B.Paste" "B.Mask")
      (net 580 "Net-(Q8-D)") (pinfunction "D") (pintype "bidirectional"))
  )

  (footprint "data-center-rdimm-ddr4-tester-footprints:SC70-3" (layer "B.Cu")
    (at 239.69 123.05)
    (property "Author" "Antmicro")
    (property "License" "Apache-2.0")
    (property "MPN" "BSS138PW")
    (property "Manufacturer" "Nexperia")
    (property "Sheetfile" "config-spi.kicad_sch")
    (property "Sheetname" "Config SPI flash")
    (property "ki_description" "60 V, 320 mA N-channel enhancement mode Trench MOSFET, SC-70-3 aka SOT-323 package")
    (property "ki_keywords" "n-channel enhancement mosfet sc70 sc-70 sot-323 sot323")
    (attr smd)
    (fp_text reference "Q7" (at 2.2 -0.51 180) (layer "B.SilkS")
        (effects (font (size 0.7 0.7) (thickness 0.15)) (justify left bottom mirror))
    )
    (fp_text value "BSS138PW" (at 0 -2.3 180) (layer "B.Fab") hide
        (effects (font (size 0.7 0.7) (thickness 0.15)) (justify left bottom mirror))
    )
    (fp_text user "${REFERENCE}" (at -1.45 -4.783 180) (layer "B.Fab") hide
        (effects (font (size 0.7 0.7) (thickness 0.15)) (justify left bottom mirror))
    )
    (fp_text user "Author: Antmicro" (at -1.45 -5.782 180) (layer "B.Fab") hide
        (effects (font (size 0.7 0.7) (thickness 0.15)) (justify left bottom mirror))
    )
    (fp_text user "License: Apache-2.0" (at -1.45 -6.782 180) (layer "B.Fab") hide
        (effects (font (size 0.7 0.7) (thickness 0.15)) (justify left bottom mirror))
    )
    (fp_line (start -0.3 -1) (end 0.627 -1.001)
      (stroke (width 0.15) (type solid)) (layer "B.SilkS"))
    (fp_line (start -0.3 1) (end 0.627 0.999)
      (stroke (width 0.15) (type solid)) (layer "B.SilkS"))
    (fp_line (start 0.627 -0.6) (end 0.627 -1.001)
      (stroke (width 0.15) (type solid)) (layer "B.SilkS"))
    (fp_line (start 0.627 0.6) (end 0.627 0.999)
      (stroke (width 0.15) (type solid)) (layer "B.SilkS"))
    (fp_rect (start 1.4 -1.3) (end -1.4 1.3)
      (stroke (width 0.05) (type solid)) (fill none) (layer "B.CrtYd"))
    (fp_rect (start -0.623 0.999) (end 0.627 -1.001)
      (stroke (width 0.15) (type solid)) (fill none) (layer "B.Fab"))
    (pad "1" smd rect (at -0.95 0.65 270) (size 0.6 0.8) (layers "B.Cu" "B.Paste" "B.Mask")
      (net 25 "DONE") (pinfunction "G") (pintype "bidirectional"))
    (pad "2" smd rect (at -0.95 -0.65 270) (size 0.6 0.8) (layers "B.Cu" "B.Paste" "B.Mask")
      (net 9 "GND") (pinfunction "S") (pintype "bidirectional"))
    (pad "3" smd rect (at 0.95 0 270) (size 0.6 0.8) (layers "B.Cu" "B.Paste" "B.Mask")
      (net 579 "Net-(Q7-D)") (pinfunction "D") (pintype "bidirectional"))
  )

  (footprint "data-center-rdimm-ddr4-tester-footprints:R_0402_1005Metric" (layer "B.Cu")
    (at 241.6 123.6 90)
    (descr "Resistor SMD 0402")
    (tags "resistor SMD 0402")
    (property "Author" "Antmicro")
    (property "License" "Apache-2.0")
    (property "MPN" "CR0402-FX-3300GLF")
    (property "Manufacturer" "Bourns")
    (property "Sheetfile" "config-spi.kicad_sch")
    (property "Sheetname" "Config SPI flash")
    (property "Tolerance" "1%")
    (property "Val" "330R")
    (property "ki_description" "330R resistor in 0402 package with 1% tolerance")
    (attr smd)
    (fp_text reference "R30" (at 1.02 1.32 270) (layer "B.SilkS")
        (effects (font (size 0.7 0.7) (thickness 0.15)) (justify left bottom mirror))
    )
    (fp_text value "R_330R_0402" (at 0 -1.4 270) (layer "B.Fab") hide
        (effects (font (size 0.7 0.7) (thickness 0.15)) (justify left bottom mirror))
    )
    (fp_text user "License: Apache-2.0" (at -0.95 -5.169 270) (layer "B.Fab") hide
        (effects (font (size 0.7 0.7) (thickness 0.15)) (justify left bottom mirror))
    )
    (fp_text user "Author: Antmicro" (at -0.95 -4.169 270) (layer "B.Fab") hide
        (effects (font (size 0.7 0.7) (thickness 0.15)) (justify left bottom mirror))
    )
    (fp_text user "${REFERENCE}" (at -0.95 -3.168 270) (layer "B.Fab") hide
        (effects (font (size 0.7 0.7) (thickness 0.15)) (justify left bottom mirror))
    )
    (fp_rect (start -0.93 0.47) (end 0.93 -0.47)
      (stroke (width 0.05) (type solid)) (fill none) (layer "B.CrtYd"))
    (fp_rect (start -0.5 0.25) (end 0.5 -0.25)
      (stroke (width 0.15) (type solid)) (fill none) (layer "B.Fab"))
    (pad "1" smd roundrect (at -0.485 0 90) (size 0.59 0.64) (layers "B.Cu" "B.Paste" "B.Mask") (roundrect_rratio 0.25)
      (net 89 "Net-(D1-Pad2)") (pintype "passive"))
    (pad "2" smd roundrect (at 0.485 0 90) (size 0.59 0.64) (layers "B.Cu" "B.Paste" "B.Mask") (roundrect_rratio 0.25)
      (net 579 "Net-(Q7-D)") (pintype "passive"))
  )

  (footprint "data-center-rdimm-ddr4-tester-footprints:R_0402_1005Metric" (layer "B.Cu")
    (at 241.6 126.2 90)
    (descr "Resistor SMD 0402")
    (tags "resistor SMD 0402")
    (property "Author" "Antmicro")
    (property "License" "Apache-2.0")
    (property "MPN" "CR0402-FX-3300GLF")
    (property "Manufacturer" "Bourns")
    (property "Sheetfile" "config-spi.kicad_sch")
    (property "Sheetname" "Config SPI flash")
    (property "Tolerance" "1%")
    (property "Val" "330R")
    (property "ki_description" "330R resistor in 0402 package with 1% tolerance")
    (attr smd)
    (fp_text reference "R31" (at 0.98 1.33 270) (layer "B.SilkS")
        (effects (font (size 0.7 0.7) (thickness 0.15)) (justify left bottom mirror))
    )
    (fp_text value "R_330R_0402" (at 0 -1.4 270) (layer "B.Fab") hide
        (effects (font (size 0.7 0.7) (thickness 0.15)) (justify left bottom mirror))
    )
    (fp_text user "Author: Antmicro" (at -0.95 -4.169 270) (layer "B.Fab") hide
        (effects (font (size 0.7 0.7) (thickness 0.15)) (justify left bottom mirror))
    )
    (fp_text user "${REFERENCE}" (at -0.95 -3.168 270) (layer "B.Fab") hide
        (effects (font (size 0.7 0.7) (thickness 0.15)) (justify left bottom mirror))
    )
    (fp_text user "License: Apache-2.0" (at -0.95 -5.169 270) (layer "B.Fab") hide
        (effects (font (size 0.7 0.7) (thickness 0.15)) (justify left bottom mirror))
    )
    (fp_rect (start -0.93 0.47) (end 0.93 -0.47)
      (stroke (width 0.05) (type solid)) (fill none) (layer "B.CrtYd"))
    (fp_rect (start -0.5 0.25) (end 0.5 -0.25)
      (stroke (width 0.15) (type solid)) (fill none) (layer "B.Fab"))
    (pad "1" smd roundrect (at -0.485 0 90) (size 0.59 0.64) (layers "B.Cu" "B.Paste" "B.Mask") (roundrect_rratio 0.25)
      (net 90 "Net-(D10-Pad2)") (pintype "passive"))
    (pad "2" smd roundrect (at 0.485 0 90) (size 0.59 0.64) (layers "B.Cu" "B.Paste" "B.Mask") (roundrect_rratio 0.25)
      (net 580 "Net-(Q8-D)") (pintype "passive"))
  )

  (footprint "data-center-rdimm-ddr4-tester-footprints:R_0402_1005Metric" (layer "B.Cu")
    (at 237.65 123.315 -90)
    (descr "Resistor SMD 0402")
    (tags "resistor SMD 0402")
    (property "Author" "Antmicro")
    (property "License" "Apache-2.0")
    (property "MPN" "CR0402-FX-3300GLF")
    (property "Manufacturer" "Bourns")
    (property "Sheetfile" "config-spi.kicad_sch")
    (property "Sheetname" "Config SPI flash")
    (property "Tolerance" "1%")
    (property "Val" "330R")
    (property "ki_description" "330R resistor in 0402 package with 1% tolerance")
    (attr smd)
    (fp_text reference "R57" (at -1.075 0.59 90) (layer "B.SilkS")
        (effects (font (size 0.7 0.7) (thickness 0.15)) (justify left bottom mirror))
    )
    (fp_text value "R_330R_0402" (at 0 -1.4 90) (layer "B.Fab") hide
        (effects (font (size 0.7 0.7) (thickness 0.15)) (justify left bottom mirror))
    )
    (fp_text user "License: Apache-2.0" (at -0.95 -5.169 90) (layer "B.Fab") hide
        (effects (font (size 0.7 0.7) (thickness 0.15)) (justify left bottom mirror))
    )
    (fp_text user "${REFERENCE}" (at -0.95 -3.168 90) (layer "B.Fab") hide
        (effects (font (size 0.7 0.7) (thickness 0.15)) (justify left bottom mirror))
    )
    (fp_text user "Author: Antmicro" (at -0.95 -4.169 90) (layer "B.Fab") hide
        (effects (font (size 0.7 0.7) (thickness 0.15)) (justify left bottom mirror))
    )
    (fp_rect (start -0.93 0.47) (end 0.93 -0.47)
      (stroke (width 0.05) (type solid)) (fill none) (layer "B.CrtYd"))
    (fp_rect (start -0.5 0.25) (end 0.5 -0.25)
      (stroke (width 0.15) (type solid)) (fill none) (layer "B.Fab"))
    (pad "1" smd roundrect (at -0.485 0 270) (size 0.59 0.64) (layers "B.Cu" "B.Paste" "B.Mask") (roundrect_rratio 0.25)
      (net 143 "3V3_SYS") (pintype "passive"))
    (pad "2" smd roundrect (at 0.485 0 270) (size 0.59 0.64) (layers "B.Cu" "B.Paste" "B.Mask") (roundrect_rratio 0.25)
      (net 25 "DONE") (pintype "passive"))
  )

  (footprint "data-center-rdimm-ddr4-tester-footprints:C_0603_1608Metric" (layer "B.Cu")
    (at 191.707 88.049 -90)
    (descr "Capacitor SMD 0603")
    (tags "capacitor 0603")
    (property "Author" "Antmicro")
    (property "Dielectric" "")
    (property "License" "Apache-2.0")
    (property "MPN" "GRM188R60J476ME15D")
    (property "Manufacturer" "Murata")
    (property "Sheetfile" "config-spi.kicad_sch")
    (property "Sheetname" "Config SPI flash")
    (property "Val" "47u")
    (property "Voltage" "")
    (property "ki_description" " ")
    (attr smd)
    (fp_text reference "C12" (at -1.139 0.597 90) (layer "B.SilkS")
        (effects (font (size 0.7 0.7) (thickness 0.15)) (justify left bottom mirror))
    )
    (fp_text value "C_47u_0603" (at 0 -1.6 90) (layer "B.Fab") hide
        (effects (font (size 0.7 0.7) (thickness 0.15)) (justify left bottom mirror))
    )
    (fp_text user "${REFERENCE}" (at -1.682 -3.895 90) (layer "B.Fab") hide
        (effects (font (size 0.7 0.7) (thickness 0.15)) (justify left bottom mirror))
    )
    (fp_text user "License: Apache-2.0" (at -1.682 -5.895 90) (layer "B.Fab") hide
        (effects (font (size 0.7 0.7) (thickness 0.15)) (justify left bottom mirror))
    )
    (fp_text user "Author: Antmicro" (at -1.682 -4.894 90) (layer "B.Fab") hide
        (effects (font (size 0.7 0.7) (thickness 0.15)) (justify left bottom mirror))
    )
    (fp_line (start -0.3 -0.3) (end 0.3 -0.3)
      (stroke (width 0.15) (type solid)) (layer "B.SilkS"))
    (fp_line (start -0.3 0.3) (end 0.3 0.3)
      (stroke (width 0.15) (type solid)) (layer "B.SilkS"))
    (fp_rect (start -1.24 0.7) (end 1.24 -0.7)
      (stroke (width 0.05) (type solid)) (fill none) (layer "B.CrtYd"))
    (fp_rect (start -0.8 0.4) (end 0.8 -0.4)
      (stroke (width 0.15) (type solid)) (fill none) (layer "B.Fab"))
    (pad "1" smd roundrect (at -0.7 0 270) (size 0.6 0.8) (layers "B.Cu" "B.Paste" "B.Mask") (roundrect_rratio 0.2)
      (net 143 "3V3_SYS") (pintype "passive"))
    (pad "2" smd roundrect (at 0.7 0 270) (size 0.6 0.8) (layers "B.Cu" "B.Paste" "B.Mask") (roundrect_rratio 0.2)
      (net 9 "GND") (pintype "passive"))
  )

  (footprint "data-center-rdimm-ddr4-tester-footprints:C_0402_1005Metric" (layer "B.Cu")
    (at 191.775 94.425)
    (descr "Capacitor SMD 0402")
    (tags "capacitor SMD 0402")
    (property "Author" "Antmicro")
    (property "Dielectric" "")
    (property "License" "Apache-2.0")
    (property "MPN" "C1005X5R1E474M050BB")
    (property "Manufacturer" "TDK")
    (property "Sheetfile" "config-spi.kicad_sch")
    (property "Sheetname" "Config SPI flash")
    (property "Val" "470n")
    (property "Voltage" "")
    (property "ki_description" " ")
    (attr smd)
    (fp_text reference "C13" (at 3.025 0.485 180) (layer "B.SilkS")
        (effects (font (size 0.7 0.7) (thickness 0.15)) (justify left bottom mirror))
    )
    (fp_text value "C_470n_0402" (at 0 -1.4 180) (layer "B.Fab") hide
        (effects (font (size 0.7 0.7) (thickness 0.15)) (justify left bottom mirror))
    )
    (fp_text user "Author: Antmicro" (at -0.932 -4.17 180) (layer "B.Fab") hide
        (effects (font (size 0.7 0.7) (thickness 0.15)) (justify left bottom mirror))
    )
    (fp_text user "License: Apache-2.0" (at -0.932 -5.17 180) (layer "B.Fab") hide
        (effects (font (size 0.7 0.7) (thickness 0.15)) (justify left bottom mirror))
    )
    (fp_text user "${REFERENCE}" (at -0.932 -3.168 180) (layer "B.Fab") hide
        (effects (font (size 0.7 0.7) (thickness 0.15)) (justify left bottom mirror))
    )
    (fp_rect (start -0.94 0.47) (end 0.94 -0.47)
      (stroke (width 0.05) (type solid)) (fill none) (layer "B.CrtYd"))
    (fp_rect (start -0.499 0.249) (end 0.499 -0.249)
      (stroke (width 0.15) (type solid)) (fill none) (layer "B.Fab"))
    (pad "1" smd roundrect (at -0.484 0) (size 0.59 0.64) (layers "B.Cu" "B.Paste" "B.Mask") (roundrect_rratio 0.25)
      (net 143 "3V3_SYS") (pintype "passive"))
    (pad "2" smd roundrect (at 0.484 0) (size 0.59 0.64) (layers "B.Cu" "B.Paste" "B.Mask") (roundrect_rratio 0.25)
      (net 9 "GND") (pintype "passive"))
  )

  (footprint "data-center-rdimm-ddr4-tester-footprints:C_0402_1005Metric" (layer "B.Cu")
    (at 183.85 90.15)
    (descr "Capacitor SMD 0402")
    (tags "capacitor SMD 0402")
    (property "Author" "Antmicro")
    (property "Dielectric" "")
    (property "License" "Apache-2.0")
    (property "MPN" "GRM155R61A475MEAAD")
    (property "Manufacturer" "Murata")
    (property "Sheetfile" "fpga-power.kicad_sch")
    (property "Sheetname" "FPGA power")
    (property "Val" "4u7")
    (property "Voltage" "")
    (property "ki_description" " ")
    (attr smd)
    (fp_text reference "C17" (at 18.704672 -8.900008 180) (layer "B.SilkS")
        (effects (font (size 0.7 0.7) (thickness 0.15)) (justify left bottom mirror))
    )
    (fp_text value "C_4u7_0402" (at 0 -1.4 180) (layer "B.Fab") hide
        (effects (font (size 0.7 0.7) (thickness 0.15)) (justify left bottom mirror))
    )
    (fp_text user "${REFERENCE}" (at -0.932 -3.168 180) (layer "B.Fab") hide
        (effects (font (size 0.7 0.7) (thickness 0.15)) (justify left bottom mirror))
    )
    (fp_text user "Author: Antmicro" (at -0.932 -4.17 180) (layer "B.Fab") hide
        (effects (font (size 0.7 0.7) (thickness 0.15)) (justify left bottom mirror))
    )
    (fp_text user "License: Apache-2.0" (at -0.932 -5.17 180) (layer "B.Fab") hide
        (effects (font (size 0.7 0.7) (thickness 0.15)) (justify left bottom mirror))
    )
    (fp_rect (start -0.94 0.47) (end 0.94 -0.47)
      (stroke (width 0.05) (type solid)) (fill none) (layer "B.CrtYd"))
    (fp_rect (start -0.499 0.249) (end 0.499 -0.249)
      (stroke (width 0.15) (type solid)) (fill none) (layer "B.Fab"))
    (pad "1" smd roundrect (at -0.484 0) (size 0.59 0.64) (layers "B.Cu" "B.Paste" "B.Mask") (roundrect_rratio 0.25)
      (net 147 "1V0_SYS") (pintype "passive"))
    (pad "2" smd roundrect (at 0.484 0) (size 0.59 0.64) (layers "B.Cu" "B.Paste" "B.Mask") (roundrect_rratio 0.25)
      (net 9 "GND") (pintype "passive"))
  )

  (footprint "data-center-rdimm-ddr4-tester-footprints:C_0201" (layer "B.Cu")
    (at 181.736328 82.410008 180)
    (descr "Capacitor SMD 0201")
    (tags "capacitor SMD 0201")
    (property "Author" "Antmicro")
    (property "Dielectric" "")
    (property "License" "Apache-2.0")
    (property "MPN" "CC0201KRX6S5BB104")
    (property "Manufacturer" "Yaego")
    (property "Sheetfile" "fpga-power.kicad_sch")
    (property "Sheetname" "FPGA power")
    (property "Val" "100n")
    (property "Voltage" "")
    (property "ki_description" " ")
    (attr smd)
    (fp_text reference "C32" (at -1.063672 -1.249992) (layer "B.SilkS")
        (effects (font (size 0.7 0.7) (thickness 0.15)) (justify left bottom mirror))
    )
    (fp_text value "C_100n_0201" (at 0 -1.4) (layer "B.Fab") hide
        (effects (font (size 0.7 0.7) (thickness 0.15)) (justify left bottom mirror))
    )
    (fp_text user "${REFERENCE}" (at -0.72 -3.4) (layer "B.Fab") hide
        (effects (font (size 0.7 0.7) (thickness 0.15)) (justify left bottom mirror))
    )
    (fp_text user "Author: Antmicro" (at -0.72 -5.4) (layer "B.Fab") hide
        (effects (font (size 0.7 0.7) (thickness 0.15)) (justify left bottom mirror))
    )
    (fp_text user "License: Apache-2.0" (at -0.72 -4.4) (layer "B.Fab") hide
        (effects (font (size 0.7 0.7) (thickness 0.15)) (justify left bottom mirror))
    )
    (fp_rect (start -0.72 0.38) (end 0.72 -0.38)
      (stroke (width 0.05) (type solid)) (fill none) (layer "B.CrtYd"))
    (fp_rect (start 0.3 -0.15) (end -0.301 0.149)
      (stroke (width 0.15) (type solid)) (fill none) (layer "B.Fab"))
    (pad "" smd roundrect (at -0.349 0.002 180) (size 0.318 0.36) (layers "B.Paste") (roundrect_rratio 0.25))
    (pad "" smd roundrect (at 0.341 0.002 180) (size 0.318 0.36) (layers "B.Paste") (roundrect_rratio 0.25))
    (pad "1" smd roundrect (at -0.321 0.002 180) (size 0.46 0.4) (layers "B.Cu" "B.Mask") (roundrect_rratio 0.25)
      (net 77 "VDDQ") (pintype "passive"))
    (pad "2" smd roundrect (at 0.32 0.002 180) (size 0.46 0.4) (layers "B.Cu" "B.Mask") (roundrect_rratio 0.25)
      (net 9 "GND") (pintype "passive"))
  )

  (footprint "data-center-rdimm-ddr4-tester-footprints:C_0201" (layer "B.Cu")
    (at 187.5 81.2 90)
    (descr "Capacitor SMD 0201")
    (tags "capacitor SMD 0201")
    (property "Author" "Antmicro")
    (property "Dielectric" "")
    (property "License" "Apache-2.0")
    (property "MPN" "CC0201KRX6S5BB104")
    (property "Manufacturer" "Yaego")
    (property "Sheetfile" "fpga-power.kicad_sch")
    (property "Sheetname" "FPGA power")
    (property "Val" "100n")
    (property "Voltage" "")
    (property "ki_description" " ")
    (attr smd)
    (fp_text reference "C43" (at 1.4 -0.4 270) (layer "B.SilkS")
        (effects (font (size 0.7 0.7) (thickness 0.15)) (justify left bottom mirror))
    )
    (fp_text value "C_100n_0201" (at 0 -1.4 270) (layer "B.Fab") hide
        (effects (font (size 0.7 0.7) (thickness 0.15)) (justify left bottom mirror))
    )
    (fp_text user "Author: Antmicro" (at -0.72 -5.4 270) (layer "B.Fab") hide
        (effects (font (size 0.7 0.7) (thickness 0.15)) (justify left bottom mirror))
    )
    (fp_text user "License: Apache-2.0" (at -0.72 -4.4 270) (layer "B.Fab") hide
        (effects (font (size 0.7 0.7) (thickness 0.15)) (justify left bottom mirror))
    )
    (fp_text user "${REFERENCE}" (at -0.72 -3.4 270) (layer "B.Fab") hide
        (effects (font (size 0.7 0.7) (thickness 0.15)) (justify left bottom mirror))
    )
    (fp_rect (start -0.72 0.38) (end 0.72 -0.38)
      (stroke (width 0.05) (type solid)) (fill none) (layer "B.CrtYd"))
    (fp_rect (start 0.3 -0.15) (end -0.301 0.149)
      (stroke (width 0.15) (type solid)) (fill none) (layer "B.Fab"))
    (pad "" smd roundrect (at -0.349 0.002 90) (size 0.318 0.36) (layers "B.Paste") (roundrect_rratio 0.25))
    (pad "" smd roundrect (at 0.341 0.002 90) (size 0.318 0.36) (layers "B.Paste") (roundrect_rratio 0.25))
    (pad "1" smd roundrect (at -0.321 0.002 90) (size 0.46 0.4) (layers "B.Cu" "B.Mask") (roundrect_rratio 0.25)
      (net 77 "VDDQ") (pintype "passive"))
    (pad "2" smd roundrect (at 0.32 0.002 90) (size 0.46 0.4) (layers "B.Cu" "B.Mask") (roundrect_rratio 0.25)
      (net 9 "GND") (pintype "passive"))
  )

  (footprint "data-center-rdimm-ddr4-tester-footprints:C_0201" (layer "B.Cu")
    (at 182.6 80.65)
    (descr "Capacitor SMD 0201")
    (tags "capacitor SMD 0201")
    (property "Author" "Antmicro")
    (property "Dielectric" "")
    (property "License" "Apache-2.0")
    (property "MPN" "CC0201KRX6S5BB104")
    (property "Manufacturer" "Yaego")
    (property "Sheetfile" "fpga-power.kicad_sch")
    (property "Sheetname" "FPGA power")
    (property "Val" "100n")
    (property "Voltage" "")
    (property "ki_description" " ")
    (attr smd)
    (fp_text reference "C44" (at 1.04 1.19 180) (layer "B.SilkS")
        (effects (font (size 0.7 0.7) (thickness 0.15)) (justify left bottom mirror))
    )
    (fp_text value "C_100n_0201" (at 0 -1.4 180) (layer "B.Fab") hide
        (effects (font (size 0.7 0.7) (thickness 0.15)) (justify left bottom mirror))
    )
    (fp_text user "License: Apache-2.0" (at -0.72 -4.4 180) (layer "B.Fab") hide
        (effects (font (size 0.7 0.7) (thickness 0.15)) (justify left bottom mirror))
    )
    (fp_text user "${REFERENCE}" (at -0.72 -3.4 180) (layer "B.Fab") hide
        (effects (font (size 0.7 0.7) (thickness 0.15)) (justify left bottom mirror))
    )
    (fp_text user "Author: Antmicro" (at -0.72 -5.4 180) (layer "B.Fab") hide
        (effects (font (size 0.7 0.7) (thickness 0.15)) (justify left bottom mirror))
    )
    (fp_rect (start -0.72 0.38) (end 0.72 -0.38)
      (stroke (width 0.05) (type solid)) (fill none) (layer "B.CrtYd"))
    (fp_rect (start 0.3 -0.15) (end -0.301 0.149)
      (stroke (width 0.15) (type solid)) (fill none) (layer "B.Fab"))
    (pad "" smd roundrect (at -0.349 0.002) (size 0.318 0.36) (layers "B.Paste") (roundrect_rratio 0.25))
    (pad "" smd roundrect (at 0.341 0.002) (size 0.318 0.36) (layers "B.Paste") (roundrect_rratio 0.25))
    (pad "1" smd roundrect (at -0.321 0.002) (size 0.46 0.4) (layers "B.Cu" "B.Mask") (roundrect_rratio 0.25)
      (net 77 "VDDQ") (pintype "passive"))
    (pad "2" smd roundrect (at 0.32 0.002) (size 0.46 0.4) (layers "B.Cu" "B.Mask") (roundrect_rratio 0.25)
      (net 9 "GND") (pintype "passive"))
  )

  (footprint "data-center-rdimm-ddr4-tester-footprints:C_0201" (layer "B.Cu")
    (at 188.186328 91.560008 -90)
    (descr "Capacitor SMD 0201")
    (tags "capacitor SMD 0201")
    (property "Author" "Antmicro")
    (property "Dielectric" "")
    (property "License" "Apache-2.0")
    (property "MPN" "CC0201KRX6S5BB104")
    (property "Manufacturer" "Yaego")
    (property "Sheetfile" "fpga-power.kicad_sch")
    (property "Sheetname" "FPGA power")
    (property "Val" "100n")
    (property "Voltage" "")
    (property "ki_description" " ")
    (attr smd)
    (fp_text reference "C50" (at -10.180016 -18.417344 90) (layer "B.SilkS")
        (effects (font (size 0.7 0.7) (thickness 0.15)) (justify left bottom mirror))
    )
    (fp_text value "C_100n_0201" (at 0 -1.4 90) (layer "B.Fab") hide
        (effects (font (size 0.7 0.7) (thickness 0.15)) (justify left bottom mirror))
    )
    (fp_text user "${REFERENCE}" (at -0.72 -3.4 90) (layer "B.Fab") hide
        (effects (font (size 0.7 0.7) (thickness 0.15)) (justify left bottom mirror))
    )
    (fp_text user "License: Apache-2.0" (at -0.72 -4.4 90) (layer "B.Fab") hide
        (effects (font (size 0.7 0.7) (thickness 0.15)) (justify left bottom mirror))
    )
    (fp_text user "Author: Antmicro" (at -0.72 -5.4 90) (layer "B.Fab") hide
        (effects (font (size 0.7 0.7) (thickness 0.15)) (justify left bottom mirror))
    )
    (fp_rect (start -0.72 0.38) (end 0.72 -0.38)
      (stroke (width 0.05) (type solid)) (fill none) (layer "B.CrtYd"))
    (fp_rect (start 0.3 -0.15) (end -0.301 0.149)
      (stroke (width 0.15) (type solid)) (fill none) (layer "B.Fab"))
    (pad "" smd roundrect (at -0.349 0.002 270) (size 0.318 0.36) (layers "B.Paste") (roundrect_rratio 0.25))
    (pad "" smd roundrect (at 0.341 0.002 270) (size 0.318 0.36) (layers "B.Paste") (roundrect_rratio 0.25))
    (pad "1" smd roundrect (at -0.321 0.002 270) (size 0.46 0.4) (layers "B.Cu" "B.Mask") (roundrect_rratio 0.25)
      (net 147 "1V0_SYS") (pintype "passive"))
    (pad "2" smd roundrect (at 0.32 0.002 270) (size 0.46 0.4) (layers "B.Cu" "B.Mask") (roundrect_rratio 0.25)
      (net 9 "GND") (pintype "passive"))
  )

  (footprint "data-center-rdimm-ddr4-tester-footprints:C_0201" (layer "B.Cu")
    (at 189.186328 94.510008 180)
    (descr "Capacitor SMD 0201")
    (tags "capacitor SMD 0201")
    (property "Author" "Antmicro")
    (property "Dielectric" "")
    (property "License" "Apache-2.0")
    (property "MPN" "CC0201KRX6S5BB104")
    (property "Manufacturer" "Yaego")
    (property "Sheetfile" "fpga-power.kicad_sch")
    (property "Sheetname" "FPGA power")
    (property "Val" "100n")
    (property "Voltage" "")
    (property "ki_description" " ")
    (attr smd)
    (fp_text reference "C54" (at -1.083672 -1.199992) (layer "B.SilkS")
        (effects (font (size 0.7 0.7) (thickness 0.15)) (justify left bottom mirror))
    )
    (fp_text value "C_100n_0201" (at 0 -1.4) (layer "B.Fab") hide
        (effects (font (size 0.7 0.7) (thickness 0.15)) (justify left bottom mirror))
    )
    (fp_text user "${REFERENCE}" (at -0.72 -3.4) (layer "B.Fab") hide
        (effects (font (size 0.7 0.7) (thickness 0.15)) (justify left bottom mirror))
    )
    (fp_text user "Author: Antmicro" (at -0.72 -5.4) (layer "B.Fab") hide
        (effects (font (size 0.7 0.7) (thickness 0.15)) (justify left bottom mirror))
    )
    (fp_text user "License: Apache-2.0" (at -0.72 -4.4) (layer "B.Fab") hide
        (effects (font (size 0.7 0.7) (thickness 0.15)) (justify left bottom mirror))
    )
    (fp_rect (start -0.72 0.38) (end 0.72 -0.38)
      (stroke (width 0.05) (type solid)) (fill none) (layer "B.CrtYd"))
    (fp_rect (start 0.3 -0.15) (end -0.301 0.149)
      (stroke (width 0.15) (type solid)) (fill none) (layer "B.Fab"))
    (pad "" smd roundrect (at -0.349 0.002 180) (size 0.318 0.36) (layers "B.Paste") (roundrect_rratio 0.25))
    (pad "" smd roundrect (at 0.341 0.002 180) (size 0.318 0.36) (layers "B.Paste") (roundrect_rratio 0.25))
    (pad "1" smd roundrect (at -0.321 0.002 180) (size 0.46 0.4) (layers "B.Cu" "B.Mask") (roundrect_rratio 0.25)
      (net 147 "1V0_SYS") (pintype "passive"))
    (pad "2" smd roundrect (at 0.32 0.002 180) (size 0.46 0.4) (layers "B.Cu" "B.Mask") (roundrect_rratio 0.25)
      (net 9 "GND") (pintype "passive"))
  )

  (footprint "data-center-rdimm-ddr4-tester-footprints:C_0201" (layer "B.Cu")
    (at 181.2 86.610008 -90)
    (descr "Capacitor SMD 0201")
    (tags "capacitor SMD 0201")
    (property "Author" "Antmicro")
    (property "Dielectric" "")
    (property "License" "Apache-2.0")
    (property "MPN" "CC0201KRX6S5BB104")
    (property "Manufacturer" "Yaego")
    (property "Sheetfile" "fpga-power.kicad_sch")
    (property "Sheetname" "FPGA power")
    (property "Val" "100n")
    (property "Voltage" "")
    (property "ki_description" " ")
    (attr smd)
    (fp_text reference "C57" (at -10.350008 -18.06 90) (layer "B.SilkS")
        (effects (font (size 0.7 0.7) (thickness 0.15)) (justify left bottom mirror))
    )
    (fp_text value "C_100n_0201" (at 0 -1.4 90) (layer "B.Fab") hide
        (effects (font (size 0.7 0.7) (thickness 0.15)) (justify left bottom mirror))
    )
    (fp_text user "License: Apache-2.0" (at -0.72 -4.4 90) (layer "B.Fab") hide
        (effects (font (size 0.7 0.7) (thickness 0.15)) (justify left bottom mirror))
    )
    (fp_text user "Author: Antmicro" (at -0.72 -5.4 90) (layer "B.Fab") hide
        (effects (font (size 0.7 0.7) (thickness 0.15)) (justify left bottom mirror))
    )
    (fp_text user "${REFERENCE}" (at -0.72 -3.4 90) (layer "B.Fab") hide
        (effects (font (size 0.7 0.7) (thickness 0.15)) (justify left bottom mirror))
    )
    (fp_rect (start -0.72 0.38) (end 0.72 -0.38)
      (stroke (width 0.05) (type solid)) (fill none) (layer "B.CrtYd"))
    (fp_rect (start 0.3 -0.15) (end -0.301 0.149)
      (stroke (width 0.15) (type solid)) (fill none) (layer "B.Fab"))
    (pad "" smd roundrect (at -0.349 0.002 270) (size 0.318 0.36) (layers "B.Paste") (roundrect_rratio 0.25))
    (pad "" smd roundrect (at 0.341 0.002 270) (size 0.318 0.36) (layers "B.Paste") (roundrect_rratio 0.25))
    (pad "1" smd roundrect (at -0.321 0.002 270) (size 0.46 0.4) (layers "B.Cu" "B.Mask") (roundrect_rratio 0.25)
      (net 147 "1V0_SYS") (pintype "passive"))
    (pad "2" smd roundrect (at 0.32 0.002 270) (size 0.46 0.4) (layers "B.Cu" "B.Mask") (roundrect_rratio 0.25)
      (net 9 "GND") (pintype "passive"))
  )

  (footprint "data-center-rdimm-ddr4-tester-footprints:C_0201" (layer "B.Cu")
    (at 181.186328 88.560008 -90)
    (descr "Capacitor SMD 0201")
    (tags "capacitor SMD 0201")
    (property "Author" "Antmicro")
    (property "Dielectric" "")
    (property "License" "Apache-2.0")
    (property "MPN" "CC0201KRX6S5BB104")
    (property "Manufacturer" "Yaego")
    (property "Sheetfile" "fpga-power.kicad_sch")
    (property "Sheetname" "FPGA power")
    (property "Val" "100n")
    (property "Voltage" "")
    (property "ki_description" " ")
    (attr smd)
    (fp_text reference "C60" (at -10.300008 -18.093672 90) (layer "B.SilkS")
        (effects (font (size 0.7 0.7) (thickness 0.15)) (justify left bottom mirror))
    )
    (fp_text value "C_100n_0201" (at 0 -1.4 90) (layer "B.Fab") hide
        (effects (font (size 0.7 0.7) (thickness 0.15)) (justify left bottom mirror))
    )
    (fp_text user "${REFERENCE}" (at -0.72 -3.4 90) (layer "B.Fab") hide
        (effects (font (size 0.7 0.7) (thickness 0.15)) (justify left bottom mirror))
    )
    (fp_text user "License: Apache-2.0" (at -0.72 -4.4 90) (layer "B.Fab") hide
        (effects (font (size 0.7 0.7) (thickness 0.15)) (justify left bottom mirror))
    )
    (fp_text user "Author: Antmicro" (at -0.72 -5.4 90) (layer "B.Fab") hide
        (effects (font (size 0.7 0.7) (thickness 0.15)) (justify left bottom mirror))
    )
    (fp_rect (start -0.72 0.38) (end 0.72 -0.38)
      (stroke (width 0.05) (type solid)) (fill none) (layer "B.CrtYd"))
    (fp_rect (start 0.3 -0.15) (end -0.301 0.149)
      (stroke (width 0.15) (type solid)) (fill none) (layer "B.Fab"))
    (pad "" smd roundrect (at -0.349 0.002 270) (size 0.318 0.36) (layers "B.Paste") (roundrect_rratio 0.25))
    (pad "" smd roundrect (at 0.341 0.002 270) (size 0.318 0.36) (layers "B.Paste") (roundrect_rratio 0.25))
    (pad "1" smd roundrect (at -0.321 0.002 270) (size 0.46 0.4) (layers "B.Cu" "B.Mask") (roundrect_rratio 0.25)
      (net 147 "1V0_SYS") (pintype "passive"))
    (pad "2" smd roundrect (at 0.32 0.002 270) (size 0.46 0.4) (layers "B.Cu" "B.Mask") (roundrect_rratio 0.25)
      (net 9 "GND") (pintype "passive"))
  )

  (footprint "data-center-rdimm-ddr4-tester-footprints:C_0201" (layer "B.Cu")
    (at 182.186328 86.560008 90)
    (descr "Capacitor SMD 0201")
    (tags "capacitor SMD 0201")
    (property "Author" "Antmicro")
    (property "Dielectric" "")
    (property "License" "Apache-2.0")
    (property "MPN" "CC0201KRX6S5BB104")
    (property "Manufacturer" "Yaego")
    (property "Sheetfile" "fpga-power.kicad_sch")
    (property "Sheetname" "FPGA power")
    (property "Val" "100n")
    (property "Voltage" "")
    (property "ki_description" " ")
    (attr smd)
    (fp_text reference "C61" (at 10.300008 18.003672 270) (layer "B.SilkS")
        (effects (font (size 0.7 0.7) (thickness 0.15)) (justify left bottom mirror))
    )
    (fp_text value "C_100n_0201" (at 0 -1.4 270) (layer "B.Fab") hide
        (effects (font (size 0.7 0.7) (thickness 0.15)) (justify left bottom mirror))
    )
    (fp_text user "${REFERENCE}" (at -0.72 -3.4 270) (layer "B.Fab") hide
        (effects (font (size 0.7 0.7) (thickness 0.15)) (justify left bottom mirror))
    )
    (fp_text user "Author: Antmicro" (at -0.72 -5.4 270) (layer "B.Fab") hide
        (effects (font (size 0.7 0.7) (thickness 0.15)) (justify left bottom mirror))
    )
    (fp_text user "License: Apache-2.0" (at -0.72 -4.4 270) (layer "B.Fab") hide
        (effects (font (size 0.7 0.7) (thickness 0.15)) (justify left bottom mirror))
    )
    (fp_rect (start -0.72 0.38) (end 0.72 -0.38)
      (stroke (width 0.05) (type solid)) (fill none) (layer "B.CrtYd"))
    (fp_rect (start 0.3 -0.15) (end -0.301 0.149)
      (stroke (width 0.15) (type solid)) (fill none) (layer "B.Fab"))
    (pad "" smd roundrect (at -0.349 0.002 90) (size 0.318 0.36) (layers "B.Paste") (roundrect_rratio 0.25))
    (pad "" smd roundrect (at 0.341 0.002 90) (size 0.318 0.36) (layers "B.Paste") (roundrect_rratio 0.25))
    (pad "1" smd roundrect (at -0.321 0.002 90) (size 0.46 0.4) (layers "B.Cu" "B.Mask") (roundrect_rratio 0.25)
      (net 147 "1V0_SYS") (pintype "passive"))
    (pad "2" smd roundrect (at 0.32 0.002 90) (size 0.46 0.4) (layers "B.Cu" "B.Mask") (roundrect_rratio 0.25)
      (net 9 "GND") (pintype "passive"))
  )

  (footprint "data-center-rdimm-ddr4-tester-footprints:C_0201" (layer "B.Cu")
    (at 183.186328 88.560008 -90)
    (descr "Capacitor SMD 0201")
    (tags "capacitor SMD 0201")
    (property "Author" "Antmicro")
    (property "Dielectric" "")
    (property "License" "Apache-2.0")
    (property "MPN" "CC0201KRX6S5BB104")
    (property "Manufacturer" "Yaego")
    (property "Sheetfile" "fpga-power.kicad_sch")
    (property "Sheetname" "FPGA power")
    (property "Val" "100n")
    (property "Voltage" "")
    (property "ki_description" " ")
    (attr smd)
    (fp_text reference "C62" (at -10.270008 -18.053672 90) (layer "B.SilkS")
        (effects (font (size 0.7 0.7) (thickness 0.15)) (justify left bottom mirror))
    )
    (fp_text value "C_100n_0201" (at 0 -1.4 90) (layer "B.Fab") hide
        (effects (font (size 0.7 0.7) (thickness 0.15)) (justify left bottom mirror))
    )
    (fp_text user "Author: Antmicro" (at -0.72 -5.4 90) (layer "B.Fab") hide
        (effects (font (size 0.7 0.7) (thickness 0.15)) (justify left bottom mirror))
    )
    (fp_text user "${REFERENCE}" (at -0.72 -3.4 90) (layer "B.Fab") hide
        (effects (font (size 0.7 0.7) (thickness 0.15)) (justify left bottom mirror))
    )
    (fp_text user "License: Apache-2.0" (at -0.72 -4.4 90) (layer "B.Fab") hide
        (effects (font (size 0.7 0.7) (thickness 0.15)) (justify left bottom mirror))
    )
    (fp_rect (start -0.72 0.38) (end 0.72 -0.38)
      (stroke (width 0.05) (type solid)) (fill none) (layer "B.CrtYd"))
    (fp_rect (start 0.3 -0.15) (end -0.301 0.149)
      (stroke (width 0.15) (type solid)) (fill none) (layer "B.Fab"))
    (pad "" smd roundrect (at -0.349 0.002 270) (size 0.318 0.36) (layers "B.Paste") (roundrect_rratio 0.25))
    (pad "" smd roundrect (at 0.341 0.002 270) (size 0.318 0.36) (layers "B.Paste") (roundrect_rratio 0.25))
    (pad "1" smd roundrect (at -0.321 0.002 270) (size 0.46 0.4) (layers "B.Cu" "B.Mask") (roundrect_rratio 0.25)
      (net 147 "1V0_SYS") (pintype "passive"))
    (pad "2" smd roundrect (at 0.32 0.002 270) (size 0.46 0.4) (layers "B.Cu" "B.Mask") (roundrect_rratio 0.25)
      (net 9 "GND") (pintype "passive"))
  )

  (footprint "data-center-rdimm-ddr4-tester-footprints:C_0201" (layer "B.Cu")
    (at 183.186328 86.560008 -90)
    (descr "Capacitor SMD 0201")
    (tags "capacitor SMD 0201")
    (property "Author" "Antmicro")
    (property "Dielectric" "")
    (property "License" "Apache-2.0")
    (property "MPN" "CC0201KRX6S5BB104")
    (property "Manufacturer" "Yaego")
    (property "Sheetfile" "fpga-power.kicad_sch")
    (property "Sheetname" "FPGA power")
    (property "Val" "100n")
    (property "Voltage" "")
    (property "ki_description" " ")
    (attr smd)
    (fp_text reference "C63" (at -10.320008 -17.963672 90) (layer "B.SilkS")
        (effects (font (size 0.7 0.7) (thickness 0.15)) (justify left bottom mirror))
    )
    (fp_text value "C_100n_0201" (at 0 -1.4 90) (layer "B.Fab") hide
        (effects (font (size 0.7 0.7) (thickness 0.15)) (justify left bottom mirror))
    )
    (fp_text user "Author: Antmicro" (at -0.72 -5.4 90) (layer "B.Fab") hide
        (effects (font (size 0.7 0.7) (thickness 0.15)) (justify left bottom mirror))
    )
    (fp_text user "${REFERENCE}" (at -0.72 -3.4 90) (layer "B.Fab") hide
        (effects (font (size 0.7 0.7) (thickness 0.15)) (justify left bottom mirror))
    )
    (fp_text user "License: Apache-2.0" (at -0.72 -4.4 90) (layer "B.Fab") hide
        (effects (font (size 0.7 0.7) (thickness 0.15)) (justify left bottom mirror))
    )
    (fp_rect (start -0.72 0.38) (end 0.72 -0.38)
      (stroke (width 0.05) (type solid)) (fill none) (layer "B.CrtYd"))
    (fp_rect (start 0.3 -0.15) (end -0.301 0.149)
      (stroke (width 0.15) (type solid)) (fill none) (layer "B.Fab"))
    (pad "" smd roundrect (at -0.349 0.002 270) (size 0.318 0.36) (layers "B.Paste") (roundrect_rratio 0.25))
    (pad "" smd roundrect (at 0.341 0.002 270) (size 0.318 0.36) (layers "B.Paste") (roundrect_rratio 0.25))
    (pad "1" smd roundrect (at -0.321 0.002 270) (size 0.46 0.4) (layers "B.Cu" "B.Mask") (roundrect_rratio 0.25)
      (net 147 "1V0_SYS") (pintype "passive"))
    (pad "2" smd roundrect (at 0.32 0.002 270) (size 0.46 0.4) (layers "B.Cu" "B.Mask") (roundrect_rratio 0.25)
      (net 9 "GND") (pintype "passive"))
  )

  (footprint "data-center-rdimm-ddr4-tester-footprints:C_0201" (layer "B.Cu")
    (at 182.186328 91.560008 90)
    (descr "Capacitor SMD 0201")
    (tags "capacitor SMD 0201")
    (property "Author" "Antmicro")
    (property "Dielectric" "")
    (property "License" "Apache-2.0")
    (property "MPN" "CC0201KRX6S5BB104")
    (property "Manufacturer" "Yaego")
    (property "Sheetfile" "fpga-power.kicad_sch")
    (property "Sheetname" "FPGA power")
    (property "Val" "100n")
    (property "Voltage" "")
    (property "ki_description" " ")
    (attr smd)
    (fp_text reference "C65" (at 10.330008 18.403672 270) (layer "B.SilkS")
        (effects (font (size 0.7 0.7) (thickness 0.15)) (justify left bottom mirror))
    )
    (fp_text value "C_100n_0201" (at 0 -1.4 270) (layer "B.Fab") hide
        (effects (font (size 0.7 0.7) (thickness 0.15)) (justify left bottom mirror))
    )
    (fp_text user "${REFERENCE}" (at -0.72 -3.4 270) (layer "B.Fab") hide
        (effects (font (size 0.7 0.7) (thickness 0.15)) (justify left bottom mirror))
    )
    (fp_text user "License: Apache-2.0" (at -0.72 -4.4 270) (layer "B.Fab") hide
        (effects (font (size 0.7 0.7) (thickness 0.15)) (justify left bottom mirror))
    )
    (fp_text user "Author: Antmicro" (at -0.72 -5.4 270) (layer "B.Fab") hide
        (effects (font (size 0.7 0.7) (thickness 0.15)) (justify left bottom mirror))
    )
    (fp_rect (start -0.72 0.38) (end 0.72 -0.38)
      (stroke (width 0.05) (type solid)) (fill none) (layer "B.CrtYd"))
    (fp_rect (start 0.3 -0.15) (end -0.301 0.149)
      (stroke (width 0.15) (type solid)) (fill none) (layer "B.Fab"))
    (pad "" smd roundrect (at -0.349 0.002 90) (size 0.318 0.36) (layers "B.Paste") (roundrect_rratio 0.25))
    (pad "" smd roundrect (at 0.341 0.002 90) (size 0.318 0.36) (layers "B.Paste") (roundrect_rratio 0.25))
    (pad "1" smd roundrect (at -0.321 0.002 90) (size 0.46 0.4) (layers "B.Cu" "B.Mask") (roundrect_rratio 0.25)
      (net 147 "1V0_SYS") (pintype "passive"))
    (pad "2" smd roundrect (at 0.32 0.002 90) (size 0.46 0.4) (layers "B.Cu" "B.Mask") (roundrect_rratio 0.25)
      (net 9 "GND") (pintype "passive"))
  )

  (footprint "data-center-rdimm-ddr4-tester-footprints:C_0201" (layer "B.Cu")
    (at 183.186328 91.560008 -90)
    (descr "Capacitor SMD 0201")
    (tags "capacitor SMD 0201")
    (property "Author" "Antmicro")
    (property "Dielectric" "")
    (property "License" "Apache-2.0")
    (property "MPN" "CC0201KRX6S5BB104")
    (property "Manufacturer" "Yaego")
    (property "Sheetfile" "fpga-power.kicad_sch")
    (property "Sheetname" "FPGA power")
    (property "Val" "100n")
    (property "Voltage" "")
    (property "ki_description" " ")
    (attr smd)
    (fp_text reference "C66" (at -10.330008 -18.333672 90) (layer "B.SilkS")
        (effects (font (size 0.7 0.7) (thickness 0.15)) (justify left bottom mirror))
    )
    (fp_text value "C_100n_0201" (at 0 -1.4 90) (layer "B.Fab") hide
        (effects (font (size 0.7 0.7) (thickness 0.15)) (justify left bottom mirror))
    )
    (fp_text user "${REFERENCE}" (at -0.72 -3.4 90) (layer "B.Fab") hide
        (effects (font (size 0.7 0.7) (thickness 0.15)) (justify left bottom mirror))
    )
    (fp_text user "License: Apache-2.0" (at -0.72 -4.4 90) (layer "B.Fab") hide
        (effects (font (size 0.7 0.7) (thickness 0.15)) (justify left bottom mirror))
    )
    (fp_text user "Author: Antmicro" (at -0.72 -5.4 90) (layer "B.Fab") hide
        (effects (font (size 0.7 0.7) (thickness 0.15)) (justify left bottom mirror))
    )
    (fp_rect (start -0.72 0.38) (end 0.72 -0.38)
      (stroke (width 0.05) (type solid)) (fill none) (layer "B.CrtYd"))
    (fp_rect (start 0.3 -0.15) (end -0.301 0.149)
      (stroke (width 0.15) (type solid)) (fill none) (layer "B.Fab"))
    (pad "" smd roundrect (at -0.349 0.002 270) (size 0.318 0.36) (layers "B.Paste") (roundrect_rratio 0.25))
    (pad "" smd roundrect (at 0.341 0.002 270) (size 0.318 0.36) (layers "B.Paste") (roundrect_rratio 0.25))
    (pad "1" smd roundrect (at -0.321 0.002 270) (size 0.46 0.4) (layers "B.Cu" "B.Mask") (roundrect_rratio 0.25)
      (net 147 "1V0_SYS") (pintype "passive"))
    (pad "2" smd roundrect (at 0.32 0.002 270) (size 0.46 0.4) (layers "B.Cu" "B.Mask") (roundrect_rratio 0.25)
      (net 9 "GND") (pintype "passive"))
  )

  (footprint "data-center-rdimm-ddr4-tester-footprints:C_0201" (layer "B.Cu")
    (at 183.186328 93.560008 -90)
    (descr "Capacitor SMD 0201")
    (tags "capacitor SMD 0201")
    (property "Author" "Antmicro")
    (property "Dielectric" "")
    (property "License" "Apache-2.0")
    (property "MPN" "CC0201KRX6S5BB104")
    (property "Manufacturer" "Yaego")
    (property "Sheetfile" "fpga-power.kicad_sch")
    (property "Sheetname" "FPGA power")
    (property "Val" "100n")
    (property "Voltage" "")
    (property "ki_description" " ")
    (attr smd)
    (fp_text reference "C68" (at -10.340008 -18.383672 90) (layer "B.SilkS")
        (effects (font (size 0.7 0.7) (thickness 0.15)) (justify left bottom mirror))
    )
    (fp_text value "C_100n_0201" (at 0 -1.4 90) (layer "B.Fab") hide
        (effects (font (size 0.7 0.7) (thickness 0.15)) (justify left bottom mirror))
    )
    (fp_text user "License: Apache-2.0" (at -0.72 -4.4 90) (layer "B.Fab") hide
        (effects (font (size 0.7 0.7) (thickness 0.15)) (justify left bottom mirror))
    )
    (fp_text user "${REFERENCE}" (at -0.72 -3.4 90) (layer "B.Fab") hide
        (effects (font (size 0.7 0.7) (thickness 0.15)) (justify left bottom mirror))
    )
    (fp_text user "Author: Antmicro" (at -0.72 -5.4 90) (layer "B.Fab") hide
        (effects (font (size 0.7 0.7) (thickness 0.15)) (justify left bottom mirror))
    )
    (fp_rect (start -0.72 0.38) (end 0.72 -0.38)
      (stroke (width 0.05) (type solid)) (fill none) (layer "B.CrtYd"))
    (fp_rect (start 0.3 -0.15) (end -0.301 0.149)
      (stroke (width 0.15) (type solid)) (fill none) (layer "B.Fab"))
    (pad "" smd roundrect (at -0.349 0.002 270) (size 0.318 0.36) (layers "B.Paste") (roundrect_rratio 0.25))
    (pad "" smd roundrect (at 0.341 0.002 270) (size 0.318 0.36) (layers "B.Paste") (roundrect_rratio 0.25))
    (pad "1" smd roundrect (at -0.321 0.002 270) (size 0.46 0.4) (layers "B.Cu" "B.Mask") (roundrect_rratio 0.25)
      (net 147 "1V0_SYS") (pintype "passive"))
    (pad "2" smd roundrect (at 0.32 0.002 270) (size 0.46 0.4) (layers "B.Cu" "B.Mask") (roundrect_rratio 0.25)
      (net 9 "GND") (pintype "passive"))
  )

  (footprint "data-center-rdimm-ddr4-tester-footprints:C_0201" (layer "B.Cu")
    (at 184.186328 93.560008 90)
    (descr "Capacitor SMD 0201")
    (tags "capacitor SMD 0201")
    (property "Author" "Antmicro")
    (property "Dielectric" "")
    (property "License" "Apache-2.0")
    (property "MPN" "CC0201KRX6S5BB104")
    (property "Manufacturer" "Yaego")
    (property "Sheetfile" "fpga-power.kicad_sch")
    (property "Sheetname" "FPGA power")
    (property "Val" "100n")
    (property "Voltage" "")
    (property "ki_description" " ")
    (attr smd)
    (fp_text reference "C69" (at 10.360008 18.343672 270) (layer "B.SilkS")
        (effects (font (size 0.7 0.7) (thickness 0.15)) (justify left bottom mirror))
    )
    (fp_text value "C_100n_0201" (at 0 -1.4 270) (layer "B.Fab") hide
        (effects (font (size 0.7 0.7) (thickness 0.15)) (justify left bottom mirror))
    )
    (fp_text user "Author: Antmicro" (at -0.72 -5.4 270) (layer "B.Fab") hide
        (effects (font (size 0.7 0.7) (thickness 0.15)) (justify left bottom mirror))
    )
    (fp_text user "${REFERENCE}" (at -0.72 -3.4 270) (layer "B.Fab") hide
        (effects (font (size 0.7 0.7) (thickness 0.15)) (justify left bottom mirror))
    )
    (fp_text user "License: Apache-2.0" (at -0.72 -4.4 270) (layer "B.Fab") hide
        (effects (font (size 0.7 0.7) (thickness 0.15)) (justify left bottom mirror))
    )
    (fp_rect (start -0.72 0.38) (end 0.72 -0.38)
      (stroke (width 0.05) (type solid)) (fill none) (layer "B.CrtYd"))
    (fp_rect (start 0.3 -0.15) (end -0.301 0.149)
      (stroke (width 0.15) (type solid)) (fill none) (layer "B.Fab"))
    (pad "" smd roundrect (at -0.349 0.002 90) (size 0.318 0.36) (layers "B.Paste") (roundrect_rratio 0.25))
    (pad "" smd roundrect (at 0.341 0.002 90) (size 0.318 0.36) (layers "B.Paste") (roundrect_rratio 0.25))
    (pad "1" smd roundrect (at -0.321 0.002 90) (size 0.46 0.4) (layers "B.Cu" "B.Mask") (roundrect_rratio 0.25)
      (net 147 "1V0_SYS") (pintype "passive"))
    (pad "2" smd roundrect (at 0.32 0.002 90) (size 0.46 0.4) (layers "B.Cu" "B.Mask") (roundrect_rratio 0.25)
      (net 9 "GND") (pintype "passive"))
  )

  (footprint "data-center-rdimm-ddr4-tester-footprints:C_0201" (layer "B.Cu")
    (at 180.936328 93.710008 180)
    (descr "Capacitor SMD 0201")
    (tags "capacitor SMD 0201")
    (property "Author" "Antmicro")
    (property "Dielectric" "")
    (property "License" "Apache-2.0")
    (property "MPN" "CC0201KRX6S5BB104")
    (property "Manufacturer" "Yaego")
    (property "Sheetfile" "fpga-power.kicad_sch")
    (property "Sheetname" "FPGA power")
    (property "Val" "100n")
    (property "Voltage" "")
    (property "ki_description" " ")
    (attr smd)
    (fp_text reference "C70" (at 0.516328 -0.399992) (layer "B.SilkS")
        (effects (font (size 0.7 0.7) (thickness 0.15)) (justify left bottom mirror))
    )
    (fp_text value "C_100n_0201" (at 0 -1.4) (layer "B.Fab") hide
        (effects (font (size 0.7 0.7) (thickness 0.15)) (justify left bottom mirror))
    )
    (fp_text user "License: Apache-2.0" (at -0.72 -4.4) (layer "B.Fab") hide
        (effects (font (size 0.7 0.7) (thickness 0.15)) (justify left bottom mirror))
    )
    (fp_text user "${REFERENCE}" (at -0.72 -3.4) (layer "B.Fab") hide
        (effects (font (size 0.7 0.7) (thickness 0.15)) (justify left bottom mirror))
    )
    (fp_text user "Author: Antmicro" (at -0.72 -5.4) (layer "B.Fab") hide
        (effects (font (size 0.7 0.7) (thickness 0.15)) (justify left bottom mirror))
    )
    (fp_rect (start -0.72 0.38) (end 0.72 -0.38)
      (stroke (width 0.05) (type solid)) (fill none) (layer "B.CrtYd"))
    (fp_rect (start 0.3 -0.15) (end -0.301 0.149)
      (stroke (width 0.15) (type solid)) (fill none) (layer "B.Fab"))
    (pad "" smd roundrect (at -0.349 0.002 180) (size 0.318 0.36) (layers "B.Paste") (roundrect_rratio 0.25))
    (pad "" smd roundrect (at 0.341 0.002 180) (size 0.318 0.36) (layers "B.Paste") (roundrect_rratio 0.25))
    (pad "1" smd roundrect (at -0.321 0.002 180) (size 0.46 0.4) (layers "B.Cu" "B.Mask") (roundrect_rratio 0.25)
      (net 147 "1V0_SYS") (pintype "passive"))
    (pad "2" smd roundrect (at 0.32 0.002 180) (size 0.46 0.4) (layers "B.Cu" "B.Mask") (roundrect_rratio 0.25)
      (net 9 "GND") (pintype "passive"))
  )

  (footprint "data-center-rdimm-ddr4-tester-footprints:C_0201" (layer "B.Cu")
    (at 187.136328 94.510008 180)
    (descr "Capacitor SMD 0201")
    (tags "capacitor SMD 0201")
    (property "Author" "Antmicro")
    (property "Dielectric" "")
    (property "License" "Apache-2.0")
    (property "MPN" "CC0201KRX6S5BB104")
    (property "Manufacturer" "Yaego")
    (property "Sheetfile" "fpga-power.kicad_sch")
    (property "Sheetname" "FPGA power")
    (property "Val" "100n")
    (property "Voltage" "")
    (property "ki_description" " ")
    (attr smd)
    (fp_text reference "C77" (at -1.113672 -1.099992) (layer "B.SilkS")
        (effects (font (size 0.7 0.7) (thickness 0.15)) (justify left bottom mirror))
    )
    (fp_text value "C_100n_0201" (at 0 -1.4) (layer "B.Fab") hide
        (effects (font (size 0.7 0.7) (thickness 0.15)) (justify left bottom mirror))
    )
    (fp_text user "${REFERENCE}" (at -0.72 -3.4) (layer "B.Fab") hide
        (effects (font (size 0.7 0.7) (thickness 0.15)) (justify left bottom mirror))
    )
    (fp_text user "License: Apache-2.0" (at -0.72 -4.4) (layer "B.Fab") hide
        (effects (font (size 0.7 0.7) (thickness 0.15)) (justify left bottom mirror))
    )
    (fp_text user "Author: Antmicro" (at -0.72 -5.4) (layer "B.Fab") hide
        (effects (font (size 0.7 0.7) (thickness 0.15)) (justify left bottom mirror))
    )
    (fp_rect (start -0.72 0.38) (end 0.72 -0.38)
      (stroke (width 0.05) (type solid)) (fill none) (layer "B.CrtYd"))
    (fp_rect (start 0.3 -0.15) (end -0.301 0.149)
      (stroke (width 0.15) (type solid)) (fill none) (layer "B.Fab"))
    (pad "" smd roundrect (at -0.349 0.002 180) (size 0.318 0.36) (layers "B.Paste") (roundrect_rratio 0.25))
    (pad "" smd roundrect (at 0.341 0.002 180) (size 0.318 0.36) (layers "B.Paste") (roundrect_rratio 0.25))
    (pad "1" smd roundrect (at -0.321 0.002 180) (size 0.46 0.4) (layers "B.Cu" "B.Mask") (roundrect_rratio 0.25)
      (net 147 "1V0_SYS") (pintype "passive"))
    (pad "2" smd roundrect (at 0.32 0.002 180) (size 0.46 0.4) (layers "B.Cu" "B.Mask") (roundrect_rratio 0.25)
      (net 9 "GND") (pintype "passive"))
  )

  (footprint "data-center-rdimm-ddr4-tester-footprints:C_0402_1005Metric" (layer "B.Cu")
    (at 185.5 88.3 -90)
    (descr "Capacitor SMD 0402")
    (tags "capacitor SMD 0402")
    (property "Author" "Antmicro")
    (property "Dielectric" "")
    (property "License" "Apache-2.0")
    (property "MPN" "GRM155R61A475MEAAD")
    (property "Manufacturer" "Murata")
    (property "Sheetfile" "fpga-power.kicad_sch")
    (property "Sheetname" "FPGA power")
    (property "Val" "4u7")
    (property "Voltage" "")
    (property "ki_description" " ")
    (attr smd)
    (fp_text reference "C144" (at -10.49 -18.49 90) (layer "B.SilkS")
        (effects (font (size 0.7 0.7) (thickness 0.15)) (justify left bottom mirror))
    )
    (fp_text value "C_4u7_0402" (at 0 -1.4 90) (layer "B.Fab") hide
        (effects (font (size 0.7 0.7) (thickness 0.15)) (justify left bottom mirror))
    )
    (fp_text user "Author: Antmicro" (at -0.932 -4.17 90) (layer "B.Fab") hide
        (effects (font (size 0.7 0.7) (thickness 0.15)) (justify left bottom mirror))
    )
    (fp_text user "${REFERENCE}" (at -0.932 -3.168 90) (layer "B.Fab") hide
        (effects (font (size 0.7 0.7) (thickness 0.15)) (justify left bottom mirror))
    )
    (fp_text user "License: Apache-2.0" (at -0.932 -5.17 90) (layer "B.Fab") hide
        (effects (font (size 0.7 0.7) (thickness 0.15)) (justify left bottom mirror))
    )
    (fp_rect (start -0.94 0.47) (end 0.94 -0.47)
      (stroke (width 0.05) (type solid)) (fill none) (layer "B.CrtYd"))
    (fp_rect (start -0.499 0.249) (end 0.499 -0.249)
      (stroke (width 0.15) (type solid)) (fill none) (layer "B.Fab"))
    (pad "1" smd roundrect (at -0.484 0 270) (size 0.59 0.64) (layers "B.Cu" "B.Paste" "B.Mask") (roundrect_rratio 0.25)
      (net 147 "1V0_SYS") (pintype "passive"))
    (pad "2" smd roundrect (at 0.484 0 270) (size 0.59 0.64) (layers "B.Cu" "B.Paste" "B.Mask") (roundrect_rratio 0.25)
      (net 9 "GND") (pintype "passive"))
  )

  (footprint "data-center-rdimm-ddr4-tester-footprints:C_0402_1005Metric" (layer "B.Cu")
    (at 181.75 90.15)
    (descr "Capacitor SMD 0402")
    (tags "capacitor SMD 0402")
    (property "Author" "Antmicro")
    (property "Dielectric" "")
    (property "License" "Apache-2.0")
    (property "MPN" "GRM155R61A475MEAAD")
    (property "Manufacturer" "Murata")
    (property "Sheetfile" "fpga-power.kicad_sch")
    (property "Sheetname" "FPGA power")
    (property "Val" "4u7")
    (property "Voltage" "")
    (property "ki_description" " ")
    (attr smd)
    (fp_text reference "C14" (at 18.79 -8.96 180) (layer "B.SilkS")
        (effects (font (size 0.7 0.7) (thickness 0.15)) (justify left bottom mirror))
    )
    (fp_text value "C_4u7_0402" (at 0 -1.4 180) (layer "B.Fab") hide
        (effects (font (size 0.7 0.7) (thickness 0.15)) (justify left bottom mirror))
    )
    (fp_text user "${REFERENCE}" (at -0.932 -3.168 180) (layer "B.Fab") hide
        (effects (font (size 0.7 0.7) (thickness 0.15)) (justify left bottom mirror))
    )
    (fp_text user "License: Apache-2.0" (at -0.932 -5.17 180) (layer "B.Fab") hide
        (effects (font (size 0.7 0.7) (thickness 0.15)) (justify left bottom mirror))
    )
    (fp_text user "Author: Antmicro" (at -0.932 -4.17 180) (layer "B.Fab") hide
        (effects (font (size 0.7 0.7) (thickness 0.15)) (justify left bottom mirror))
    )
    (fp_rect (start -0.94 0.47) (end 0.94 -0.47)
      (stroke (width 0.05) (type solid)) (fill none) (layer "B.CrtYd"))
    (fp_rect (start -0.499 0.249) (end 0.499 -0.249)
      (stroke (width 0.15) (type solid)) (fill none) (layer "B.Fab"))
    (pad "1" smd roundrect (at -0.484 0) (size 0.59 0.64) (layers "B.Cu" "B.Paste" "B.Mask") (roundrect_rratio 0.25)
      (net 147 "1V0_SYS") (pintype "passive"))
    (pad "2" smd roundrect (at 0.484 0) (size 0.59 0.64) (layers "B.Cu" "B.Paste" "B.Mask") (roundrect_rratio 0.25)
      (net 9 "GND") (pintype "passive"))
  )

  (footprint "data-center-rdimm-ddr4-tester-footprints:C_0402_1005Metric" (layer "B.Cu")
    (at 193.75 88.725)
    (descr "Capacitor SMD 0402")
    (tags "capacitor SMD 0402")
    (property "Author" "Antmicro")
    (property "Dielectric" "")
    (property "License" "Apache-2.0")
    (property "MPN" "C1005X5R1E474M050BB")
    (property "Manufacturer" "TDK")
    (property "Sheetfile" "config-spi.kicad_sch")
    (property "Sheetname" "Config SPI flash")
    (property "Val" "470n")
    (property "Voltage" "")
    (property "ki_description" " ")
    (attr smd)
    (fp_text reference "C37" (at 3.05 0.355 180) (layer "B.SilkS")
        (effects (font (size 0.7 0.7) (thickness 0.15)) (justify left bottom mirror))
    )
    (fp_text value "C_470n_0402" (at 0 -1.4 180) (layer "B.Fab") hide
        (effects (font (size 0.7 0.7) (thickness 0.15)) (justify left bottom mirror))
    )
    (fp_text user "License: Apache-2.0" (at -0.932 -5.17 180) (layer "B.Fab") hide
        (effects (font (size 0.7 0.7) (thickness 0.15)) (justify left bottom mirror))
    )
    (fp_text user "${REFERENCE}" (at -0.932 -3.168 180) (layer "B.Fab") hide
        (effects (font (size 0.7 0.7) (thickness 0.15)) (justify left bottom mirror))
    )
    (fp_text user "Author: Antmicro" (at -0.932 -4.17 180) (layer "B.Fab") hide
        (effects (font (size 0.7 0.7) (thickness 0.15)) (justify left bottom mirror))
    )
    (fp_rect (start -0.94 0.47) (end 0.94 -0.47)
      (stroke (width 0.05) (type solid)) (fill none) (layer "B.CrtYd"))
    (fp_rect (start -0.499 0.249) (end 0.499 -0.249)
      (stroke (width 0.15) (type solid)) (fill none) (layer "B.Fab"))
    (pad "1" smd roundrect (at -0.484 0) (size 0.59 0.64) (layers "B.Cu" "B.Paste" "B.Mask") (roundrect_rratio 0.25)
      (net 143 "3V3_SYS") (pintype "passive"))
    (pad "2" smd roundrect (at 0.484 0) (size 0.59 0.64) (layers "B.Cu" "B.Paste" "B.Mask") (roundrect_rratio 0.25)
      (net 9 "GND") (pintype "passive"))
  )

  (footprint "data-center-rdimm-ddr4-tester-footprints:C_0402_1005Metric" (layer "B.Cu")
    (at 158.236328 79.860008 180)
    (descr "Capacitor SMD 0402")
    (tags "capacitor SMD 0402")
    (property "Author" "Antmicro")
    (property "Dielectric" "X5R")
    (property "License" "Apache-2.0")
    (property "MPN" "GRM155R61H104KE14D")
    (property "Manufacturer" "Murata")
    (property "Sheetfile" "hyperram.kicad_sch")
    (property "Sheetname" "HyperRAM")
    (property "Val" "100n")
    (property "Voltage" "50V")
    (property "ki_description" " ")
    (attr smd)
    (fp_text reference "C103" (at -1.32 0.59) (layer "B.SilkS")
        (effects (font (size 0.7 0.7) (thickness 0.15)) (justify left bottom mirror))
    )
    (fp_text value "C_100n_0402" (at 0 -1.4) (layer "B.Fab") hide
        (effects (font (size 0.7 0.7) (thickness 0.15)) (justify left bottom mirror))
    )
    (fp_text user "License: Apache-2.0" (at -0.932 -5.17) (layer "B.Fab") hide
        (effects (font (size 0.7 0.7) (thickness 0.15)) (justify left bottom mirror))
    )
    (fp_text user "Author: Antmicro" (at -0.932 -4.17) (layer "B.Fab") hide
        (effects (font (size 0.7 0.7) (thickness 0.15)) (justify left bottom mirror))
    )
    (fp_text user "${REFERENCE}" (at -0.932 -3.168) (layer "B.Fab") hide
        (effects (font (size 0.7 0.7) (thickness 0.15)) (justify left bottom mirror))
    )
    (fp_rect (start -0.94 0.47) (end 0.94 -0.47)
      (stroke (width 0.05) (type solid)) (fill none) (layer "B.CrtYd"))
    (fp_rect (start -0.499 0.249) (end 0.499 -0.249)
      (stroke (width 0.15) (type solid)) (fill none) (layer "B.Fab"))
    (pad "1" smd roundrect (at -0.484 0 180) (size 0.59 0.64) (layers "B.Cu" "B.Paste" "B.Mask") (roundrect_rratio 0.25)
      (net 143 "3V3_SYS") (pintype "passive"))
    (pad "2" smd roundrect (at 0.484 0 180) (size 0.59 0.64) (layers "B.Cu" "B.Paste" "B.Mask") (roundrect_rratio 0.25)
      (net 9 "GND") (pintype "passive"))
  )

  (footprint "data-center-rdimm-ddr4-tester-footprints:C_0402_1005Metric" locked (layer "B.Cu")
    (at 155.0156 82.5632 90)
    (descr "Capacitor SMD 0402")
    (tags "capacitor SMD 0402")
    (property "Author" "Antmicro")
    (property "Dielectric" "X5R")
    (property "License" "Apache-2.0")
    (property "MPN" "GRM155R61H104KE14D")
    (property "Manufacturer" "Murata")
    (property "Sheetfile" "hyperram.kicad_sch")
    (property "Sheetname" "HyperRAM")
    (property "Val" "100n")
    (property "Voltage" "50V")
    (property "ki_description" " ")
    (attr smd)
    (fp_text reference "C104" (at 1.2832 1.3144 270) (layer "B.SilkS")
        (effects (font (size 0.7 0.7) (thickness 0.15)) (justify left bottom mirror))
    )
    (fp_text value "C_100n_0402" (at 0 -1.4 270) (layer "B.Fab") hide
        (effects (font (size 0.7 0.7) (thickness 0.15)) (justify left bottom mirror))
    )
    (fp_text user "Author: Antmicro" (at -0.932 -4.17 270) (layer "B.Fab") hide
        (effects (font (size 0.7 0.7) (thickness 0.15)) (justify left bottom mirror))
    )
    (fp_text user "${REFERENCE}" (at -0.932 -3.168 270) (layer "B.Fab") hide
        (effects (font (size 0.7 0.7) (thickness 0.15)) (justify left bottom mirror))
    )
    (fp_text user "License: Apache-2.0" (at -0.932 -5.17 270) (layer "B.Fab") hide
        (effects (font (size 0.7 0.7) (thickness 0.15)) (justify left bottom mirror))
    )
    (fp_rect (start -0.94 0.47) (end 0.94 -0.47)
      (stroke (width 0.05) (type solid)) (fill none) (layer "B.CrtYd"))
    (fp_rect (start -0.499 0.249) (end 0.499 -0.249)
      (stroke (width 0.15) (type solid)) (fill none) (layer "B.Fab"))
    (pad "1" smd roundrect locked (at -0.484 0 90) (size 0.59 0.64) (layers "B.Cu" "B.Paste" "B.Mask") (roundrect_rratio 0.25)
      (net 143 "3V3_SYS") (pintype "passive"))
    (pad "2" smd roundrect locked (at 0.484 0 90) (size 0.59 0.64) (layers "B.Cu" "B.Paste" "B.Mask") (roundrect_rratio 0.25)
      (net 9 "GND") (pintype "passive"))
  )

  (footprint "data-center-rdimm-ddr4-tester-footprints:C_0402_1005Metric" (layer "B.Cu")
    (at 153.7 79.1 180)
    (descr "Capacitor SMD 0402")
    (tags "capacitor SMD 0402")
    (property "Author" "Antmicro")
    (property "Dielectric" "X5R")
    (property "License" "Apache-2.0")
    (property "MPN" "GRM155R61H104KE14D")
    (property "Manufacturer" "Murata")
    (property "Sheetfile" "hyperram.kicad_sch")
    (property "Sheetname" "HyperRAM")
    (property "Val" "100n")
    (property "Voltage" "50V")
    (property "ki_description" " ")
    (attr smd)
    (fp_text reference "C105" (at -1.32 0.59) (layer "B.SilkS")
        (effects (font (size 0.7 0.7) (thickness 0.15)) (justify left bottom mirror))
    )
    (fp_text value "C_100n_0402" (at 0 -1.4) (layer "B.Fab") hide
        (effects (font (size 0.7 0.7) (thickness 0.15)) (justify left bottom mirror))
    )
    (fp_text user "Author: Antmicro" (at -0.932 -4.17) (layer "B.Fab") hide
        (effects (font (size 0.7 0.7) (thickness 0.15)) (justify left bottom mirror))
    )
    (fp_text user "${REFERENCE}" (at -0.932 -3.168) (layer "B.Fab") hide
        (effects (font (size 0.7 0.7) (thickness 0.15)) (justify left bottom mirror))
    )
    (fp_text user "License: Apache-2.0" (at -0.932 -5.17) (layer "B.Fab") hide
        (effects (font (size 0.7 0.7) (thickness 0.15)) (justify left bottom mirror))
    )
    (fp_rect (start -0.94 0.47) (end 0.94 -0.47)
      (stroke (width 0.05) (type solid)) (fill none) (layer "B.CrtYd"))
    (fp_rect (start -0.499 0.249) (end 0.499 -0.249)
      (stroke (width 0.15) (type solid)) (fill none) (layer "B.Fab"))
    (pad "1" smd roundrect (at -0.484 0 180) (size 0.59 0.64) (layers "B.Cu" "B.Paste" "B.Mask") (roundrect_rratio 0.25)
      (net 143 "3V3_SYS") (pintype "passive"))
    (pad "2" smd roundrect (at 0.484 0 180) (size 0.59 0.64) (layers "B.Cu" "B.Paste" "B.Mask") (roundrect_rratio 0.25)
      (net 9 "GND") (pintype "passive"))
  )

  (footprint "data-center-rdimm-ddr4-tester-footprints:C_0201" (layer "B.Cu")
    (at 184.186328 86.560008 90)
    (descr "Capacitor SMD 0201")
    (tags "capacitor SMD 0201")
    (property "Author" "Antmicro")
    (property "Dielectric" "")
    (property "License" "Apache-2.0")
    (property "MPN" "CC0201KRX6S5BB104")
    (property "Manufacturer" "Yaego")
    (property "Sheetfile" "fpga-power.kicad_sch")
    (property "Sheetname" "FPGA power")
    (property "Val" "100n")
    (property "Voltage" "")
    (property "ki_description" " ")
    (attr smd)
    (fp_text reference "C58" (at 10.320008 17.933672 270) (layer "B.SilkS")
        (effects (font (size 0.7 0.7) (thickness 0.15)) (justify left bottom mirror))
    )
    (fp_text value "C_100n_0201" (at 0 -1.4 270) (layer "B.Fab") hide
        (effects (font (size 0.7 0.7) (thickness 0.15)) (justify left bottom mirror))
    )
    (fp_text user "${REFERENCE}" (at -0.72 -3.4 270) (layer "B.Fab") hide
        (effects (font (size 0.7 0.7) (thickness 0.15)) (justify left bottom mirror))
    )
    (fp_text user "License: Apache-2.0" (at -0.72 -4.4 270) (layer "B.Fab") hide
        (effects (font (size 0.7 0.7) (thickness 0.15)) (justify left bottom mirror))
    )
    (fp_text user "Author: Antmicro" (at -0.72 -5.4 270) (layer "B.Fab") hide
        (effects (font (size 0.7 0.7) (thickness 0.15)) (justify left bottom mirror))
    )
    (fp_rect (start -0.72 0.38) (end 0.72 -0.38)
      (stroke (width 0.05) (type solid)) (fill none) (layer "B.CrtYd"))
    (fp_rect (start 0.3 -0.15) (end -0.301 0.149)
      (stroke (width 0.15) (type solid)) (fill none) (layer "B.Fab"))
    (pad "" smd roundrect (at -0.349 0.002 90) (size 0.318 0.36) (layers "B.Paste") (roundrect_rratio 0.25))
    (pad "" smd roundrect (at 0.341 0.002 90) (size 0.318 0.36) (layers "B.Paste") (roundrect_rratio 0.25))
    (pad "1" smd roundrect (at -0.321 0.002 90) (size 0.46 0.4) (layers "B.Cu" "B.Mask") (roundrect_rratio 0.25)
      (net 147 "1V0_SYS") (pintype "passive"))
    (pad "2" smd roundrect (at 0.32 0.002 90) (size 0.46 0.4) (layers "B.Cu" "B.Mask") (roundrect_rratio 0.25)
      (net 9 "GND") (pintype "passive"))
  )

  (footprint "data-center-rdimm-ddr4-tester-footprints:C_0201" (layer "B.Cu")
    (at 181.186328 91.560008 -90)
    (descr "Capacitor SMD 0201")
    (tags "capacitor SMD 0201")
    (property "Author" "Antmicro")
    (property "Dielectric" "")
    (property "License" "Apache-2.0")
    (property "MPN" "CC0201KRX6S5BB104")
    (property "Manufacturer" "Yaego")
    (property "Sheetfile" "fpga-power.kicad_sch")
    (property "Sheetname" "FPGA power")
    (property "Val" "100n")
    (property "Voltage" "")
    (property "ki_description" " ")
    (attr smd)
    (fp_text reference "C64" (at -10.240008 -18.473672 90) (layer "B.SilkS")
        (effects (font (size 0.7 0.7) (thickness 0.15)) (justify left bottom mirror))
    )
    (fp_text value "C_100n_0201" (at 0 -1.4 90) (layer "B.Fab") hide
        (effects (font (size 0.7 0.7) (thickness 0.15)) (justify left bottom mirror))
    )
    (fp_text user "${REFERENCE}" (at -0.72 -3.4 90) (layer "B.Fab") hide
        (effects (font (size 0.7 0.7) (thickness 0.15)) (justify left bottom mirror))
    )
    (fp_text user "Author: Antmicro" (at -0.72 -5.4 90) (layer "B.Fab") hide
        (effects (font (size 0.7 0.7) (thickness 0.15)) (justify left bottom mirror))
    )
    (fp_text user "License: Apache-2.0" (at -0.72 -4.4 90) (layer "B.Fab") hide
        (effects (font (size 0.7 0.7) (thickness 0.15)) (justify left bottom mirror))
    )
    (fp_rect (start -0.72 0.38) (end 0.72 -0.38)
      (stroke (width 0.05) (type solid)) (fill none) (layer "B.CrtYd"))
    (fp_rect (start 0.3 -0.15) (end -0.301 0.149)
      (stroke (width 0.15) (type solid)) (fill none) (layer "B.Fab"))
    (pad "" smd roundrect (at -0.349 0.002 270) (size 0.318 0.36) (layers "B.Paste") (roundrect_rratio 0.25))
    (pad "" smd roundrect (at 0.341 0.002 270) (size 0.318 0.36) (layers "B.Paste") (roundrect_rratio 0.25))
    (pad "1" smd roundrect (at -0.321 0.002 270) (size 0.46 0.4) (layers "B.Cu" "B.Mask") (roundrect_rratio 0.25)
      (net 147 "1V0_SYS") (pintype "passive"))
    (pad "2" smd roundrect (at 0.32 0.002 270) (size 0.46 0.4) (layers "B.Cu" "B.Mask") (roundrect_rratio 0.25)
      (net 9 "GND") (pintype "passive"))
  )

  (footprint "data-center-rdimm-ddr4-tester-footprints:C_0201" (layer "B.Cu")
    (at 195.636328 78.010008 90)
    (descr "Capacitor SMD 0201")
    (tags "capacitor SMD 0201")
    (property "Author" "Antmicro")
    (property "Dielectric" "")
    (property "License" "Apache-2.0")
    (property "MPN" "CC0201KRX6S5BB104")
    (property "Manufacturer" "Yaego")
    (property "Sheetfile" "fpga-power.kicad_sch")
    (property "Sheetname" "FPGA power")
    (property "Val" "100n")
    (property "Voltage" "")
    (property "ki_description" " ")
    (attr smd)
    (fp_text reference "C34" (at 2.830008 0.333672 270) (layer "B.SilkS")
        (effects (font (size 0.7 0.7) (thickness 0.15)) (justify left bottom mirror))
    )
    (fp_text value "C_100n_0201" (at 0 -1.4 270) (layer "B.Fab") hide
        (effects (font (size 0.7 0.7) (thickness 0.15)) (justify left bottom mirror))
    )
    (fp_text user "Author: Antmicro" (at -0.72 -5.4 270) (layer "B.Fab") hide
        (effects (font (size 0.7 0.7) (thickness 0.15)) (justify left bottom mirror))
    )
    (fp_text user "${REFERENCE}" (at -0.72 -3.4 270) (layer "B.Fab") hide
        (effects (font (size 0.7 0.7) (thickness 0.15)) (justify left bottom mirror))
    )
    (fp_text user "License: Apache-2.0" (at -0.72 -4.4 270) (layer "B.Fab") hide
        (effects (font (size 0.7 0.7) (thickness 0.15)) (justify left bottom mirror))
    )
    (fp_rect (start -0.72 0.38) (end 0.72 -0.38)
      (stroke (width 0.05) (type solid)) (fill none) (layer "B.CrtYd"))
    (fp_rect (start 0.3 -0.15) (end -0.301 0.149)
      (stroke (width 0.15) (type solid)) (fill none) (layer "B.Fab"))
    (pad "" smd roundrect (at -0.349 0.002 90) (size 0.318 0.36) (layers "B.Paste") (roundrect_rratio 0.25))
    (pad "" smd roundrect (at 0.341 0.002 90) (size 0.318 0.36) (layers "B.Paste") (roundrect_rratio 0.25))
    (pad "1" smd roundrect (at -0.321 0.002 90) (size 0.46 0.4) (layers "B.Cu" "B.Mask") (roundrect_rratio 0.25)
      (net 77 "VDDQ") (pintype "passive"))
    (pad "2" smd roundrect (at 0.32 0.002 90) (size 0.46 0.4) (layers "B.Cu" "B.Mask") (roundrect_rratio 0.25)
      (net 9 "GND") (pintype "passive"))
  )

  (footprint "data-center-rdimm-ddr4-tester-footprints:C_0603_1608Metric" (layer "B.Cu")
    (at 174.936328 97.360008)
    (descr "Capacitor SMD 0603")
    (tags "capacitor 0603")
    (property "Author" "Antmicro")
    (property "Dielectric" "")
    (property "License" "Apache-2.0")
    (property "MPN" "GRM188R60J476ME15D")
    (property "Manufacturer" "Murata")
    (property "Sheetfile" "fpga-power.kicad_sch")
    (property "Sheetname" "FPGA power")
    (property "Val" "47u")
    (property "Voltage" "")
    (property "ki_description" " ")
    (attr smd)
    (fp_text reference "C3" (at 2.523672 0.489992 180) (layer "B.SilkS")
        (effects (font (size 0.7 0.7) (thickness 0.15)) (justify left bottom mirror))
    )
    (fp_text value "C_47u_0603" (at 0 -1.6 180) (layer "B.Fab") hide
        (effects (font (size 0.7 0.7) (thickness 0.15)) (justify left bottom mirror))
    )
    (fp_text user "${REFERENCE}" (at -1.682 -3.895 180) (layer "B.Fab") hide
        (effects (font (size 0.7 0.7) (thickness 0.15)) (justify left bottom mirror))
    )
    (fp_text user "Author: Antmicro" (at -1.682 -4.894 180) (layer "B.Fab") hide
        (effects (font (size 0.7 0.7) (thickness 0.15)) (justify left bottom mirror))
    )
    (fp_text user "License: Apache-2.0" (at -1.682 -5.895 180) (layer "B.Fab") hide
        (effects (font (size 0.7 0.7) (thickness 0.15)) (justify left bottom mirror))
    )
    (fp_line (start -0.3 -0.3) (end 0.3 -0.3)
      (stroke (width 0.15) (type solid)) (layer "B.SilkS"))
    (fp_line (start -0.3 0.3) (end 0.3 0.3)
      (stroke (width 0.15) (type solid)) (layer "B.SilkS"))
    (fp_rect (start -1.24 0.7) (end 1.24 -0.7)
      (stroke (width 0.05) (type solid)) (fill none) (layer "B.CrtYd"))
    (fp_rect (start -0.8 0.4) (end 0.8 -0.4)
      (stroke (width 0.15) (type solid)) (fill none) (layer "B.Fab"))
    (pad "1" smd roundrect (at -0.7 0) (size 0.6 0.8) (layers "B.Cu" "B.Paste" "B.Mask") (roundrect_rratio 0.2)
      (net 143 "3V3_SYS") (pintype "passive"))
    (pad "2" smd roundrect (at 0.7 0) (size 0.6 0.8) (layers "B.Cu" "B.Paste" "B.Mask") (roundrect_rratio 0.2)
      (net 9 "GND") (pintype "passive"))
  )

  (footprint "data-center-rdimm-ddr4-tester-footprints:C_0603_1608Metric" (layer "B.Cu")
    (at 176.825 83.7 90)
    (descr "Capacitor SMD 0603")
    (tags "capacitor 0603")
    (property "Author" "Antmicro")
    (property "Dielectric" "")
    (property "License" "Apache-2.0")
    (property "MPN" "GRM188R60J476ME15D")
    (property "Manufacturer" "Murata")
    (property "Sheetfile" "fpga-power.kicad_sch")
    (property "Sheetname" "FPGA power")
    (property "Val" "47u")
    (property "Voltage" "")
    (property "ki_description" " ")
    (attr smd)
    (fp_text reference "C6" (at 2.54 0.355 270) (layer "B.SilkS")
        (effects (font (size 0.7 0.7) (thickness 0.15)) (justify left bottom mirror))
    )
    (fp_text value "C_47u_0603" (at 0 -1.6 270) (layer "B.Fab") hide
        (effects (font (size 0.7 0.7) (thickness 0.15)) (justify left bottom mirror))
    )
    (fp_text user "License: Apache-2.0" (at -1.682 -5.895 270) (layer "B.Fab") hide
        (effects (font (size 0.7 0.7) (thickness 0.15)) (justify left bottom mirror))
    )
    (fp_text user "Author: Antmicro" (at -1.682 -4.894 270) (layer "B.Fab") hide
        (effects (font (size 0.7 0.7) (thickness 0.15)) (justify left bottom mirror))
    )
    (fp_text user "${REFERENCE}" (at -1.682 -3.895 270) (layer "B.Fab") hide
        (effects (font (size 0.7 0.7) (thickness 0.15)) (justify left bottom mirror))
    )
    (fp_line (start -0.3 -0.3) (end 0.3 -0.3)
      (stroke (width 0.15) (type solid)) (layer "B.SilkS"))
    (fp_line (start -0.3 0.3) (end 0.3 0.3)
      (stroke (width 0.15) (type solid)) (layer "B.SilkS"))
    (fp_rect (start -1.24 0.7) (end 1.24 -0.7)
      (stroke (width 0.05) (type solid)) (fill none) (layer "B.CrtYd"))
    (fp_rect (start -0.8 0.4) (end 0.8 -0.4)
      (stroke (width 0.15) (type solid)) (fill none) (layer "B.Fab"))
    (pad "1" smd roundrect (at -0.7 0 90) (size 0.6 0.8) (layers "B.Cu" "B.Paste" "B.Mask") (roundrect_rratio 0.2)
      (net 143 "3V3_SYS") (pintype "passive"))
    (pad "2" smd roundrect (at 0.7 0 90) (size 0.6 0.8) (layers "B.Cu" "B.Paste" "B.Mask") (roundrect_rratio 0.2)
      (net 9 "GND") (pintype "passive"))
  )

  (footprint "data-center-rdimm-ddr4-tester-footprints:C_0402_1005Metric" (layer "B.Cu")
    (at 185.086328 92.975008 -90)
    (descr "Capacitor SMD 0402")
    (tags "capacitor SMD 0402")
    (property "Author" "Antmicro")
    (property "Dielectric" "")
    (property "License" "Apache-2.0")
    (property "MPN" "GRM155R61A475MEAAD")
    (property "Manufacturer" "Murata")
    (property "Sheetfile" "fpga-power.kicad_sch")
    (property "Sheetname" "FPGA power")
    (property "Val" "4u7")
    (property "Voltage" "")
    (property "ki_description" " ")
    (attr smd)
    (fp_text reference "C7" (at -9.855008 -18.433672 90) (layer "B.SilkS")
        (effects (font (size 0.7 0.7) (thickness 0.15)) (justify left bottom mirror))
    )
    (fp_text value "C_4u7_0402" (at 0 -1.4 90) (layer "B.Fab") hide
        (effects (font (size 0.7 0.7) (thickness 0.15)) (justify left bottom mirror))
    )
    (fp_text user "${REFERENCE}" (at -0.932 -3.168 90) (layer "B.Fab") hide
        (effects (font (size 0.7 0.7) (thickness 0.15)) (justify left bottom mirror))
    )
    (fp_text user "License: Apache-2.0" (at -0.932 -5.17 90) (layer "B.Fab") hide
        (effects (font (size 0.7 0.7) (thickness 0.15)) (justify left bottom mirror))
    )
    (fp_text user "Author: Antmicro" (at -0.932 -4.17 90) (layer "B.Fab") hide
        (effects (font (size 0.7 0.7) (thickness 0.15)) (justify left bottom mirror))
    )
    (fp_rect (start -0.94 0.47) (end 0.94 -0.47)
      (stroke (width 0.05) (type solid)) (fill none) (layer "B.CrtYd"))
    (fp_rect (start -0.499 0.249) (end 0.499 -0.249)
      (stroke (width 0.15) (type solid)) (fill none) (layer "B.Fab"))
    (pad "1" smd roundrect (at -0.484 0 270) (size 0.59 0.64) (layers "B.Cu" "B.Paste" "B.Mask") (roundrect_rratio 0.25)
      (net 144 "1V8_SYS") (pintype "passive"))
    (pad "2" smd roundrect (at 0.484 0 270) (size 0.59 0.64) (layers "B.Cu" "B.Paste" "B.Mask") (roundrect_rratio 0.25)
      (net 9 "GND") (pintype "passive"))
  )

  (footprint "data-center-rdimm-ddr4-tester-footprints:C_0201" (layer "B.Cu")
    (at 186.95 87.45 180)
    (descr "Capacitor SMD 0201")
    (tags "capacitor SMD 0201")
    (property "Author" "Antmicro")
    (property "Dielectric" "")
    (property "License" "Apache-2.0")
    (property "MPN" "CC0201KRX6S5BB104")
    (property "Manufacturer" "Yaego")
    (property "Sheetfile" "fpga-power.kicad_sch")
    (property "Sheetname" "FPGA power")
    (property "Val" "100n")
    (property "Voltage" "")
    (property "ki_description" " ")
    (attr smd)
    (fp_text reference "C9" (at -18.58 9.37) (layer "B.SilkS")
        (effects (font (size 0.7 0.7) (thickness 0.15)) (justify left bottom mirror))
    )
    (fp_text value "C_100n_0201" (at 0 -1.4) (layer "B.Fab") hide
        (effects (font (size 0.7 0.7) (thickness 0.15)) (justify left bottom mirror))
    )
    (fp_text user "License: Apache-2.0" (at -0.72 -4.4) (layer "B.Fab") hide
        (effects (font (size 0.7 0.7) (thickness 0.15)) (justify left bottom mirror))
    )
    (fp_text user "Author: Antmicro" (at -0.72 -5.4) (layer "B.Fab") hide
        (effects (font (size 0.7 0.7) (thickness 0.15)) (justify left bottom mirror))
    )
    (fp_text user "${REFERENCE}" (at -0.72 -3.4) (layer "B.Fab") hide
        (effects (font (size 0.7 0.7) (thickness 0.15)) (justify left bottom mirror))
    )
    (fp_rect (start -0.72 0.38) (end 0.72 -0.38)
      (stroke (width 0.05) (type solid)) (fill none) (layer "B.CrtYd"))
    (fp_rect (start 0.3 -0.15) (end -0.301 0.149)
      (stroke (width 0.15) (type solid)) (fill none) (layer "B.Fab"))
    (pad "" smd roundrect (at -0.349 0.002 180) (size 0.318 0.36) (layers "B.Paste") (roundrect_rratio 0.25))
    (pad "" smd roundrect (at 0.341 0.002 180) (size 0.318 0.36) (layers "B.Paste") (roundrect_rratio 0.25))
    (pad "1" smd roundrect (at -0.321 0.002 180) (size 0.46 0.4) (layers "B.Cu" "B.Mask") (roundrect_rratio 0.25)
      (net 144 "1V8_SYS") (pintype "passive"))
    (pad "2" smd roundrect (at 0.32 0.002 180) (size 0.46 0.4) (layers "B.Cu" "B.Mask") (roundrect_rratio 0.25)
      (net 9 "GND") (pintype "passive"))
  )

  (footprint "data-center-rdimm-ddr4-tester-footprints:C_0201" (layer "B.Cu")
    (at 189.086328 89.560008 90)
    (descr "Capacitor SMD 0201")
    (tags "capacitor SMD 0201")
    (property "Author" "Antmicro")
    (property "Dielectric" "")
    (property "License" "Apache-2.0")
    (property "MPN" "CC0201KRX6S5BB104")
    (property "Manufacturer" "Yaego")
    (property "Sheetfile" "fpga-power.kicad_sch")
    (property "Sheetname" "FPGA power")
    (property "Val" "100n")
    (property "Voltage" "")
    (property "ki_description" " ")
    (attr smd)
    (fp_text reference "C11" (at 10.120008 18.163672 270) (layer "B.SilkS")
        (effects (font (size 0.7 0.7) (thickness 0.15)) (justify left bottom mirror))
    )
    (fp_text value "C_100n_0201" (at 0 -1.4 270) (layer "B.Fab") hide
        (effects (font (size 0.7 0.7) (thickness 0.15)) (justify left bottom mirror))
    )
    (fp_text user "License: Apache-2.0" (at -0.72 -4.4 270) (layer "B.Fab") hide
        (effects (font (size 0.7 0.7) (thickness 0.15)) (justify left bottom mirror))
    )
    (fp_text user "Author: Antmicro" (at -0.72 -5.4 270) (layer "B.Fab") hide
        (effects (font (size 0.7 0.7) (thickness 0.15)) (justify left bottom mirror))
    )
    (fp_text user "${REFERENCE}" (at -0.72 -3.4 270) (layer "B.Fab") hide
        (effects (font (size 0.7 0.7) (thickness 0.15)) (justify left bottom mirror))
    )
    (fp_rect (start -0.72 0.38) (end 0.72 -0.38)
      (stroke (width 0.05) (type solid)) (fill none) (layer "B.CrtYd"))
    (fp_rect (start 0.3 -0.15) (end -0.301 0.149)
      (stroke (width 0.15) (type solid)) (fill none) (layer "B.Fab"))
    (pad "" smd roundrect (at -0.349 0.002 90) (size 0.318 0.36) (layers "B.Paste") (roundrect_rratio 0.25))
    (pad "" smd roundrect (at 0.341 0.002 90) (size 0.318 0.36) (layers "B.Paste") (roundrect_rratio 0.25))
    (pad "1" smd roundrect (at -0.321 0.002 90) (size 0.46 0.4) (layers "B.Cu" "B.Mask") (roundrect_rratio 0.25)
      (net 144 "1V8_SYS") (pintype "passive"))
    (pad "2" smd roundrect (at 0.32 0.002 90) (size 0.46 0.4) (layers "B.Cu" "B.Mask") (roundrect_rratio 0.25)
      (net 9 "GND") (pintype "passive"))
  )

  (footprint "data-center-rdimm-ddr4-tester-footprints:C_0603_1608Metric" (layer "B.Cu")
    (at 184.936328 101.960008 180)
    (descr "Capacitor SMD 0603")
    (tags "capacitor 0603")
    (property "Author" "Antmicro")
    (property "Dielectric" "")
    (property "License" "Apache-2.0")
    (property "MPN" "GRM188R60J476ME15D")
    (property "Manufacturer" "Murata")
    (property "Sheetfile" "fpga-power.kicad_sch")
    (property "Sheetname" "FPGA power")
    (property "Val" "47u")
    (property "Voltage" "")
    (property "ki_description" " ")
    (attr smd)
    (fp_text reference "C15" (at 0.916328 -0.369992) (layer "B.SilkS")
        (effects (font (size 0.7 0.7) (thickness 0.15)) (justify left bottom mirror))
    )
    (fp_text value "C_47u_0603" (at 0 -1.6) (layer "B.Fab") hide
        (effects (font (size 0.7 0.7) (thickness 0.15)) (justify left bottom mirror))
    )
    (fp_text user "License: Apache-2.0" (at -1.682 -5.895) (layer "B.Fab") hide
        (effects (font (size 0.7 0.7) (thickness 0.15)) (justify left bottom mirror))
    )
    (fp_text user "${REFERENCE}" (at -1.682 -3.895) (layer "B.Fab") hide
        (effects (font (size 0.7 0.7) (thickness 0.15)) (justify left bottom mirror))
    )
    (fp_text user "Author: Antmicro" (at -1.682 -4.894) (layer "B.Fab") hide
        (effects (font (size 0.7 0.7) (thickness 0.15)) (justify left bottom mirror))
    )
    (fp_line (start -0.3 -0.3) (end 0.3 -0.3)
      (stroke (width 0.15) (type solid)) (layer "B.SilkS"))
    (fp_line (start -0.3 0.3) (end 0.3 0.3)
      (stroke (width 0.15) (type solid)) (layer "B.SilkS"))
    (fp_rect (start -1.24 0.7) (end 1.24 -0.7)
      (stroke (width 0.05) (type solid)) (fill none) (layer "B.CrtYd"))
    (fp_rect (start -0.8 0.4) (end 0.8 -0.4)
      (stroke (width 0.15) (type solid)) (fill none) (layer "B.Fab"))
    (pad "1" smd roundrect (at -0.7 0 180) (size 0.6 0.8) (layers "B.Cu" "B.Paste" "B.Mask") (roundrect_rratio 0.2)
      (net 143 "3V3_SYS") (pintype "passive"))
    (pad "2" smd roundrect (at 0.7 0 180) (size 0.6 0.8) (layers "B.Cu" "B.Paste" "B.Mask") (roundrect_rratio 0.2)
      (net 9 "GND") (pintype "passive"))
  )

  (footprint "data-center-rdimm-ddr4-tester-footprints:C_0402_1005Metric" (layer "B.Cu")
    (at 186.8 86.3)
    (descr "Capacitor SMD 0402")
    (tags "capacitor SMD 0402")
    (property "Author" "Antmicro")
    (property "Dielectric" "")
    (property "License" "Apache-2.0")
    (property "MPN" "GRM155R61A475MEAAD")
    (property "Manufacturer" "Murata")
    (property "Sheetfile" "fpga-power.kicad_sch")
    (property "Sheetname" "FPGA power")
    (property "Val" "4u7")
    (property "Voltage" "")
    (property "ki_description" " ")
    (attr smd)
    (fp_text reference "C16" (at 18.7 -9.13 180) (layer "B.SilkS")
        (effects (font (size 0.7 0.7) (thickness 0.15)) (justify left bottom mirror))
    )
    (fp_text value "C_4u7_0402" (at 0 -1.4 180) (layer "B.Fab") hide
        (effects (font (size 0.7 0.7) (thickness 0.15)) (justify left bottom mirror))
    )
    (fp_text user "Author: Antmicro" (at -0.932 -4.17 180) (layer "B.Fab") hide
        (effects (font (size 0.7 0.7) (thickness 0.15)) (justify left bottom mirror))
    )
    (fp_text user "${REFERENCE}" (at -0.932 -3.168 180) (layer "B.Fab") hide
        (effects (font (size 0.7 0.7) (thickness 0.15)) (justify left bottom mirror))
    )
    (fp_text user "License: Apache-2.0" (at -0.932 -5.17 180) (layer "B.Fab") hide
        (effects (font (size 0.7 0.7) (thickness 0.15)) (justify left bottom mirror))
    )
    (fp_rect (start -0.94 0.47) (end 0.94 -0.47)
      (stroke (width 0.05) (type solid)) (fill none) (layer "B.CrtYd"))
    (fp_rect (start -0.499 0.249) (end 0.499 -0.249)
      (stroke (width 0.15) (type solid)) (fill none) (layer "B.Fab"))
    (pad "1" smd roundrect (at -0.484 0) (size 0.59 0.64) (layers "B.Cu" "B.Paste" "B.Mask") (roundrect_rratio 0.25)
      (net 144 "1V8_SYS") (pintype "passive"))
    (pad "2" smd roundrect (at 0.484 0) (size 0.59 0.64) (layers "B.Cu" "B.Paste" "B.Mask") (roundrect_rratio 0.25)
      (net 9 "GND") (pintype "passive"))
  )

  (footprint "data-center-rdimm-ddr4-tester-footprints:C_0201" (layer "B.Cu")
    (at 193.65 85.575 180)
    (descr "Capacitor SMD 0201")
    (tags "capacitor SMD 0201")
    (property "Author" "Antmicro")
    (property "Dielectric" "")
    (property "License" "Apache-2.0")
    (property "MPN" "CC0201KRX6S5BB104")
    (property "Manufacturer" "Yaego")
    (property "Sheetfile" "fpga-power.kicad_sch")
    (property "Sheetname" "FPGA power")
    (property "Val" "100n")
    (property "Voltage" "")
    (property "ki_description" " ")
    (attr smd)
    (fp_text reference "C21" (at -1.06 0.375) (layer "B.SilkS")
        (effects (font (size 0.7 0.7) (thickness 0.15)) (justify left bottom mirror))
    )
    (fp_text value "C_100n_0201" (at 0 -1.4) (layer "B.Fab") hide
        (effects (font (size 0.7 0.7) (thickness 0.15)) (justify left bottom mirror))
    )
    (fp_text user "${REFERENCE}" (at -0.72 -3.4) (layer "B.Fab") hide
        (effects (font (size 0.7 0.7) (thickness 0.15)) (justify left bottom mirror))
    )
    (fp_text user "Author: Antmicro" (at -0.72 -5.4) (layer "B.Fab") hide
        (effects (font (size 0.7 0.7) (thickness 0.15)) (justify left bottom mirror))
    )
    (fp_text user "License: Apache-2.0" (at -0.72 -4.4) (layer "B.Fab") hide
        (effects (font (size 0.7 0.7) (thickness 0.15)) (justify left bottom mirror))
    )
    (fp_rect (start -0.72 0.38) (end 0.72 -0.38)
      (stroke (width 0.05) (type solid)) (fill none) (layer "B.CrtYd"))
    (fp_rect (start 0.3 -0.15) (end -0.301 0.149)
      (stroke (width 0.15) (type solid)) (fill none) (layer "B.Fab"))
    (pad "" smd roundrect (at -0.349 0.002 180) (size 0.318 0.36) (layers "B.Paste") (roundrect_rratio 0.25))
    (pad "" smd roundrect (at 0.341 0.002 180) (size 0.318 0.36) (layers "B.Paste") (roundrect_rratio 0.25))
    (pad "1" smd roundrect (at -0.321 0.002 180) (size 0.46 0.4) (layers "B.Cu" "B.Mask") (roundrect_rratio 0.25)
      (net 77 "VDDQ") (pintype "passive"))
    (pad "2" smd roundrect (at 0.32 0.002 180) (size 0.46 0.4) (layers "B.Cu" "B.Mask") (roundrect_rratio 0.25)
      (net 9 "GND") (pintype "passive"))
  )

  (footprint "data-center-rdimm-ddr4-tester-footprints:C_0603_1608Metric" (layer "B.Cu")
    (at 179.236328 88.260008 180)
    (descr "Capacitor SMD 0603")
    (tags "capacitor 0603")
    (property "Author" "Antmicro")
    (property "Dielectric" "")
    (property "License" "Apache-2.0")
    (property "MPN" "GRM188R60J476ME15D")
    (property "Manufacturer" "Murata")
    (property "Sheetfile" "fpga-power.kicad_sch")
    (property "Sheetname" "FPGA power")
    (property "Val" "47u")
    (property "Voltage" "")
    (property "ki_description" " ")
    (attr smd)
    (fp_text reference "C23" (at -1.043672 0.780008) (layer "B.SilkS")
        (effects (font (size 0.7 0.7) (thickness 0.15)) (justify left bottom mirror))
    )
    (fp_text value "C_47u_0603" (at 0 -1.6) (layer "B.Fab") hide
        (effects (font (size 0.7 0.7) (thickness 0.15)) (justify left bottom mirror))
    )
    (fp_text user "${REFERENCE}" (at -1.682 -3.895) (layer "B.Fab") hide
        (effects (font (size 0.7 0.7) (thickness 0.15)) (justify left bottom mirror))
    )
    (fp_text user "Author: Antmicro" (at -1.682 -4.894) (layer "B.Fab") hide
        (effects (font (size 0.7 0.7) (thickness 0.15)) (justify left bottom mirror))
    )
    (fp_text user "License: Apache-2.0" (at -1.682 -5.895) (layer "B.Fab") hide
        (effects (font (size 0.7 0.7) (thickness 0.15)) (justify left bottom mirror))
    )
    (fp_line (start -0.3 -0.3) (end 0.3 -0.3)
      (stroke (width 0.15) (type solid)) (layer "B.SilkS"))
    (fp_line (start -0.3 0.3) (end 0.3 0.3)
      (stroke (width 0.15) (type solid)) (layer "B.SilkS"))
    (fp_rect (start -1.24 0.7) (end 1.24 -0.7)
      (stroke (width 0.05) (type solid)) (fill none) (layer "B.CrtYd"))
    (fp_rect (start -0.8 0.4) (end 0.8 -0.4)
      (stroke (width 0.15) (type solid)) (fill none) (layer "B.Fab"))
    (pad "1" smd roundrect (at -0.7 0 180) (size 0.6 0.8) (layers "B.Cu" "B.Paste" "B.Mask") (roundrect_rratio 0.2)
      (net 77 "VDDQ") (pintype "passive"))
    (pad "2" smd roundrect (at 0.7 0 180) (size 0.6 0.8) (layers "B.Cu" "B.Paste" "B.Mask") (roundrect_rratio 0.2)
      (net 9 "GND") (pintype "passive"))
  )

  (footprint "data-center-rdimm-ddr4-tester-footprints:C_0603_1608Metric" (layer "B.Cu")
    (at 194.5 78.65 90)
    (descr "Capacitor SMD 0603")
    (tags "capacitor 0603")
    (property "Author" "Antmicro")
    (property "Dielectric" "")
    (property "License" "Apache-2.0")
    (property "MPN" "GRM188R60J476ME15D")
    (property "Manufacturer" "Murata")
    (property "Sheetfile" "fpga-power.kicad_sch")
    (property "Sheetname" "FPGA power")
    (property "Val" "47u")
    (property "Voltage" "")
    (property "ki_description" " ")
    (attr smd)
    (fp_text reference "C24" (at 3.47 0.45 270) (layer "B.SilkS")
        (effects (font (size 0.7 0.7) (thickness 0.15)) (justify left bottom mirror))
    )
    (fp_text value "C_47u_0603" (at 0 -1.6 270) (layer "B.Fab") hide
        (effects (font (size 0.7 0.7) (thickness 0.15)) (justify left bottom mirror))
    )
    (fp_text user "${REFERENCE}" (at -1.682 -3.895 270) (layer "B.Fab") hide
        (effects (font (size 0.7 0.7) (thickness 0.15)) (justify left bottom mirror))
    )
    (fp_text user "Author: Antmicro" (at -1.682 -4.894 270) (layer "B.Fab") hide
        (effects (font (size 0.7 0.7) (thickness 0.15)) (justify left bottom mirror))
    )
    (fp_text user "License: Apache-2.0" (at -1.682 -5.895 270) (layer "B.Fab") hide
        (effects (font (size 0.7 0.7) (thickness 0.15)) (justify left bottom mirror))
    )
    (fp_line (start -0.3 -0.3) (end 0.3 -0.3)
      (stroke (width 0.15) (type solid)) (layer "B.SilkS"))
    (fp_line (start -0.3 0.3) (end 0.3 0.3)
      (stroke (width 0.15) (type solid)) (layer "B.SilkS"))
    (fp_rect (start -1.24 0.7) (end 1.24 -0.7)
      (stroke (width 0.05) (type solid)) (fill none) (layer "B.CrtYd"))
    (fp_rect (start -0.8 0.4) (end 0.8 -0.4)
      (stroke (width 0.15) (type solid)) (fill none) (layer "B.Fab"))
    (pad "1" smd roundrect (at -0.7 0 90) (size 0.6 0.8) (layers "B.Cu" "B.Paste" "B.Mask") (roundrect_rratio 0.2)
      (net 77 "VDDQ") (pintype "passive"))
    (pad "2" smd roundrect (at 0.7 0 90) (size 0.6 0.8) (layers "B.Cu" "B.Paste" "B.Mask") (roundrect_rratio 0.2)
      (net 9 "GND") (pintype "passive"))
  )

  (footprint "data-center-rdimm-ddr4-tester-footprints:C_0201" (layer "B.Cu")
    (at 188.186328 88.535008 -90)
    (descr "Capacitor SMD 0201")
    (tags "capacitor SMD 0201")
    (property "Author" "Antmicro")
    (property "Dielectric" "")
    (property "License" "Apache-2.0")
    (property "MPN" "CC0201KRX6S5BB104")
    (property "Manufacturer" "Yaego")
    (property "Sheetfile" "fpga-power.kicad_sch")
    (property "Sheetname" "FPGA power")
    (property "Val" "100n")
    (property "Voltage" "")
    (property "ki_description" " ")
    (attr smd)
    (fp_text reference "C47" (at -10.285008 -18.163672 90) (layer "B.SilkS")
        (effects (font (size 0.7 0.7) (thickness 0.15)) (justify left bottom mirror))
    )
    (fp_text value "C_100n_0201" (at 0 -1.4 90) (layer "B.Fab") hide
        (effects (font (size 0.7 0.7) (thickness 0.15)) (justify left bottom mirror))
    )
    (fp_text user "Author: Antmicro" (at -0.72 -5.4 90) (layer "B.Fab") hide
        (effects (font (size 0.7 0.7) (thickness 0.15)) (justify left bottom mirror))
    )
    (fp_text user "${REFERENCE}" (at -0.72 -3.4 90) (layer "B.Fab") hide
        (effects (font (size 0.7 0.7) (thickness 0.15)) (justify left bottom mirror))
    )
    (fp_text user "License: Apache-2.0" (at -0.72 -4.4 90) (layer "B.Fab") hide
        (effects (font (size 0.7 0.7) (thickness 0.15)) (justify left bottom mirror))
    )
    (fp_rect (start -0.72 0.38) (end 0.72 -0.38)
      (stroke (width 0.05) (type solid)) (fill none) (layer "B.CrtYd"))
    (fp_rect (start 0.3 -0.15) (end -0.301 0.149)
      (stroke (width 0.15) (type solid)) (fill none) (layer "B.Fab"))
    (pad "" smd roundrect (at -0.349 0.002 270) (size 0.318 0.36) (layers "B.Paste") (roundrect_rratio 0.25))
    (pad "" smd roundrect (at 0.341 0.002 270) (size 0.318 0.36) (layers "B.Paste") (roundrect_rratio 0.25))
    (pad "1" smd roundrect (at -0.321 0.002 270) (size 0.46 0.4) (layers "B.Cu" "B.Mask") (roundrect_rratio 0.25)
      (net 144 "1V8_SYS") (pintype "passive"))
    (pad "2" smd roundrect (at 0.32 0.002 270) (size 0.46 0.4) (layers "B.Cu" "B.Mask") (roundrect_rratio 0.25)
      (net 9 "GND") (pintype "passive"))
  )

  (footprint "data-center-rdimm-ddr4-tester-footprints:C_0201" (layer "B.Cu")
    (at 187.086328 93.410008 -90)
    (descr "Capacitor SMD 0201")
    (tags "capacitor SMD 0201")
    (property "Author" "Antmicro")
    (property "Dielectric" "")
    (property "License" "Apache-2.0")
    (property "MPN" "CC0201KRX6S5BB104")
    (property "Manufacturer" "Yaego")
    (property "Sheetfile" "fpga-power.kicad_sch")
    (property "Sheetname" "FPGA power")
    (property "Val" "100n")
    (property "Voltage" "")
    (property "ki_description" " ")
    (attr smd)
    (fp_text reference "C48" (at -10.220008 -18.493672 90) (layer "B.SilkS")
        (effects (font (size 0.7 0.7) (thickness 0.15)) (justify left bottom mirror))
    )
    (fp_text value "C_100n_0201" (at 0 -1.4 90) (layer "B.Fab") hide
        (effects (font (size 0.7 0.7) (thickness 0.15)) (justify left bottom mirror))
    )
    (fp_text user "Author: Antmicro" (at -0.72 -5.4 90) (layer "B.Fab") hide
        (effects (font (size 0.7 0.7) (thickness 0.15)) (justify left bottom mirror))
    )
    (fp_text user "License: Apache-2.0" (at -0.72 -4.4 90) (layer "B.Fab") hide
        (effects (font (size 0.7 0.7) (thickness 0.15)) (justify left bottom mirror))
    )
    (fp_text user "${REFERENCE}" (at -0.72 -3.4 90) (layer "B.Fab") hide
        (effects (font (size 0.7 0.7) (thickness 0.15)) (justify left bottom mirror))
    )
    (fp_rect (start -0.72 0.38) (end 0.72 -0.38)
      (stroke (width 0.05) (type solid)) (fill none) (layer "B.CrtYd"))
    (fp_rect (start 0.3 -0.15) (end -0.301 0.149)
      (stroke (width 0.15) (type solid)) (fill none) (layer "B.Fab"))
    (pad "" smd roundrect (at -0.349 0.002 270) (size 0.318 0.36) (layers "B.Paste") (roundrect_rratio 0.25))
    (pad "" smd roundrect (at 0.341 0.002 270) (size 0.318 0.36) (layers "B.Paste") (roundrect_rratio 0.25))
    (pad "1" smd roundrect (at -0.321 0.002 270) (size 0.46 0.4) (layers "B.Cu" "B.Mask") (roundrect_rratio 0.25)
      (net 144 "1V8_SYS") (pintype "passive"))
    (pad "2" smd roundrect (at 0.32 0.002 270) (size 0.46 0.4) (layers "B.Cu" "B.Mask") (roundrect_rratio 0.25)
      (net 9 "GND") (pintype "passive"))
  )

  (footprint "data-center-rdimm-ddr4-tester-footprints:C_0201" (layer "B.Cu")
    (at 187.186328 91.560008 90)
    (descr "Capacitor SMD 0201")
    (tags "capacitor SMD 0201")
    (property "Author" "Antmicro")
    (property "Dielectric" "")
    (property "License" "Apache-2.0")
    (property "MPN" "CC0201KRX6S5BB104")
    (property "Manufacturer" "Yaego")
    (property "Sheetfile" "fpga-power.kicad_sch")
    (property "Sheetname" "FPGA power")
    (property "Val" "100n")
    (property "Voltage" "")
    (property "ki_description" " ")
    (attr smd)
    (fp_text reference "C51" (at 10.240008 18.413672 270) (layer "B.SilkS")
        (effects (font (size 0.7 0.7) (thickness 0.15)) (justify left bottom mirror))
    )
    (fp_text value "C_100n_0201" (at 0 -1.4 270) (layer "B.Fab") hide
        (effects (font (size 0.7 0.7) (thickness 0.15)) (justify left bottom mirror))
    )
    (fp_text user "${REFERENCE}" (at -0.72 -3.4 270) (layer "B.Fab") hide
        (effects (font (size 0.7 0.7) (thickness 0.15)) (justify left bottom mirror))
    )
    (fp_text user "License: Apache-2.0" (at -0.72 -4.4 270) (layer "B.Fab") hide
        (effects (font (size 0.7 0.7) (thickness 0.15)) (justify left bottom mirror))
    )
    (fp_text user "Author: Antmicro" (at -0.72 -5.4 270) (layer "B.Fab") hide
        (effects (font (size 0.7 0.7) (thickness 0.15)) (justify left bottom mirror))
    )
    (fp_rect (start -0.72 0.38) (end 0.72 -0.38)
      (stroke (width 0.05) (type solid)) (fill none) (layer "B.CrtYd"))
    (fp_rect (start 0.3 -0.15) (end -0.301 0.149)
      (stroke (width 0.15) (type solid)) (fill none) (layer "B.Fab"))
    (pad "" smd roundrect (at -0.349 0.002 90) (size 0.318 0.36) (layers "B.Paste") (roundrect_rratio 0.25))
    (pad "" smd roundrect (at 0.341 0.002 90) (size 0.318 0.36) (layers "B.Paste") (roundrect_rratio 0.25))
    (pad "1" smd roundrect (at -0.321 0.002 90) (size 0.46 0.4) (layers "B.Cu" "B.Mask") (roundrect_rratio 0.25)
      (net 144 "1V8_SYS") (pintype "passive"))
    (pad "2" smd roundrect (at 0.32 0.002 90) (size 0.46 0.4) (layers "B.Cu" "B.Mask") (roundrect_rratio 0.25)
      (net 9 "GND") (pintype "passive"))
  )

  (footprint "data-center-rdimm-ddr4-tester-footprints:C_0201" (layer "B.Cu")
    (at 189.925 98.15 90)
    (descr "Capacitor SMD 0201")
    (tags "capacitor SMD 0201")
    (property "Author" "Antmicro")
    (property "Dielectric" "")
    (property "License" "Apache-2.0")
    (property "MPN" "CC0201KRX6S5BB104")
    (property "Manufacturer" "Yaego")
    (property "Sheetfile" "fpga-power.kicad_sch")
    (property "Sheetname" "FPGA power")
    (property "Val" "100n")
    (property "Voltage" "")
    (property "ki_description" " ")
    (attr smd)
    (fp_text reference "C53" (at 1.06 1.235 270) (layer "B.SilkS")
        (effects (font (size 0.7 0.7) (thickness 0.15)) (justify left bottom mirror))
    )
    (fp_text value "C_100n_0201" (at 0 -1.4 270) (layer "B.Fab") hide
        (effects (font (size 0.7 0.7) (thickness 0.15)) (justify left bottom mirror))
    )
    (fp_text user "Author: Antmicro" (at -0.72 -5.4 270) (layer "B.Fab") hide
        (effects (font (size 0.7 0.7) (thickness 0.15)) (justify left bottom mirror))
    )
    (fp_text user "License: Apache-2.0" (at -0.72 -4.4 270) (layer "B.Fab") hide
        (effects (font (size 0.7 0.7) (thickness 0.15)) (justify left bottom mirror))
    )
    (fp_text user "${REFERENCE}" (at -0.72 -3.4 270) (layer "B.Fab") hide
        (effects (font (size 0.7 0.7) (thickness 0.15)) (justify left bottom mirror))
    )
    (fp_rect (start -0.72 0.38) (end 0.72 -0.38)
      (stroke (width 0.05) (type solid)) (fill none) (layer "B.CrtYd"))
    (fp_rect (start 0.3 -0.15) (end -0.301 0.149)
      (stroke (width 0.15) (type solid)) (fill none) (layer "B.Fab"))
    (pad "" smd roundrect (at -0.349 0.002 90) (size 0.318 0.36) (layers "B.Paste") (roundrect_rratio 0.25))
    (pad "" smd roundrect (at 0.341 0.002 90) (size 0.318 0.36) (layers "B.Paste") (roundrect_rratio 0.25))
    (pad "1" smd roundrect (at -0.321 0.002 90) (size 0.46 0.4) (layers "B.Cu" "B.Mask") (roundrect_rratio 0.25)
      (net 144 "1V8_SYS") (pintype "passive"))
    (pad "2" smd roundrect (at 0.32 0.002 90) (size 0.46 0.4) (layers "B.Cu" "B.Mask") (roundrect_rratio 0.25)
      (net 9 "GND") (pintype "passive"))
  )

  (footprint "data-center-rdimm-ddr4-tester-footprints:C_0201" (layer "B.Cu")
    (at 184.186328 91.560008 90)
    (descr "Capacitor SMD 0201")
    (tags "capacitor SMD 0201")
    (property "Author" "Antmicro")
    (property "Dielectric" "")
    (property "License" "Apache-2.0")
    (property "MPN" "CC0201KRX6S5BB104")
    (property "Manufacturer" "Yaego")
    (property "Sheetfile" "fpga-power.kicad_sch")
    (property "Sheetname" "FPGA power")
    (property "Val" "100n")
    (property "Voltage" "")
    (property "ki_description" " ")
    (attr smd)
    (fp_text reference "C55" (at 10.340008 18.373672 270) (layer "B.SilkS")
        (effects (font (size 0.7 0.7) (thickness 0.15)) (justify left bottom mirror))
    )
    (fp_text value "C_100n_0201" (at 0 -1.4 270) (layer "B.Fab") hide
        (effects (font (size 0.7 0.7) (thickness 0.15)) (justify left bottom mirror))
    )
    (fp_text user "License: Apache-2.0" (at -0.72 -4.4 270) (layer "B.Fab") hide
        (effects (font (size 0.7 0.7) (thickness 0.15)) (justify left bottom mirror))
    )
    (fp_text user "${REFERENCE}" (at -0.72 -3.4 270) (layer "B.Fab") hide
        (effects (font (size 0.7 0.7) (thickness 0.15)) (justify left bottom mirror))
    )
    (fp_text user "Author: Antmicro" (at -0.72 -5.4 270) (layer "B.Fab") hide
        (effects (font (size 0.7 0.7) (thickness 0.15)) (justify left bottom mirror))
    )
    (fp_rect (start -0.72 0.38) (end 0.72 -0.38)
      (stroke (width 0.05) (type solid)) (fill none) (layer "B.CrtYd"))
    (fp_rect (start 0.3 -0.15) (end -0.301 0.149)
      (stroke (width 0.15) (type solid)) (fill none) (layer "B.Fab"))
    (pad "" smd roundrect (at -0.349 0.002 90) (size 0.318 0.36) (layers "B.Paste") (roundrect_rratio 0.25))
    (pad "" smd roundrect (at 0.341 0.002 90) (size 0.318 0.36) (layers "B.Paste") (roundrect_rratio 0.25))
    (pad "1" smd roundrect (at -0.321 0.002 90) (size 0.46 0.4) (layers "B.Cu" "B.Mask") (roundrect_rratio 0.25)
      (net 144 "1V8_SYS") (pintype "passive"))
    (pad "2" smd roundrect (at 0.32 0.002 90) (size 0.46 0.4) (layers "B.Cu" "B.Mask") (roundrect_rratio 0.25)
      (net 9 "GND") (pintype "passive"))
  )

  (footprint "data-center-rdimm-ddr4-tester-footprints:C_0201" (layer "B.Cu")
    (at 185.186328 86.560008 -90)
    (descr "Capacitor SMD 0201")
    (tags "capacitor SMD 0201")
    (property "Author" "Antmicro")
    (property "Dielectric" "")
    (property "License" "Apache-2.0")
    (property "MPN" "CC0201KRX6S5BB104")
    (property "Manufacturer" "Yaego")
    (property "Sheetfile" "fpga-power.kicad_sch")
    (property "Sheetname" "FPGA power")
    (property "Val" "100n")
    (property "Voltage" "")
    (property "ki_description" " ")
    (attr smd)
    (fp_text reference "C56" (at -10.320008 -17.903672 90) (layer "B.SilkS")
        (effects (font (size 0.7 0.7) (thickness 0.15)) (justify left bottom mirror))
    )
    (fp_text value "C_100n_0201" (at 0 -1.4 90) (layer "B.Fab") hide
        (effects (font (size 0.7 0.7) (thickness 0.15)) (justify left bottom mirror))
    )
    (fp_text user "${REFERENCE}" (at -0.72 -3.4 90) (layer "B.Fab") hide
        (effects (font (size 0.7 0.7) (thickness 0.15)) (justify left bottom mirror))
    )
    (fp_text user "License: Apache-2.0" (at -0.72 -4.4 90) (layer "B.Fab") hide
        (effects (font (size 0.7 0.7) (thickness 0.15)) (justify left bottom mirror))
    )
    (fp_text user "Author: Antmicro" (at -0.72 -5.4 90) (layer "B.Fab") hide
        (effects (font (size 0.7 0.7) (thickness 0.15)) (justify left bottom mirror))
    )
    (fp_rect (start -0.72 0.38) (end 0.72 -0.38)
      (stroke (width 0.05) (type solid)) (fill none) (layer "B.CrtYd"))
    (fp_rect (start 0.3 -0.15) (end -0.301 0.149)
      (stroke (width 0.15) (type solid)) (fill none) (layer "B.Fab"))
    (pad "" smd roundrect (at -0.349 0.002 270) (size 0.318 0.36) (layers "B.Paste") (roundrect_rratio 0.25))
    (pad "" smd roundrect (at 0.341 0.002 270) (size 0.318 0.36) (layers "B.Paste") (roundrect_rratio 0.25))
    (pad "1" smd roundrect (at -0.321 0.002 270) (size 0.46 0.4) (layers "B.Cu" "B.Mask") (roundrect_rratio 0.25)
      (net 144 "1V8_SYS") (pintype "passive"))
    (pad "2" smd roundrect (at 0.32 0.002 270) (size 0.46 0.4) (layers "B.Cu" "B.Mask") (roundrect_rratio 0.25)
      (net 9 "GND") (pintype "passive"))
  )

  (footprint "data-center-rdimm-ddr4-tester-footprints:C_0201" (layer "B.Cu")
    (at 193.311328 79.285008 90)
    (descr "Capacitor SMD 0201")
    (tags "capacitor SMD 0201")
    (property "Author" "Antmicro")
    (property "Dielectric" "")
    (property "License" "Apache-2.0")
    (property "MPN" "CC0201KRX6S5BB104")
    (property "Manufacturer" "Yaego")
    (property "Sheetfile" "fpga-power.kicad_sch")
    (property "Sheetname" "FPGA power")
    (property "Val" "100n")
    (property "Voltage" "")
    (property "ki_description" " ")
    (attr smd)
    (fp_text reference "C71" (at 4.075008 0.688672 270) (layer "B.SilkS")
        (effects (font (size 0.7 0.7) (thickness 0.15)) (justify left bottom mirror))
    )
    (fp_text value "C_100n_0201" (at 0 -1.4 270) (layer "B.Fab") hide
        (effects (font (size 0.7 0.7) (thickness 0.15)) (justify left bottom mirror))
    )
    (fp_text user "${REFERENCE}" (at -0.72 -3.4 270) (layer "B.Fab") hide
        (effects (font (size 0.7 0.7) (thickness 0.15)) (justify left bottom mirror))
    )
    (fp_text user "License: Apache-2.0" (at -0.72 -4.4 270) (layer "B.Fab") hide
        (effects (font (size 0.7 0.7) (thickness 0.15)) (justify left bottom mirror))
    )
    (fp_text user "Author: Antmicro" (at -0.72 -5.4 270) (layer "B.Fab") hide
        (effects (font (size 0.7 0.7) (thickness 0.15)) (justify left bottom mirror))
    )
    (fp_rect (start -0.72 0.38) (end 0.72 -0.38)
      (stroke (width 0.05) (type solid)) (fill none) (layer "B.CrtYd"))
    (fp_rect (start 0.3 -0.15) (end -0.301 0.149)
      (stroke (width 0.15) (type solid)) (fill none) (layer "B.Fab"))
    (pad "" smd roundrect (at -0.349 0.002 90) (size 0.318 0.36) (layers "B.Paste") (roundrect_rratio 0.25))
    (pad "" smd roundrect (at 0.341 0.002 90) (size 0.318 0.36) (layers "B.Paste") (roundrect_rratio 0.25))
    (pad "1" smd roundrect (at -0.321 0.002 90) (size 0.46 0.4) (layers "B.Cu" "B.Mask") (roundrect_rratio 0.25)
      (net 77 "VDDQ") (pintype "passive"))
    (pad "2" smd roundrect (at 0.32 0.002 90) (size 0.46 0.4) (layers "B.Cu" "B.Mask") (roundrect_rratio 0.25)
      (net 9 "GND") (pintype "passive"))
  )

  (footprint "data-center-rdimm-ddr4-tester-footprints:C_0201" (layer "B.Cu")
    (at 190.886328 83.060008 90)
    (descr "Capacitor SMD 0201")
    (tags "capacitor SMD 0201")
    (property "Author" "Antmicro")
    (property "Dielectric" "")
    (property "License" "Apache-2.0")
    (property "MPN" "CC0201KRX6S5BB104")
    (property "Manufacturer" "Yaego")
    (property "Sheetfile" "fpga-power.kicad_sch")
    (property "Sheetname" "FPGA power")
    (property "Val" "100n")
    (property "Voltage" "")
    (property "ki_description" " ")
    (attr smd)
    (fp_text reference "C72" (at 1.060008 1.233672 270) (layer "B.SilkS")
        (effects (font (size 0.7 0.7) (thickness 0.15)) (justify left bottom mirror))
    )
    (fp_text value "C_100n_0201" (at 0 -1.4 270) (layer "B.Fab") hide
        (effects (font (size 0.7 0.7) (thickness 0.15)) (justify left bottom mirror))
    )
    (fp_text user "${REFERENCE}" (at -0.72 -3.4 270) (layer "B.Fab") hide
        (effects (font (size 0.7 0.7) (thickness 0.15)) (justify left bottom mirror))
    )
    (fp_text user "License: Apache-2.0" (at -0.72 -4.4 270) (layer "B.Fab") hide
        (effects (font (size 0.7 0.7) (thickness 0.15)) (justify left bottom mirror))
    )
    (fp_text user "Author: Antmicro" (at -0.72 -5.4 270) (layer "B.Fab") hide
        (effects (font (size 0.7 0.7) (thickness 0.15)) (justify left bottom mirror))
    )
    (fp_rect (start -0.72 0.38) (end 0.72 -0.38)
      (stroke (width 0.05) (type solid)) (fill none) (layer "B.CrtYd"))
    (fp_rect (start 0.3 -0.15) (end -0.301 0.149)
      (stroke (width 0.15) (type solid)) (fill none) (layer "B.Fab"))
    (pad "" smd roundrect (at -0.349 0.002 90) (size 0.318 0.36) (layers "B.Paste") (roundrect_rratio 0.25))
    (pad "" smd roundrect (at 0.341 0.002 90) (size 0.318 0.36) (layers "B.Paste") (roundrect_rratio 0.25))
    (pad "1" smd roundrect (at -0.321 0.002 90) (size 0.46 0.4) (layers "B.Cu" "B.Mask") (roundrect_rratio 0.25)
      (net 77 "VDDQ") (pintype "passive"))
    (pad "2" smd roundrect (at 0.32 0.002 90) (size 0.46 0.4) (layers "B.Cu" "B.Mask") (roundrect_rratio 0.25)
      (net 9 "GND") (pintype "passive"))
  )

  (footprint "data-center-rdimm-ddr4-tester-footprints:C_0201" (layer "B.Cu")
    (at 179.275 80.075 90)
    (descr "Capacitor SMD 0201")
    (tags "capacitor SMD 0201")
    (property "Author" "Antmicro")
    (property "Dielectric" "")
    (property "License" "Apache-2.0")
    (property "MPN" "CC0201KRX6S5BB104")
    (property "Manufacturer" "Yaego")
    (property "Sheetfile" "fpga-power.kicad_sch")
    (property "Sheetname" "FPGA power")
    (property "Val" "100n")
    (property "Voltage" "")
    (property "ki_description" " ")
    (attr smd)
    (fp_text reference "C73" (at 1.035 -0.365 270) (layer "B.SilkS")
        (effects (font (size 0.7 0.7) (thickness 0.15)) (justify left bottom mirror))
    )
    (fp_text value "C_100n_0201" (at 0 -1.4 270) (layer "B.Fab") hide
        (effects (font (size 0.7 0.7) (thickness 0.15)) (justify left bottom mirror))
    )
    (fp_text user "License: Apache-2.0" (at -0.72 -4.4 270) (layer "B.Fab") hide
        (effects (font (size 0.7 0.7) (thickness 0.15)) (justify left bottom mirror))
    )
    (fp_text user "${REFERENCE}" (at -0.72 -3.4 270) (layer "B.Fab") hide
        (effects (font (size 0.7 0.7) (thickness 0.15)) (justify left bottom mirror))
    )
    (fp_text user "Author: Antmicro" (at -0.72 -5.4 270) (layer "B.Fab") hide
        (effects (font (size 0.7 0.7) (thickness 0.15)) (justify left bottom mirror))
    )
    (fp_rect (start -0.72 0.38) (end 0.72 -0.38)
      (stroke (width 0.05) (type solid)) (fill none) (layer "B.CrtYd"))
    (fp_rect (start 0.3 -0.15) (end -0.301 0.149)
      (stroke (width 0.15) (type solid)) (fill none) (layer "B.Fab"))
    (pad "" smd roundrect (at -0.349 0.002 90) (size 0.318 0.36) (layers "B.Paste") (roundrect_rratio 0.25))
    (pad "" smd roundrect (at 0.341 0.002 90) (size 0.318 0.36) (layers "B.Paste") (roundrect_rratio 0.25))
    (pad "1" smd roundrect (at -0.321 0.002 90) (size 0.46 0.4) (layers "B.Cu" "B.Mask") (roundrect_rratio 0.25)
      (net 77 "VDDQ") (pintype "passive"))
    (pad "2" smd roundrect (at 0.32 0.002 90) (size 0.46 0.4) (layers "B.Cu" "B.Mask") (roundrect_rratio 0.25)
      (net 9 "GND") (pintype "passive"))
  )

  (footprint "data-center-rdimm-ddr4-tester-footprints:C_0201" (layer "B.Cu")
    (at 192.5 77.6)
    (descr "Capacitor SMD 0201")
    (tags "capacitor SMD 0201")
    (property "Author" "Antmicro")
    (property "Dielectric" "")
    (property "License" "Apache-2.0")
    (property "MPN" "CC0201KRX6S5BB104")
    (property "Manufacturer" "Yaego")
    (property "Sheetfile" "fpga-power.kicad_sch")
    (property "Sheetname" "FPGA power")
    (property "Val" "100n")
    (property "Voltage" "")
    (property "ki_description" " ")
    (attr smd)
    (fp_text reference "C75" (at 0.51 1.11 180) (layer "B.SilkS")
        (effects (font (size 0.7 0.7) (thickness 0.15)) (justify left bottom mirror))
    )
    (fp_text value "C_100n_0201" (at 0 -1.4 180) (layer "B.Fab") hide
        (effects (font (size 0.7 0.7) (thickness 0.15)) (justify left bottom mirror))
    )
    (fp_text user "License: Apache-2.0" (at -0.72 -4.4 180) (layer "B.Fab") hide
        (effects (font (size 0.7 0.7) (thickness 0.15)) (justify left bottom mirror))
    )
    (fp_text user "Author: Antmicro" (at -0.72 -5.4 180) (layer "B.Fab") hide
        (effects (font (size 0.7 0.7) (thickness 0.15)) (justify left bottom mirror))
    )
    (fp_text user "${REFERENCE}" (at -0.72 -3.4 180) (layer "B.Fab") hide
        (effects (font (size 0.7 0.7) (thickness 0.15)) (justify left bottom mirror))
    )
    (fp_rect (start -0.72 0.38) (end 0.72 -0.38)
      (stroke (width 0.05) (type solid)) (fill none) (layer "B.CrtYd"))
    (fp_rect (start 0.3 -0.15) (end -0.301 0.149)
      (stroke (width 0.15) (type solid)) (fill none) (layer "B.Fab"))
    (pad "" smd roundrect (at -0.349 0.002) (size 0.318 0.36) (layers "B.Paste") (roundrect_rratio 0.25))
    (pad "" smd roundrect (at 0.341 0.002) (size 0.318 0.36) (layers "B.Paste") (roundrect_rratio 0.25))
    (pad "1" smd roundrect (at -0.321 0.002) (size 0.46 0.4) (layers "B.Cu" "B.Mask") (roundrect_rratio 0.25)
      (net 77 "VDDQ") (pintype "passive"))
    (pad "2" smd roundrect (at 0.32 0.002) (size 0.46 0.4) (layers "B.Cu" "B.Mask") (roundrect_rratio 0.25)
      (net 9 "GND") (pintype "passive"))
  )

  (footprint "data-center-rdimm-ddr4-tester-footprints:C_0201" (layer "B.Cu")
    (at 194.2 82.05 90)
    (descr "Capacitor SMD 0201")
    (tags "capacitor SMD 0201")
    (property "Author" "Antmicro")
    (property "Dielectric" "")
    (property "License" "Apache-2.0")
    (property "MPN" "CC0201KRX6S5BB104")
    (property "Manufacturer" "Yaego")
    (property "Sheetfile" "fpga-power.kicad_sch")
    (property "Sheetname" "FPGA power")
    (property "Val" "100n")
    (property "Voltage" "")
    (property "ki_description" " ")
    (attr smd)
    (fp_text reference "C76" (at 1.18 -0.33 270) (layer "B.SilkS")
        (effects (font (size 0.7 0.7) (thickness 0.15)) (justify left bottom mirror))
    )
    (fp_text value "C_100n_0201" (at 0 -1.4 270) (layer "B.Fab") hide
        (effects (font (size 0.7 0.7) (thickness 0.15)) (justify left bottom mirror))
    )
    (fp_text user "License: Apache-2.0" (at -0.72 -4.4 270) (layer "B.Fab") hide
        (effects (font (size 0.7 0.7) (thickness 0.15)) (justify left bottom mirror))
    )
    (fp_text user "${REFERENCE}" (at -0.72 -3.4 270) (layer "B.Fab") hide
        (effects (font (size 0.7 0.7) (thickness 0.15)) (justify left bottom mirror))
    )
    (fp_text user "Author: Antmicro" (at -0.72 -5.4 270) (layer "B.Fab") hide
        (effects (font (size 0.7 0.7) (thickness 0.15)) (justify left bottom mirror))
    )
    (fp_rect (start -0.72 0.38) (end 0.72 -0.38)
      (stroke (width 0.05) (type solid)) (fill none) (layer "B.CrtYd"))
    (fp_rect (start 0.3 -0.15) (end -0.301 0.149)
      (stroke (width 0.15) (type solid)) (fill none) (layer "B.Fab"))
    (pad "" smd roundrect (at -0.349 0.002 90) (size 0.318 0.36) (layers "B.Paste") (roundrect_rratio 0.25))
    (pad "" smd roundrect (at 0.341 0.002 90) (size 0.318 0.36) (layers "B.Paste") (roundrect_rratio 0.25))
    (pad "1" smd roundrect (at -0.321 0.002 90) (size 0.46 0.4) (layers "B.Cu" "B.Mask") (roundrect_rratio 0.25)
      (net 77 "VDDQ") (pintype "passive"))
    (pad "2" smd roundrect (at 0.32 0.002 90) (size 0.46 0.4) (layers "B.Cu" "B.Mask") (roundrect_rratio 0.25)
      (net 9 "GND") (pintype "passive"))
  )

  (footprint "data-center-rdimm-ddr4-tester-footprints:C_0201" (layer "B.Cu")
    (at 196 83.05 -90)
    (descr "Capacitor SMD 0201")
    (tags "capacitor SMD 0201")
    (property "Author" "Antmicro")
    (property "Dielectric" "")
    (property "License" "Apache-2.0")
    (property "MPN" "CC0201KRX6S5BB104")
    (property "Manufacturer" "Yaego")
    (property "Sheetfile" "fpga-power.kicad_sch")
    (property "Sheetname" "FPGA power")
    (property "Val" "100n")
    (property "Voltage" "")
    (property "ki_description" " ")
    (attr smd)
    (fp_text reference "C143" (at -1.48 0.36 90) (layer "B.SilkS")
        (effects (font (size 0.7 0.7) (thickness 0.15)) (justify left bottom mirror))
    )
    (fp_text value "C_100n_0201" (at 0 -1.4 90) (layer "B.Fab") hide
        (effects (font (size 0.7 0.7) (thickness 0.15)) (justify left bottom mirror))
    )
    (fp_text user "${REFERENCE}" (at -0.72 -3.4 90) (layer "B.Fab") hide
        (effects (font (size 0.7 0.7) (thickness 0.15)) (justify left bottom mirror))
    )
    (fp_text user "License: Apache-2.0" (at -0.72 -4.4 90) (layer "B.Fab") hide
        (effects (font (size 0.7 0.7) (thickness 0.15)) (justify left bottom mirror))
    )
    (fp_text user "Author: Antmicro" (at -0.72 -5.4 90) (layer "B.Fab") hide
        (effects (font (size 0.7 0.7) (thickness 0.15)) (justify left bottom mirror))
    )
    (fp_rect (start -0.72 0.38) (end 0.72 -0.38)
      (stroke (width 0.05) (type solid)) (fill none) (layer "B.CrtYd"))
    (fp_rect (start 0.3 -0.15) (end -0.301 0.149)
      (stroke (width 0.15) (type solid)) (fill none) (layer "B.Fab"))
    (pad "" smd roundrect (at -0.349 0.002 270) (size 0.318 0.36) (layers "B.Paste") (roundrect_rratio 0.25))
    (pad "" smd roundrect (at 0.341 0.002 270) (size 0.318 0.36) (layers "B.Paste") (roundrect_rratio 0.25))
    (pad "1" smd roundrect (at -0.321 0.002 270) (size 0.46 0.4) (layers "B.Cu" "B.Mask") (roundrect_rratio 0.25)
      (net 77 "VDDQ") (pintype "passive"))
    (pad "2" smd roundrect (at 0.32 0.002 270) (size 0.46 0.4) (layers "B.Cu" "B.Mask") (roundrect_rratio 0.25)
      (net 9 "GND") (pintype "passive"))
  )

  (footprint "data-center-rdimm-ddr4-tester-footprints:R_0402_1005Metric" (layer "B.Cu")
    (at 160.686328 87.120008 90)
    (descr "Resistor SMD 0402")
    (tags "resistor SMD 0402")
    (property "Author" "Antmicro")
    (property "License" "Apache-2.0")
    (property "MPN" "CR0402-FX-1002GLF")
    (property "Manufacturer" "Bourns")
    (property "Sheetfile" "ethernet.kicad_sch")
    (property "Sheetname" "Ethernet")
    (property "Tolerance" "1%")
    (property "Val" "10k")
    (property "ki_description" "10k resistor in 0402 package with 1% tolerance")
    (attr smd)
    (fp_text reference "R73" (at 1.170008 8.103672 270) (layer "B.SilkS")
        (effects (font (size 0.7 0.7) (thickness 0.15)) (justify left bottom mirror))
    )
    (fp_text value "R_10k_0402" (at 0 -1.4 270) (layer "B.Fab") hide
        (effects (font (size 0.7 0.7) (thickness 0.15)) (justify left bottom mirror))
    )
    (fp_text user "Author: Antmicro" (at -0.95 -4.169 270) (layer "B.Fab") hide
        (effects (font (size 0.7 0.7) (thickness 0.15)) (justify left bottom mirror))
    )
    (fp_text user "${REFERENCE}" (at -0.95 -3.168 270) (layer "B.Fab") hide
        (effects (font (size 0.7 0.7) (thickness 0.15)) (justify left bottom mirror))
    )
    (fp_text user "License: Apache-2.0" (at -0.95 -5.169 270) (layer "B.Fab") hide
        (effects (font (size 0.7 0.7) (thickness 0.15)) (justify left bottom mirror))
    )
    (fp_rect (start -0.93 0.47) (end 0.93 -0.47)
      (stroke (width 0.05) (type solid)) (fill none) (layer "B.CrtYd"))
    (fp_rect (start -0.5 0.25) (end 0.5 -0.25)
      (stroke (width 0.15) (type solid)) (fill none) (layer "B.Fab"))
    (pad "1" smd roundrect (at -0.485 0 90) (size 0.59 0.64) (layers "B.Cu" "B.Paste" "B.Mask") (roundrect_rratio 0.25)
      (net 37 "ETH_RXD3") (pintype "passive"))
    (pad "2" smd roundrect (at 0.485 0 90) (size 0.59 0.64) (layers "B.Cu" "B.Paste" "B.Mask") (roundrect_rratio 0.25)
      (net 143 "3V3_SYS") (pintype "passive"))
  )

  (footprint "data-center-rdimm-ddr4-tester-footprints:R_0402_1005Metric" (layer "B.Cu")
    (at 160.736328 89.340008 -90)
    (descr "Resistor SMD 0402")
    (tags "resistor SMD 0402")
    (property "Author" "Antmicro")
    (property "DNP" "DNP")
    (property "License" "Apache-2.0")
    (property "MPN" "CR0402-FX-2201GLF")
    (property "Manufacturer" "Bourns")
    (property "Sheetfile" "ethernet.kicad_sch")
    (property "Sheetname" "Ethernet")
    (property "Tolerance" "1%")
    (property "Val" "2k2")
    (property "dnp" "")
    (property "exclude_from_bom" "")
    (property "ki_description" "2k2 resistor in 0402 package with 1% tolerance")
    (attr exclude_from_pos_files exclude_from_bom)
    (fp_text reference "R91" (at -1.165008 -7.958672 90) (layer "B.SilkS")
        (effects (font (size 0.7 0.7) (thickness 0.15)) (justify left bottom mirror))
    )
    (fp_text value "R_2k2_0402" (at 0 -1.4 90) (layer "B.Fab") hide
        (effects (font (size 0.7 0.7) (thickness 0.15)) (justify left bottom mirror))
    )
    (fp_text user "Author: Antmicro" (at -0.95 -4.169 90) (layer "B.Fab") hide
        (effects (font (size 0.7 0.7) (thickness 0.15)) (justify left bottom mirror))
    )
    (fp_text user "License: Apache-2.0" (at -0.95 -5.169 90) (layer "B.Fab") hide
        (effects (font (size 0.7 0.7) (thickness 0.15)) (justify left bottom mirror))
    )
    (fp_text user "${REFERENCE}" (at -0.95 -3.168 90) (layer "B.Fab") hide
        (effects (font (size 0.7 0.7) (thickness 0.15)) (justify left bottom mirror))
    )
    (fp_rect (start -0.93 0.47) (end 0.93 -0.47)
      (stroke (width 0.05) (type solid)) (fill none) (layer "B.CrtYd"))
    (fp_rect (start -0.5 0.25) (end 0.5 -0.25)
      (stroke (width 0.15) (type solid)) (fill none) (layer "B.Fab"))
    (pad "1" smd roundrect (at -0.485 0 270) (size 0.59 0.64) (layers "B.Cu" "B.Paste" "B.Mask") (roundrect_rratio 0.25)
      (net 37 "ETH_RXD3") (pintype "passive"))
    (pad "2" smd roundrect (at 0.485 0 270) (size 0.59 0.64) (layers "B.Cu" "B.Paste" "B.Mask") (roundrect_rratio 0.25)
      (net 9 "GND") (pintype "passive"))
  )

  (footprint "data-center-rdimm-ddr4-tester-footprints:C_0402_1005Metric" (layer "B.Cu")
    (at 186.136328 92.985008 90)
    (descr "Capacitor SMD 0402")
    (tags "capacitor SMD 0402")
    (property "Author" "Antmicro")
    (property "Dielectric" "")
    (property "License" "Apache-2.0")
    (property "MPN" "GRM155R61A475MEAAD")
    (property "Manufacturer" "Murata")
    (property "Sheetfile" "fpga-power.kicad_sch")
    (property "Sheetname" "FPGA power")
    (property "Val" "4u7")
    (property "Voltage" "")
    (property "ki_description" " ")
    (attr smd)
    (fp_text reference "C115" (at 10.625008 18.513672 270) (layer "B.SilkS")
        (effects (font (size 0.7 0.7) (thickness 0.15)) (justify left bottom mirror))
    )
    (fp_text value "C_4u7_0402" (at 0 -1.4 270) (layer "B.Fab") hide
        (effects (font (size 0.7 0.7) (thickness 0.15)) (justify left bottom mirror))
    )
    (fp_text user "License: Apache-2.0" (at -0.932 -5.17 270) (layer "B.Fab") hide
        (effects (font (size 0.7 0.7) (thickness 0.15)) (justify left bottom mirror))
    )
    (fp_text user "${REFERENCE}" (at -0.932 -3.168 270) (layer "B.Fab") hide
        (effects (font (size 0.7 0.7) (thickness 0.15)) (justify left bottom mirror))
    )
    (fp_text user "Author: Antmicro" (at -0.932 -4.17 270) (layer "B.Fab") hide
        (effects (font (size 0.7 0.7) (thickness 0.15)) (justify left bottom mirror))
    )
    (fp_rect (start -0.94 0.47) (end 0.94 -0.47)
      (stroke (width 0.05) (type solid)) (fill none) (layer "B.CrtYd"))
    (fp_rect (start -0.499 0.249) (end 0.499 -0.249)
      (stroke (width 0.15) (type solid)) (fill none) (layer "B.Fab"))
    (pad "1" smd roundrect (at -0.484 0 90) (size 0.59 0.64) (layers "B.Cu" "B.Paste" "B.Mask") (roundrect_rratio 0.25)
      (net 144 "1V8_SYS") (pintype "passive"))
    (pad "2" smd roundrect (at 0.484 0 90) (size 0.59 0.64) (layers "B.Cu" "B.Paste" "B.Mask") (roundrect_rratio 0.25)
      (net 9 "GND") (pintype "passive"))
  )

  (footprint "data-center-rdimm-ddr4-tester-footprints:C_0402_1005Metric" (layer "B.Cu")
    (at 187.461328 89.785008 180)
    (descr "Capacitor SMD 0402")
    (tags "capacitor SMD 0402")
    (property "Author" "Antmicro")
    (property "Dielectric" "")
    (property "License" "Apache-2.0")
    (property "MPN" "GRM155R61A475MEAAD")
    (property "Manufacturer" "Murata")
    (property "Sheetfile" "fpga-power.kicad_sch")
    (property "Sheetname" "FPGA power")
    (property "Val" "4u7")
    (property "Voltage" "")
    (property "ki_description" " ")
    (attr smd)
    (fp_text reference "C19" (at -19.088672 8.495008) (layer "B.SilkS")
        (effects (font (size 0.7 0.7) (thickness 0.15)) (justify left bottom mirror))
    )
    (fp_text value "C_4u7_0402" (at 0 -1.4) (layer "B.Fab") hide
        (effects (font (size 0.7 0.7) (thickness 0.15)) (justify left bottom mirror))
    )
    (fp_text user "Author: Antmicro" (at -0.932 -4.17) (layer "B.Fab") hide
        (effects (font (size 0.7 0.7) (thickness 0.15)) (justify left bottom mirror))
    )
    (fp_text user "License: Apache-2.0" (at -0.932 -5.17) (layer "B.Fab") hide
        (effects (font (size 0.7 0.7) (thickness 0.15)) (justify left bottom mirror))
    )
    (fp_text user "${REFERENCE}" (at -0.932 -3.168) (layer "B.Fab") hide
        (effects (font (size 0.7 0.7) (thickness 0.15)) (justify left bottom mirror))
    )
    (fp_rect (start -0.94 0.47) (end 0.94 -0.47)
      (stroke (width 0.05) (type solid)) (fill none) (layer "B.CrtYd"))
    (fp_rect (start -0.499 0.249) (end 0.499 -0.249)
      (stroke (width 0.15) (type solid)) (fill none) (layer "B.Fab"))
    (pad "1" smd roundrect (at -0.484 0 180) (size 0.59 0.64) (layers "B.Cu" "B.Paste" "B.Mask") (roundrect_rratio 0.25)
      (net 144 "1V8_SYS") (pintype "passive"))
    (pad "2" smd roundrect (at 0.484 0 180) (size 0.59 0.64) (layers "B.Cu" "B.Paste" "B.Mask") (roundrect_rratio 0.25)
      (net 9 "GND") (pintype "passive"))
  )

  (footprint "data-center-rdimm-ddr4-tester-footprints:C_0201" (layer "B.Cu")
    (at 181.725 77.475)
    (descr "Capacitor SMD 0201")
    (tags "capacitor SMD 0201")
    (property "Author" "Antmicro")
    (property "Dielectric" "")
    (property "License" "Apache-2.0")
    (property "MPN" "CC0201KRX6S5BB104")
    (property "Manufacturer" "Yaego")
    (property "Sheetfile" "fpga-power.kicad_sch")
    (property "Sheetname" "FPGA power")
    (property "Val" "100n")
    (property "Voltage" "")
    (property "ki_description" " ")
    (attr smd)
    (fp_text reference "C74" (at -0.555 0.415 180) (layer "B.SilkS")
        (effects (font (size 0.7 0.7) (thickness 0.15)) (justify left bottom mirror))
    )
    (fp_text value "C_100n_0201" (at 0 -1.4 180) (layer "B.Fab") hide
        (effects (font (size 0.7 0.7) (thickness 0.15)) (justify left bottom mirror))
    )
    (fp_text user "License: Apache-2.0" (at -0.72 -4.4 180) (layer "B.Fab") hide
        (effects (font (size 0.7 0.7) (thickness 0.15)) (justify left bottom mirror))
    )
    (fp_text user "Author: Antmicro" (at -0.72 -5.4 180) (layer "B.Fab") hide
        (effects (font (size 0.7 0.7) (thickness 0.15)) (justify left bottom mirror))
    )
    (fp_text user "${REFERENCE}" (at -0.72 -3.4 180) (layer "B.Fab") hide
        (effects (font (size 0.7 0.7) (thickness 0.15)) (justify left bottom mirror))
    )
    (fp_rect (start -0.72 0.38) (end 0.72 -0.38)
      (stroke (width 0.05) (type solid)) (fill none) (layer "B.CrtYd"))
    (fp_rect (start 0.3 -0.15) (end -0.301 0.149)
      (stroke (width 0.15) (type solid)) (fill none) (layer "B.Fab"))
    (pad "" smd roundrect (at -0.349 0.002) (size 0.318 0.36) (layers "B.Paste") (roundrect_rratio 0.25))
    (pad "" smd roundrect (at 0.341 0.002) (size 0.318 0.36) (layers "B.Paste") (roundrect_rratio 0.25))
    (pad "1" smd roundrect (at -0.321 0.002) (size 0.46 0.4) (layers "B.Cu" "B.Mask") (roundrect_rratio 0.25)
      (net 77 "VDDQ") (pintype "passive"))
    (pad "2" smd roundrect (at 0.32 0.002) (size 0.46 0.4) (layers "B.Cu" "B.Mask") (roundrect_rratio 0.25)
      (net 9 "GND") (pintype "passive"))
  )

  (footprint "data-center-rdimm-ddr4-tester-footprints:C_0201" (layer "B.Cu")
    (at 190.076328 91.820008 90)
    (descr "Capacitor SMD 0201")
    (tags "capacitor SMD 0201")
    (property "Author" "Antmicro")
    (property "Dielectric" "")
    (property "License" "Apache-2.0")
    (property "MPN" "CC0201KRX6S5BB104")
    (property "Manufacturer" "Yaego")
    (property "Sheetfile" "fpga-power.kicad_sch")
    (property "Sheetname" "FPGA power")
    (property "Val" "100n")
    (property "Voltage" "")
    (property "ki_description" " ")
    (attr smd)
    (fp_text reference "C52" (at 2.740008 0.393672 270) (layer "B.SilkS")
        (effects (font (size 0.7 0.7) (thickness 0.15)) (justify left bottom mirror))
    )
    (fp_text value "C_100n_0201" (at 0 -1.4 270) (layer "B.Fab") hide
        (effects (font (size 0.7 0.7) (thickness 0.15)) (justify left bottom mirror))
    )
    (fp_text user "${REFERENCE}" (at -0.72 -3.4 270) (layer "B.Fab") hide
        (effects (font (size 0.7 0.7) (thickness 0.15)) (justify left bottom mirror))
    )
    (fp_text user "License: Apache-2.0" (at -0.72 -4.4 270) (layer "B.Fab") hide
        (effects (font (size 0.7 0.7) (thickness 0.15)) (justify left bottom mirror))
    )
    (fp_text user "Author: Antmicro" (at -0.72 -5.4 270) (layer "B.Fab") hide
        (effects (font (size 0.7 0.7) (thickness 0.15)) (justify left bottom mirror))
    )
    (fp_rect (start -0.72 0.38) (end 0.72 -0.38)
      (stroke (width 0.05) (type solid)) (fill none) (layer "B.CrtYd"))
    (fp_rect (start 0.3 -0.15) (end -0.301 0.149)
      (stroke (width 0.15) (type solid)) (fill none) (layer "B.Fab"))
    (pad "" smd roundrect (at -0.349 0.002 90) (size 0.318 0.36) (layers "B.Paste") (roundrect_rratio 0.25))
    (pad "" smd roundrect (at 0.341 0.002 90) (size 0.318 0.36) (layers "B.Paste") (roundrect_rratio 0.25))
    (pad "1" smd roundrect (at -0.321 0.002 90) (size 0.46 0.4) (layers "B.Cu" "B.Mask") (roundrect_rratio 0.25)
      (net 147 "1V0_SYS") (pintype "passive"))
    (pad "2" smd roundrect (at 0.32 0.002 90) (size 0.46 0.4) (layers "B.Cu" "B.Mask") (roundrect_rratio 0.25)
      (net 9 "GND") (pintype "passive"))
  )

  (footprint "data-center-rdimm-ddr4-tester-footprints:C_0402_1005Metric" (layer "B.Cu")
    (at 185.425 78.275 180)
    (descr "Capacitor SMD 0402")
    (tags "capacitor SMD 0402")
    (property "Author" "Antmicro")
    (property "Dielectric" "X5R")
    (property "License" "Apache-2.0")
    (property "MPN" "GRM155R61H104KE14D")
    (property "Manufacturer" "Murata")
    (property "Sheetfile" "fpga-banks-16-34.kicad_sch")
    (property "Sheetname" "FPGA banks 16-34")
    (property "Val" "100n")
    (property "Voltage" "50V")
    (property "ki_description" " ")
    (attr smd)
    (fp_text reference "C18" (at 0.705 0.125) (layer "B.SilkS")
        (effects (font (size 0.7 0.7) (thickness 0.15)) (justify left bottom mirror))
    )
    (fp_text value "C_100n_0402" (at 0 -1.4) (layer "B.Fab") hide
        (effects (font (size 0.7 0.7) (thickness 0.15)) (justify left bottom mirror))
    )
    (fp_text user "${REFERENCE}" (at -0.932 -3.168) (layer "B.Fab") hide
        (effects (font (size 0.7 0.7) (thickness 0.15)) (justify left bottom mirror))
    )
    (fp_text user "License: Apache-2.0" (at -0.932 -5.17) (layer "B.Fab") hide
        (effects (font (size 0.7 0.7) (thickness 0.15)) (justify left bottom mirror))
    )
    (fp_text user "Author: Antmicro" (at -0.932 -4.17) (layer "B.Fab") hide
        (effects (font (size 0.7 0.7) (thickness 0.15)) (justify left bottom mirror))
    )
    (fp_rect (start -0.94 0.47) (end 0.94 -0.47)
      (stroke (width 0.05) (type solid)) (fill none) (layer "B.CrtYd"))
    (fp_rect (start -0.499 0.249) (end 0.499 -0.249)
      (stroke (width 0.15) (type solid)) (fill none) (layer "B.Fab"))
    (pad "1" smd roundrect (at -0.484 0 180) (size 0.59 0.64) (layers "B.Cu" "B.Paste" "B.Mask") (roundrect_rratio 0.25)
      (net 312 "VREF_33") (pintype "passive"))
    (pad "2" smd roundrect (at 0.484 0 180) (size 0.59 0.64) (layers "B.Cu" "B.Paste" "B.Mask") (roundrect_rratio 0.25)
      (net 9 "GND") (pintype "passive"))
  )

  (footprint "data-center-rdimm-ddr4-tester-footprints:C_0402_1005Metric" (layer "B.Cu")
    (at 185.425 77.25 180)
    (descr "Capacitor SMD 0402")
    (tags "capacitor SMD 0402")
    (property "Author" "Antmicro")
    (property "Dielectric" "X5R")
    (property "License" "Apache-2.0")
    (property "MPN" "GRM155R61H104KE14D")
    (property "Manufacturer" "Murata")
    (property "Sheetfile" "fpga-banks-16-34.kicad_sch")
    (property "Sheetname" "FPGA banks 16-34")
    (property "Val" "100n")
    (property "Voltage" "50V")
    (property "ki_description" " ")
    (attr smd)
    (fp_text reference "C146" (at 0.655 0.13) (layer "B.SilkS")
        (effects (font (size 0.7 0.7) (thickness 0.15)) (justify left bottom mirror))
    )
    (fp_text value "C_100n_0402" (at 0 -1.4) (layer "B.Fab") hide
        (effects (font (size 0.7 0.7) (thickness 0.15)) (justify left bottom mirror))
    )
    (fp_text user "License: Apache-2.0" (at -0.932 -5.17) (layer "B.Fab") hide
        (effects (font (size 0.7 0.7) (thickness 0.15)) (justify left bottom mirror))
    )
    (fp_text user "${REFERENCE}" (at -0.932 -3.168) (layer "B.Fab") hide
        (effects (font (size 0.7 0.7) (thickness 0.15)) (justify left bottom mirror))
    )
    (fp_text user "Author: Antmicro" (at -0.932 -4.17) (layer "B.Fab") hide
        (effects (font (size 0.7 0.7) (thickness 0.15)) (justify left bottom mirror))
    )
    (fp_rect (start -0.94 0.47) (end 0.94 -0.47)
      (stroke (width 0.05) (type solid)) (fill none) (layer "B.CrtYd"))
    (fp_rect (start -0.499 0.249) (end 0.499 -0.249)
      (stroke (width 0.15) (type solid)) (fill none) (layer "B.Fab"))
    (pad "1" smd roundrect (at -0.484 0 180) (size 0.59 0.64) (layers "B.Cu" "B.Paste" "B.Mask") (roundrect_rratio 0.25)
      (net 312 "VREF_33") (pintype "passive"))
    (pad "2" smd roundrect (at 0.484 0 180) (size 0.59 0.64) (layers "B.Cu" "B.Paste" "B.Mask") (roundrect_rratio 0.25)
      (net 9 "GND") (pintype "passive"))
  )

  (footprint "data-center-rdimm-ddr4-tester-footprints:R_0603_1608Metric" (layer "B.Cu")
    (at 187.75 77.275 90)
    (descr "Resistor SMD 0603")
    (tags "resistor SMD 0603")
    (property "Author" "Antmicro")
    (property "License" "Apache-2.0")
    (property "MPN" "CR0603-FX-1001ELF")
    (property "Manufacturer" "Bourns")
    (property "Sheetfile" "fpga-banks-16-34.kicad_sch")
    (property "Sheetname" "FPGA banks 16-34")
    (property "Tolerance" "1%")
    (property "Val" "1k")
    (property "ki_description" "1k resistor in 0603 package with 1% tolerance")
    (attr smd)
    (fp_text reference "R65" (at 3.235 0.4 270) (layer "B.SilkS")
        (effects (font (size 0.7 0.7) (thickness 0.15)) (justify left bottom mirror))
    )
    (fp_text value "R_1k_0603" (at 0 -1.6 270) (layer "B.Fab") hide
        (effects (font (size 0.7 0.7) (thickness 0.15)) (justify left bottom mirror))
    )
    (fp_text user "License: Apache-2.0" (at -1.25 -5.9 270) (layer "B.Fab") hide
        (effects (font (size 0.7 0.7) (thickness 0.15)) (justify left bottom mirror))
    )
    (fp_text user "Author: Antmicro" (at -1.25 -4.9 270) (layer "B.Fab") hide
        (effects (font (size 0.7 0.7) (thickness 0.15)) (justify left bottom mirror))
    )
    (fp_text user "${REFERENCE}" (at -1.25 -3.898 270) (layer "B.Fab") hide
        (effects (font (size 0.7 0.7) (thickness 0.15)) (justify left bottom mirror))
    )
    (fp_line (start -0.3 -0.3) (end 0.3 -0.3)
      (stroke (width 0.15) (type solid)) (layer "B.SilkS"))
    (fp_line (start -0.3 0.3) (end 0.3 0.3)
      (stroke (width 0.15) (type solid)) (layer "B.SilkS"))
    (fp_rect (start -1.25 0.7) (end 1.25 -0.7)
      (stroke (width 0.05) (type solid)) (fill none) (layer "B.CrtYd"))
    (fp_rect (start -0.8 0.4) (end 0.8 -0.4)
      (stroke (width 0.15) (type solid)) (fill none) (layer "B.Fab"))
    (pad "1" smd roundrect (at -0.7 0 90) (size 0.6 0.8) (layers "B.Cu" "B.Paste" "B.Mask") (roundrect_rratio 0.2)
      (net 77 "VDDQ") (pintype "passive"))
    (pad "2" smd roundrect (at 0.7 0 90) (size 0.6 0.8) (layers "B.Cu" "B.Paste" "B.Mask") (roundrect_rratio 0.2)
      (net 312 "VREF_33") (pintype "passive"))
  )

  (footprint "data-center-rdimm-ddr4-tester-footprints:Testpoint_smd_1mm" (layer "B.Cu")
    (at 148.176328 107.619208)
    (property "Author" "Antmicro")
    (property "License" "Apache-2.0")
    (property "MPN" "")
    (property "Manufacturer" "")
    (property "Sheetfile" "interfaces.kicad_sch")
    (property "Sheetname" "Interfaces")
    (property "ki_description" "Test Point 1mm")
    (attr exclude_from_pos_files)
    (fp_text reference "TP11" (at 0 0.731898 180) (layer "B.SilkS")
        (effects (font (size 0.7 0.7) (thickness 0.15)) (justify left bottom mirror))
    )
    (fp_text value "TP_1mm_SMD" (at 0 -1.4 180) (layer "B.Fab") hide
        (effects (font (size 0.7 0.7) (thickness 0.15)) (justify left bottom mirror))
    )
    (fp_text user "${REFERENCE}" (at -0.5 -2.8 180) (layer "B.Fab") hide
        (effects (font (size 0.7 0.7) (thickness 0.15)) (justify left bottom mirror))
    )
    (fp_text user "License: Apache-2.0" (at -0.5 -5.2 180) (layer "B.Fab") hide
        (effects (font (size 0.7 0.7) (thickness 0.15)) (justify left bottom mirror))
    )
    (fp_text user "Author: Antmicro" (at -0.5 -4 180) (layer "B.Fab") hide
        (effects (font (size 0.7 0.7) (thickness 0.15)) (justify left bottom mirror))
    )
    (pad "1" smd circle (at 0 0) (size 1 1) (layers "B.Cu" "B.Mask")
      (net 665 "Net-(U7-ADBUS5)") (pinfunction "1") (pintype "passive"))
  )

  (footprint "data-center-rdimm-ddr4-tester-footprints:Testpoint_smd_1mm" (layer "B.Cu")
    (at 170.666328 105.200008 -90)
    (property "Author" "Antmicro")
    (property "License" "Apache-2.0")
    (property "MPN" "")
    (property "Manufacturer" "")
    (property "Sheetfile" "config-spi.kicad_sch")
    (property "Sheetname" "Config SPI flash")
    (property "ki_description" "Test Point 1mm")
    (attr exclude_from_pos_files)
    (fp_text reference "EMCCLK1" (at 1.469992 -2.423672 180) (layer "B.SilkS")
        (effects (font (size 0.7 0.7) (thickness 0.15)) (justify left bottom mirror))
    )
    (fp_text value "TP_1mm_SMD" (at 0 -1.4 90) (layer "B.Fab") hide
        (effects (font (size 0.7 0.7) (thickness 0.15)) (justify left bottom mirror))
    )
    (fp_text user "License: Apache-2.0" (at -0.5 -5.2 90) (layer "B.Fab") hide
        (effects (font (size 0.7 0.7) (thickness 0.15)) (justify left bottom mirror))
    )
    (fp_text user "Author: Antmicro" (at -0.5 -4 90) (layer "B.Fab") hide
        (effects (font (size 0.7 0.7) (thickness 0.15)) (justify left bottom mirror))
    )
    (fp_text user "${REFERENCE}" (at -0.5 -2.8 90) (layer "B.Fab") hide
        (effects (font (size 0.7 0.7) (thickness 0.15)) (justify left bottom mirror))
    )
    (pad "1" smd circle (at 0 0 270) (size 1 1) (layers "B.Cu" "B.Mask")
      (net 99 "EMCCLK") (pinfunction "1") (pintype "passive"))
  )

  (footprint "data-center-rdimm-ddr4-tester-footprints:R_0603_1608Metric" (layer "B.Cu")
    (at 185.725 75.975 180)
    (descr "Resistor SMD 0603")
    (tags "resistor SMD 0603")
    (property "Author" "Antmicro")
    (property "License" "Apache-2.0")
    (property "MPN" "CR0603-FX-1001ELF")
    (property "Manufacturer" "Bourns")
    (property "Sheetfile" "fpga-banks-16-34.kicad_sch")
    (property "Sheetname" "FPGA banks 16-34")
    (property "Tolerance" "1%")
    (property "Val" "1k")
    (property "ki_description" "1k resistor in 0603 package with 1% tolerance")
    (attr smd)
    (fp_text reference "R66" (at 1.035 -0.185) (layer "B.SilkS")
        (effects (font (size 0.7 0.7) (thickness 0.15)) (justify left bottom mirror))
    )
    (fp_text value "R_1k_0603" (at 0 -1.6) (layer "B.Fab") hide
        (effects (font (size 0.7 0.7) (thickness 0.15)) (justify left bottom mirror))
    )
    (fp_text user "${REFERENCE}" (at -1.25 -3.898) (layer "B.Fab") hide
        (effects (font (size 0.7 0.7) (thickness 0.15)) (justify left bottom mirror))
    )
    (fp_text user "Author: Antmicro" (at -1.25 -4.9) (layer "B.Fab") hide
        (effects (font (size 0.7 0.7) (thickness 0.15)) (justify left bottom mirror))
    )
    (fp_text user "License: Apache-2.0" (at -1.25 -5.9) (layer "B.Fab") hide
        (effects (font (size 0.7 0.7) (thickness 0.15)) (justify left bottom mirror))
    )
    (fp_line (start -0.3 -0.3) (end 0.3 -0.3)
      (stroke (width 0.15) (type solid)) (layer "B.SilkS"))
    (fp_line (start -0.3 0.3) (end 0.3 0.3)
      (stroke (width 0.15) (type solid)) (layer "B.SilkS"))
    (fp_rect (start -1.25 0.7) (end 1.25 -0.7)
      (stroke (width 0.05) (type solid)) (fill none) (layer "B.CrtYd"))
    (fp_rect (start -0.8 0.4) (end 0.8 -0.4)
      (stroke (width 0.15) (type solid)) (fill none) (layer "B.Fab"))
    (pad "1" smd roundrect (at -0.7 0 180) (size 0.6 0.8) (layers "B.Cu" "B.Paste" "B.Mask") (roundrect_rratio 0.2)
      (net 312 "VREF_33") (pintype "passive"))
    (pad "2" smd roundrect (at 0.7 0 180) (size 0.6 0.8) (layers "B.Cu" "B.Paste" "B.Mask") (roundrect_rratio 0.2)
      (net 9 "GND") (pintype "passive"))
  )

  (footprint "data-center-rdimm-ddr4-tester-footprints:R_0402_1005Metric" (layer "B.Cu")
    (at 158.686328 89.010008 -90)
    (descr "Resistor SMD 0402")
    (tags "resistor SMD 0402")
    (property "Author" "Antmicro")
    (property "License" "Apache-2.0")
    (property "MPN" "CR0402-FX-2201GLF")
    (property "Manufacturer" "Bourns")
    (property "Sheetfile" "ethernet.kicad_sch")
    (property "Sheetname" "Ethernet")
    (property "Tolerance" "1%")
    (property "Val" "2k2")
    (property "ki_description" "2k2 resistor in 0402 package with 1% tolerance")
    (attr smd)
    (fp_text reference "R89" (at -1.165008 -7.958672 90) (layer "B.SilkS")
        (effects (font (size 0.7 0.7) (thickness 0.15)) (justify left bottom mirror))
    )
    (fp_text value "R_2k2_0402" (at 0 -1.4 90) (layer "B.Fab") hide
        (effects (font (size 0.7 0.7) (thickness 0.15)) (justify left bottom mirror))
    )
    (fp_text user "Author: Antmicro" (at -0.95 -4.169 90) (layer "B.Fab") hide
        (effects (font (size 0.7 0.7) (thickness 0.15)) (justify left bottom mirror))
    )
    (fp_text user "${REFERENCE}" (at -0.95 -3.168 90) (layer "B.Fab") hide
        (effects (font (size 0.7 0.7) (thickness 0.15)) (justify left bottom mirror))
    )
    (fp_text user "License: Apache-2.0" (at -0.95 -5.169 90) (layer "B.Fab") hide
        (effects (font (size 0.7 0.7) (thickness 0.15)) (justify left bottom mirror))
    )
    (fp_rect (start -0.93 0.47) (end 0.93 -0.47)
      (stroke (width 0.05) (type solid)) (fill none) (layer "B.CrtYd"))
    (fp_rect (start -0.5 0.25) (end 0.5 -0.25)
      (stroke (width 0.15) (type solid)) (fill none) (layer "B.Fab"))
    (pad "1" smd roundrect (at -0.485 0 270) (size 0.59 0.64) (layers "B.Cu" "B.Paste" "B.Mask") (roundrect_rratio 0.25)
      (net 27 "ETH_RXD1") (pintype "passive"))
    (pad "2" smd roundrect (at 0.485 0 270) (size 0.59 0.64) (layers "B.Cu" "B.Paste" "B.Mask") (roundrect_rratio 0.25)
      (net 9 "GND") (pintype "passive"))
  )

  (footprint "data-center-rdimm-ddr4-tester-footprints:R_0402_1005Metric" (layer "B.Cu")
    (at 159.636328 87.320008 90)
    (descr "Resistor SMD 0402")
    (tags "resistor SMD 0402")
    (property "Author" "Antmicro")
    (property "License" "Apache-2.0")
    (property "MPN" "CR0402-FX-1002GLF")
    (property "Manufacturer" "Bourns")
    (property "Sheetfile" "ethernet.kicad_sch")
    (property "Sheetname" "Ethernet")
    (property "Tolerance" "1%")
    (property "Val" "10k")
    (property "ki_description" "10k resistor in 0402 package with 1% tolerance")
    (attr smd)
    (fp_text reference "R72" (at 1.170008 8.103672 270) (layer "B.SilkS")
        (effects (font (size 0.7 0.7) (thickness 0.15)) (justify left bottom mirror))
    )
    (fp_text value "R_10k_0402" (at 0 -1.4 270) (layer "B.Fab") hide
        (effects (font (size 0.7 0.7) (thickness 0.15)) (justify left bottom mirror))
    )
    (fp_text user "${REFERENCE}" (at -0.95 -3.168 270) (layer "B.Fab") hide
        (effects (font (size 0.7 0.7) (thickness 0.15)) (justify left bottom mirror))
    )
    (fp_text user "Author: Antmicro" (at -0.95 -4.169 270) (layer "B.Fab") hide
        (effects (font (size 0.7 0.7) (thickness 0.15)) (justify left bottom mirror))
    )
    (fp_text user "License: Apache-2.0" (at -0.95 -5.169 270) (layer "B.Fab") hide
        (effects (font (size 0.7 0.7) (thickness 0.15)) (justify left bottom mirror))
    )
    (fp_rect (start -0.93 0.47) (end 0.93 -0.47)
      (stroke (width 0.05) (type solid)) (fill none) (layer "B.CrtYd"))
    (fp_rect (start -0.5 0.25) (end 0.5 -0.25)
      (stroke (width 0.15) (type solid)) (fill none) (layer "B.Fab"))
    (pad "1" smd roundrect (at -0.485 0 90) (size 0.59 0.64) (layers "B.Cu" "B.Paste" "B.Mask") (roundrect_rratio 0.25)
      (net 41 "ETH_RXD2") (pintype "passive"))
    (pad "2" smd roundrect (at 0.485 0 90) (size 0.59 0.64) (layers "B.Cu" "B.Paste" "B.Mask") (roundrect_rratio 0.25)
      (net 143 "3V3_SYS") (pintype "passive"))
  )

  (footprint "data-center-rdimm-ddr4-tester-footprints:C_0201" (layer "B.Cu")
    (at 187.186328 88.560008 90)
    (descr "Capacitor SMD 0201")
    (tags "capacitor SMD 0201")
    (property "Author" "Antmicro")
    (property "Dielectric" "")
    (property "License" "Apache-2.0")
    (property "MPN" "CC0201KRX6S5BB104")
    (property "Manufacturer" "Yaego")
    (property "Sheetfile" "fpga-power.kicad_sch")
    (property "Sheetname" "FPGA power")
    (property "Val" "100n")
    (property "Voltage" "")
    (property "ki_description" " ")
    (attr smd)
    (fp_text reference "C49" (at 10.330008 18.203672 270) (layer "B.SilkS")
        (effects (font (size 0.7 0.7) (thickness 0.15)) (justify left bottom mirror))
    )
    (fp_text value "C_100n_0201" (at 0 -1.4 270) (layer "B.Fab") hide
        (effects (font (size 0.7 0.7) (thickness 0.15)) (justify left bottom mirror))
    )
    (fp_text user "Author: Antmicro" (at -0.72 -5.4 270) (layer "B.Fab") hide
        (effects (font (size 0.7 0.7) (thickness 0.15)) (justify left bottom mirror))
    )
    (fp_text user "${REFERENCE}" (at -0.72 -3.4 270) (layer "B.Fab") hide
        (effects (font (size 0.7 0.7) (thickness 0.15)) (justify left bottom mirror))
    )
    (fp_text user "License: Apache-2.0" (at -0.72 -4.4 270) (layer "B.Fab") hide
        (effects (font (size 0.7 0.7) (thickness 0.15)) (justify left bottom mirror))
    )
    (fp_rect (start -0.72 0.38) (end 0.72 -0.38)
      (stroke (width 0.05) (type solid)) (fill none) (layer "B.CrtYd"))
    (fp_rect (start 0.3 -0.15) (end -0.301 0.149)
      (stroke (width 0.15) (type solid)) (fill none) (layer "B.Fab"))
    (pad "" smd roundrect (at -0.349 0.002 90) (size 0.318 0.36) (layers "B.Paste") (roundrect_rratio 0.25))
    (pad "" smd roundrect (at 0.341 0.002 90) (size 0.318 0.36) (layers "B.Paste") (roundrect_rratio 0.25))
    (pad "1" smd roundrect (at -0.321 0.002 90) (size 0.46 0.4) (layers "B.Cu" "B.Mask") (roundrect_rratio 0.25)
      (net 144 "1V8_SYS") (pintype "passive"))
    (pad "2" smd roundrect (at 0.32 0.002 90) (size 0.46 0.4) (layers "B.Cu" "B.Mask") (roundrect_rratio 0.25)
      (net 9 "GND") (pintype "passive"))
  )

  (footprint "data-center-rdimm-ddr4-tester-footprints:C_0201" (layer "B.Cu")
    (at 182.186328 88.560008 90)
    (descr "Capacitor SMD 0201")
    (tags "capacitor SMD 0201")
    (property "Author" "Antmicro")
    (property "Dielectric" "")
    (property "License" "Apache-2.0")
    (property "MPN" "CC0201KRX6S5BB104")
    (property "Manufacturer" "Yaego")
    (property "Sheetfile" "fpga-power.kicad_sch")
    (property "Sheetname" "FPGA power")
    (property "Val" "100n")
    (property "Voltage" "")
    (property "ki_description" " ")
    (attr smd)
    (fp_text reference "C59" (at 10.270008 18.063672 270) (layer "B.SilkS")
        (effects (font (size 0.7 0.7) (thickness 0.15)) (justify left bottom mirror))
    )
    (fp_text value "C_100n_0201" (at 0 -1.4 270) (layer "B.Fab") hide
        (effects (font (size 0.7 0.7) (thickness 0.15)) (justify left bottom mirror))
    )
    (fp_text user "Author: Antmicro" (at -0.72 -5.4 270) (layer "B.Fab") hide
        (effects (font (size 0.7 0.7) (thickness 0.15)) (justify left bottom mirror))
    )
    (fp_text user "License: Apache-2.0" (at -0.72 -4.4 270) (layer "B.Fab") hide
        (effects (font (size 0.7 0.7) (thickness 0.15)) (justify left bottom mirror))
    )
    (fp_text user "${REFERENCE}" (at -0.72 -3.4 270) (layer "B.Fab") hide
        (effects (font (size 0.7 0.7) (thickness 0.15)) (justify left bottom mirror))
    )
    (fp_rect (start -0.72 0.38) (end 0.72 -0.38)
      (stroke (width 0.05) (type solid)) (fill none) (layer "B.CrtYd"))
    (fp_rect (start 0.3 -0.15) (end -0.301 0.149)
      (stroke (width 0.15) (type solid)) (fill none) (layer "B.Fab"))
    (pad "" smd roundrect (at -0.349 0.002 90) (size 0.318 0.36) (layers "B.Paste") (roundrect_rratio 0.25))
    (pad "" smd roundrect (at 0.341 0.002 90) (size 0.318 0.36) (layers "B.Paste") (roundrect_rratio 0.25))
    (pad "1" smd roundrect (at -0.321 0.002 90) (size 0.46 0.4) (layers "B.Cu" "B.Mask") (roundrect_rratio 0.25)
      (net 147 "1V0_SYS") (pintype "passive"))
    (pad "2" smd roundrect (at 0.32 0.002 90) (size 0.46 0.4) (layers "B.Cu" "B.Mask") (roundrect_rratio 0.25)
      (net 9 "GND") (pintype "passive"))
  )

  (footprint "data-center-rdimm-ddr4-tester-footprints:C_0603_1608Metric" (layer "B.Cu")
    (at 185.625 90.725 90)
    (descr "Capacitor SMD 0603")
    (tags "capacitor 0603")
    (property "Author" "Antmicro")
    (property "Dielectric" "")
    (property "License" "Apache-2.0")
    (property "MPN" "GRM188R60J476ME15D")
    (property "Manufacturer" "Murata")
    (property "Sheetfile" "fpga-power.kicad_sch")
    (property "Sheetname" "FPGA power")
    (property "Val" "47u")
    (property "Voltage" "")
    (property "ki_description" " ")
    (attr smd)
    (fp_text reference "C22" (at 10.195 18.315 270) (layer "B.SilkS")
        (effects (font (size 0.7 0.7) (thickness 0.15)) (justify left bottom mirror))
    )
    (fp_text value "C_47u_0603" (at 0 -1.6 270) (layer "B.Fab") hide
        (effects (font (size 0.7 0.7) (thickness 0.15)) (justify left bottom mirror))
    )
    (fp_text user "Author: Antmicro" (at -1.682 -4.894 270) (layer "B.Fab") hide
        (effects (font (size 0.7 0.7) (thickness 0.15)) (justify left bottom mirror))
    )
    (fp_text user "License: Apache-2.0" (at -1.682 -5.895 270) (layer "B.Fab") hide
        (effects (font (size 0.7 0.7) (thickness 0.15)) (justify left bottom mirror))
    )
    (fp_text user "${REFERENCE}" (at -1.682 -3.895 270) (layer "B.Fab") hide
        (effects (font (size 0.7 0.7) (thickness 0.15)) (justify left bottom mirror))
    )
    (fp_line (start -0.3 -0.3) (end 0.3 -0.3)
      (stroke (width 0.15) (type solid)) (layer "B.SilkS"))
    (fp_line (start -0.3 0.3) (end 0.3 0.3)
      (stroke (width 0.15) (type solid)) (layer "B.SilkS"))
    (fp_rect (start -1.24 0.7) (end 1.24 -0.7)
      (stroke (width 0.05) (type solid)) (fill none) (layer "B.CrtYd"))
    (fp_rect (start -0.8 0.4) (end 0.8 -0.4)
      (stroke (width 0.15) (type solid)) (fill none) (layer "B.Fab"))
    (pad "1" smd roundrect (at -0.7 0 90) (size 0.6 0.8) (layers "B.Cu" "B.Paste" "B.Mask") (roundrect_rratio 0.2)
      (net 144 "1V8_SYS") (pintype "passive"))
    (pad "2" smd roundrect (at 0.7 0 90) (size 0.6 0.8) (layers "B.Cu" "B.Paste" "B.Mask") (roundrect_rratio 0.2)
      (net 9 "GND") (pintype "passive"))
  )

  (footprint "data-center-rdimm-ddr4-tester-footprints:C_0603_1608Metric" (layer "B.Cu")
    (at 188.775 98.35 90)
    (descr "Capacitor SMD 0603")
    (tags "capacitor 0603")
    (property "Author" "Antmicro")
    (property "Dielectric" "")
    (property "License" "Apache-2.0")
    (property "MPN" "GRM188R60J476ME15D")
    (property "Manufacturer" "Murata")
    (property "Sheetfile" "fpga-power.kicad_sch")
    (property "Sheetname" "FPGA power")
    (property "Val" "47u")
    (property "Voltage" "")
    (property "ki_description" " ")
    (attr smd)
    (fp_text reference "C114" (at -0.95 0.325 270) (layer "B.SilkS")
        (effects (font (size 0.7 0.7) (thickness 0.15)) (justify left bottom mirror))
    )
    (fp_text value "C_47u_0603" (at 0 -1.6 270) (layer "B.Fab") hide
        (effects (font (size 0.7 0.7) (thickness 0.15)) (justify left bottom mirror))
    )
    (fp_text user "License: Apache-2.0" (at -1.682 -5.895 270) (layer "B.Fab") hide
        (effects (font (size 0.7 0.7) (thickness 0.15)) (justify left bottom mirror))
    )
    (fp_text user "Author: Antmicro" (at -1.682 -4.894 270) (layer "B.Fab") hide
        (effects (font (size 0.7 0.7) (thickness 0.15)) (justify left bottom mirror))
    )
    (fp_text user "${REFERENCE}" (at -1.682 -3.895 270) (layer "B.Fab") hide
        (effects (font (size 0.7 0.7) (thickness 0.15)) (justify left bottom mirror))
    )
    (fp_line (start -0.3 -0.3) (end 0.3 -0.3)
      (stroke (width 0.15) (type solid)) (layer "B.SilkS"))
    (fp_line (start -0.3 0.3) (end 0.3 0.3)
      (stroke (width 0.15) (type solid)) (layer "B.SilkS"))
    (fp_rect (start -1.24 0.7) (end 1.24 -0.7)
      (stroke (width 0.05) (type solid)) (fill none) (layer "B.CrtYd"))
    (fp_rect (start -0.8 0.4) (end 0.8 -0.4)
      (stroke (width 0.15) (type solid)) (fill none) (layer "B.Fab"))
    (pad "1" smd roundrect (at -0.7 0 90) (size 0.6 0.8) (layers "B.Cu" "B.Paste" "B.Mask") (roundrect_rratio 0.2)
      (net 144 "1V8_SYS") (pintype "passive"))
    (pad "2" smd roundrect (at 0.7 0 90) (size 0.6 0.8) (layers "B.Cu" "B.Paste" "B.Mask") (roundrect_rratio 0.2)
      (net 9 "GND") (pintype "passive"))
  )

  (footprint "data-center-rdimm-ddr4-tester-footprints:C_0201" (layer "B.Cu")
    (at 182.186328 93.560008 90)
    (descr "Capacitor SMD 0201")
    (tags "capacitor SMD 0201")
    (property "Author" "Antmicro")
    (property "Dielectric" "")
    (property "License" "Apache-2.0")
    (property "MPN" "CC0201KRX6S5BB104")
    (property "Manufacturer" "Yaego")
    (property "Sheetfile" "fpga-power.kicad_sch")
    (property "Sheetname" "FPGA power")
    (property "Val" "100n")
    (property "Voltage" "")
    (property "ki_description" " ")
    (attr smd)
    (fp_text reference "C67" (at 10.360008 18.393672 270) (layer "B.SilkS")
        (effects (font (size 0.7 0.7) (thickness 0.15)) (justify left bottom mirror))
    )
    (fp_text value "C_100n_0201" (at 0 -1.4 270) (layer "B.Fab") hide
        (effects (font (size 0.7 0.7) (thickness 0.15)) (justify left bottom mirror))
    )
    (fp_text user "${REFERENCE}" (at -0.72 -3.4 270) (layer "B.Fab") hide
        (effects (font (size 0.7 0.7) (thickness 0.15)) (justify left bottom mirror))
    )
    (fp_text user "Author: Antmicro" (at -0.72 -5.4 270) (layer "B.Fab") hide
        (effects (font (size 0.7 0.7) (thickness 0.15)) (justify left bottom mirror))
    )
    (fp_text user "License: Apache-2.0" (at -0.72 -4.4 270) (layer "B.Fab") hide
        (effects (font (size 0.7 0.7) (thickness 0.15)) (justify left bottom mirror))
    )
    (fp_rect (start -0.72 0.38) (end 0.72 -0.38)
      (stroke (width 0.05) (type solid)) (fill none) (layer "B.CrtYd"))
    (fp_rect (start 0.3 -0.15) (end -0.301 0.149)
      (stroke (width 0.15) (type solid)) (fill none) (layer "B.Fab"))
    (pad "" smd roundrect (at -0.349 0.002 90) (size 0.318 0.36) (layers "B.Paste") (roundrect_rratio 0.25))
    (pad "" smd roundrect (at 0.341 0.002 90) (size 0.318 0.36) (layers "B.Paste") (roundrect_rratio 0.25))
    (pad "1" smd roundrect (at -0.321 0.002 90) (size 0.46 0.4) (layers "B.Cu" "B.Mask") (roundrect_rratio 0.25)
      (net 147 "1V0_SYS") (pintype "passive"))
    (pad "2" smd roundrect (at 0.32 0.002 90) (size 0.46 0.4) (layers "B.Cu" "B.Mask") (roundrect_rratio 0.25)
      (net 9 "GND") (pintype "passive"))
  )

  (footprint "data-center-rdimm-ddr4-tester-footprints:C_0603_1608Metric" (layer "B.Cu")
    (at 185.611328 95.585008 -90)
    (descr "Capacitor SMD 0603")
    (tags "capacitor 0603")
    (property "Author" "Antmicro")
    (property "Dielectric" "")
    (property "License" "Apache-2.0")
    (property "MPN" "GRM188R60J476ME15D")
    (property "Manufacturer" "Murata")
    (property "Sheetfile" "fpga-power.kicad_sch")
    (property "Sheetname" "FPGA power")
    (property "Val" "47u")
    (property "Voltage" "")
    (property "ki_description" " ")
    (attr smd)
    (fp_text reference "C25" (at -0.895008 0.611328 90) (layer "B.SilkS")
        (effects (font (size 0.7 0.7) (thickness 0.15)) (justify left bottom mirror))
    )
    (fp_text value "C_47u_0603" (at 0 -1.6 90) (layer "B.Fab") hide
        (effects (font (size 0.7 0.7) (thickness 0.15)) (justify left bottom mirror))
    )
    (fp_text user "Author: Antmicro" (at -1.682 -4.894 90) (layer "B.Fab") hide
        (effects (font (size 0.7 0.7) (thickness 0.15)) (justify left bottom mirror))
    )
    (fp_text user "${REFERENCE}" (at -1.682 -3.895 90) (layer "B.Fab") hide
        (effects (font (size 0.7 0.7) (thickness 0.15)) (justify left bottom mirror))
    )
    (fp_text user "License: Apache-2.0" (at -1.682 -5.895 90) (layer "B.Fab") hide
        (effects (font (size 0.7 0.7) (thickness 0.15)) (justify left bottom mirror))
    )
    (fp_line (start -0.3 -0.3) (end 0.3 -0.3)
      (stroke (width 0.15) (type solid)) (layer "B.SilkS"))
    (fp_line (start -0.3 0.3) (end 0.3 0.3)
      (stroke (width 0.15) (type solid)) (layer "B.SilkS"))
    (fp_rect (start -1.24 0.7) (end 1.24 -0.7)
      (stroke (width 0.05) (type solid)) (fill none) (layer "B.CrtYd"))
    (fp_rect (start -0.8 0.4) (end 0.8 -0.4)
      (stroke (width 0.15) (type solid)) (fill none) (layer "B.Fab"))
    (pad "1" smd roundrect (at -0.7 0 270) (size 0.6 0.8) (layers "B.Cu" "B.Paste" "B.Mask") (roundrect_rratio 0.2)
      (net 144 "1V8_SYS") (pintype "passive"))
    (pad "2" smd roundrect (at 0.7 0 270) (size 0.6 0.8) (layers "B.Cu" "B.Paste" "B.Mask") (roundrect_rratio 0.2)
      (net 9 "GND") (pintype "passive"))
  )

  (footprint "data-center-rdimm-ddr4-tester-footprints:C_0402_1005Metric" (layer "B.Cu")
    (at 193.086328 54.760008 90)
    (descr "Capacitor SMD 0402")
    (tags "capacitor SMD 0402")
    (property "Author" "Antmicro")
    (property "Dielectric" "X5R")
    (property "License" "Apache-2.0")
    (property "MPN" "GRM155R61H104KE14D")
    (property "Manufacturer" "Murata")
    (property "Sheetfile" "DDR4.kicad_sch")
    (property "Sheetname" "DDR4")
    (property "Val" "100n")
    (property "Voltage" "50V")
    (property "ki_description" " ")
    (attr smd)
    (fp_text reference "C160" (at 4.050008 0.423672 270) (layer "B.SilkS")
        (effects (font (size 0.7 0.7) (thickness 0.15)) (justify left bottom mirror))
    )
    (fp_text value "C_100n_0402" (at 0 -1.4 270) (layer "B.Fab") hide
        (effects (font (size 0.7 0.7) (thickness 0.15)) (justify left bottom mirror))
    )
    (fp_text user "License: Apache-2.0" (at -0.932 -5.17 270) (layer "B.Fab") hide
        (effects (font (size 0.7 0.7) (thickness 0.15)) (justify left bottom mirror))
    )
    (fp_text user "${REFERENCE}" (at -0.932 -3.168 270) (layer "B.Fab") hide
        (effects (font (size 0.7 0.7) (thickness 0.15)) (justify left bottom mirror))
    )
    (fp_text user "Author: Antmicro" (at -0.932 -4.17 270) (layer "B.Fab") hide
        (effects (font (size 0.7 0.7) (thickness 0.15)) (justify left bottom mirror))
    )
    (fp_rect (start -0.94 0.47) (end 0.94 -0.47)
      (stroke (width 0.05) (type solid)) (fill none) (layer "B.CrtYd"))
    (fp_rect (start -0.499 0.249) (end 0.499 -0.249)
      (stroke (width 0.15) (type solid)) (fill none) (layer "B.Fab"))
    (pad "1" smd roundrect (at -0.484 0 90) (size 0.59 0.64) (layers "B.Cu" "B.Paste" "B.Mask") (roundrect_rratio 0.25)
      (net 77 "VDDQ") (pintype "passive"))
    (pad "2" smd roundrect (at 0.484 0 90) (size 0.59 0.64) (layers "B.Cu" "B.Paste" "B.Mask") (roundrect_rratio 0.25)
      (net 9 "GND") (pintype "passive"))
  )

  (footprint "data-center-rdimm-ddr4-tester-footprints:C_0402_1005Metric" (layer "B.Cu")
    (at 190.536328 54.760008 90)
    (descr "Capacitor SMD 0402")
    (tags "capacitor SMD 0402")
    (property "Author" "Antmicro")
    (property "Dielectric" "X5R")
    (property "License" "Apache-2.0")
    (property "MPN" "GRM155R61H104KE14D")
    (property "Manufacturer" "Murata")
    (property "Sheetfile" "DDR4.kicad_sch")
    (property "Sheetname" "DDR4")
    (property "Val" "100n")
    (property "Voltage" "50V")
    (property "ki_description" " ")
    (attr smd)
    (fp_text reference "C161" (at 4.050008 0.423672 270) (layer "B.SilkS")
        (effects (font (size 0.7 0.7) (thickness 0.15)) (justify left bottom mirror))
    )
    (fp_text value "C_100n_0402" (at 0 -1.4 270) (layer "B.Fab") hide
        (effects (font (size 0.7 0.7) (thickness 0.15)) (justify left bottom mirror))
    )
    (fp_text user "License: Apache-2.0" (at -0.932 -5.17 270) (layer "B.Fab") hide
        (effects (font (size 0.7 0.7) (thickness 0.15)) (justify left bottom mirror))
    )
    (fp_text user "${REFERENCE}" (at -0.932 -3.168 270) (layer "B.Fab") hide
        (effects (font (size 0.7 0.7) (thickness 0.15)) (justify left bottom mirror))
    )
    (fp_text user "Author: Antmicro" (at -0.932 -4.17 270) (layer "B.Fab") hide
        (effects (font (size 0.7 0.7) (thickness 0.15)) (justify left bottom mirror))
    )
    (fp_rect (start -0.94 0.47) (end 0.94 -0.47)
      (stroke (width 0.05) (type solid)) (fill none) (layer "B.CrtYd"))
    (fp_rect (start -0.499 0.249) (end 0.499 -0.249)
      (stroke (width 0.15) (type solid)) (fill none) (layer "B.Fab"))
    (pad "1" smd roundrect (at -0.484 0 90) (size 0.59 0.64) (layers "B.Cu" "B.Paste" "B.Mask") (roundrect_rratio 0.25)
      (net 77 "VDDQ") (pintype "passive"))
    (pad "2" smd roundrect (at 0.484 0 90) (size 0.59 0.64) (layers "B.Cu" "B.Paste" "B.Mask") (roundrect_rratio 0.25)
      (net 9 "GND") (pintype "passive"))
  )

  (footprint "data-center-rdimm-ddr4-tester-footprints:C_0402_1005Metric" (layer "B.Cu")
    (at 187.986328 54.760008 90)
    (descr "Capacitor SMD 0402")
    (tags "capacitor SMD 0402")
    (property "Author" "Antmicro")
    (property "Dielectric" "X5R")
    (property "License" "Apache-2.0")
    (property "MPN" "GRM155R61H104KE14D")
    (property "Manufacturer" "Murata")
    (property "Sheetfile" "DDR4.kicad_sch")
    (property "Sheetname" "DDR4")
    (property "Val" "100n")
    (property "Voltage" "50V")
    (property "ki_description" " ")
    (attr smd)
    (fp_text reference "C162" (at 4.050008 0.423672 270) (layer "B.SilkS")
        (effects (font (size 0.7 0.7) (thickness 0.15)) (justify left bottom mirror))
    )
    (fp_text value "C_100n_0402" (at 0 -1.4 270) (layer "B.Fab") hide
        (effects (font (size 0.7 0.7) (thickness 0.15)) (justify left bottom mirror))
    )
    (fp_text user "License: Apache-2.0" (at -0.932 -5.17 270) (layer "B.Fab") hide
        (effects (font (size 0.7 0.7) (thickness 0.15)) (justify left bottom mirror))
    )
    (fp_text user "Author: Antmicro" (at -0.932 -4.17 270) (layer "B.Fab") hide
        (effects (font (size 0.7 0.7) (thickness 0.15)) (justify left bottom mirror))
    )
    (fp_text user "${REFERENCE}" (at -0.932 -3.168 270) (layer "B.Fab") hide
        (effects (font (size 0.7 0.7) (thickness 0.15)) (justify left bottom mirror))
    )
    (fp_rect (start -0.94 0.47) (end 0.94 -0.47)
      (stroke (width 0.05) (type solid)) (fill none) (layer "B.CrtYd"))
    (fp_rect (start -0.499 0.249) (end 0.499 -0.249)
      (stroke (width 0.15) (type solid)) (fill none) (layer "B.Fab"))
    (pad "1" smd roundrect (at -0.484 0 90) (size 0.59 0.64) (layers "B.Cu" "B.Paste" "B.Mask") (roundrect_rratio 0.25)
      (net 77 "VDDQ") (pintype "passive"))
    (pad "2" smd roundrect (at 0.484 0 90) (size 0.59 0.64) (layers "B.Cu" "B.Paste" "B.Mask") (roundrect_rratio 0.25)
      (net 9 "GND") (pintype "passive"))
  )

  (footprint "data-center-rdimm-ddr4-tester-footprints:C_0402_1005Metric" (layer "B.Cu")
    (at 185.436328 54.760008 90)
    (descr "Capacitor SMD 0402")
    (tags "capacitor SMD 0402")
    (property "Author" "Antmicro")
    (property "Dielectric" "X5R")
    (property "License" "Apache-2.0")
    (property "MPN" "GRM155R61H104KE14D")
    (property "Manufacturer" "Murata")
    (property "Sheetfile" "DDR4.kicad_sch")
    (property "Sheetname" "DDR4")
    (property "Val" "100n")
    (property "Voltage" "50V")
    (property "ki_description" " ")
    (attr smd)
    (fp_text reference "C163" (at 4.050008 0.423672 270) (layer "B.SilkS")
        (effects (font (size 0.7 0.7) (thickness 0.15)) (justify left bottom mirror))
    )
    (fp_text value "C_100n_0402" (at 0 -1.4 270) (layer "B.Fab") hide
        (effects (font (size 0.7 0.7) (thickness 0.15)) (justify left bottom mirror))
    )
    (fp_text user "License: Apache-2.0" (at -0.932 -5.17 270) (layer "B.Fab") hide
        (effects (font (size 0.7 0.7) (thickness 0.15)) (justify left bottom mirror))
    )
    (fp_text user "Author: Antmicro" (at -0.932 -4.17 270) (layer "B.Fab") hide
        (effects (font (size 0.7 0.7) (thickness 0.15)) (justify left bottom mirror))
    )
    (fp_text user "${REFERENCE}" (at -0.932 -3.168 270) (layer "B.Fab") hide
        (effects (font (size 0.7 0.7) (thickness 0.15)) (justify left bottom mirror))
    )
    (fp_rect (start -0.94 0.47) (end 0.94 -0.47)
      (stroke (width 0.05) (type solid)) (fill none) (layer "B.CrtYd"))
    (fp_rect (start -0.499 0.249) (end 0.499 -0.249)
      (stroke (width 0.15) (type solid)) (fill none) (layer "B.Fab"))
    (pad "1" smd roundrect (at -0.484 0 90) (size 0.59 0.64) (layers "B.Cu" "B.Paste" "B.Mask") (roundrect_rratio 0.25)
      (net 77 "VDDQ") (pintype "passive"))
    (pad "2" smd roundrect (at 0.484 0 90) (size 0.59 0.64) (layers "B.Cu" "B.Paste" "B.Mask") (roundrect_rratio 0.25)
      (net 9 "GND") (pintype "passive"))
  )

  (footprint "data-center-rdimm-ddr4-tester-footprints:C_0402_1005Metric" (layer "B.Cu")
    (at 171.836328 55.060008 90)
    (descr "Capacitor SMD 0402")
    (tags "capacitor SMD 0402")
    (property "Author" "Antmicro")
    (property "Dielectric" "X5R")
    (property "License" "Apache-2.0")
    (property "MPN" "GRM155R61H104KE14D")
    (property "Manufacturer" "Murata")
    (property "Sheetfile" "DDR4.kicad_sch")
    (property "Sheetname" "DDR4")
    (property "Val" "100n")
    (property "Voltage" "50V")
    (property "ki_description" " ")
    (attr smd)
    (fp_text reference "C166" (at 4.350008 0.363672 270) (layer "B.SilkS")
        (effects (font (size 0.7 0.7) (thickness 0.15)) (justify left bottom mirror))
    )
    (fp_text value "C_100n_0402" (at 0 -1.4 270) (layer "B.Fab") hide
        (effects (font (size 0.7 0.7) (thickness 0.15)) (justify left bottom mirror))
    )
    (fp_text user "License: Apache-2.0" (at -0.932 -5.17 270) (layer "B.Fab") hide
        (effects (font (size 0.7 0.7) (thickness 0.15)) (justify left bottom mirror))
    )
    (fp_text user "Author: Antmicro" (at -0.932 -4.17 270) (layer "B.Fab") hide
        (effects (font (size 0.7 0.7) (thickness 0.15)) (justify left bottom mirror))
    )
    (fp_text user "${REFERENCE}" (at -0.932 -3.168 270) (layer "B.Fab") hide
        (effects (font (size 0.7 0.7) (thickness 0.15)) (justify left bottom mirror))
    )
    (fp_rect (start -0.94 0.47) (end 0.94 -0.47)
      (stroke (width 0.05) (type solid)) (fill none) (layer "B.CrtYd"))
    (fp_rect (start -0.499 0.249) (end 0.499 -0.249)
      (stroke (width 0.15) (type solid)) (fill none) (layer "B.Fab"))
    (pad "1" smd roundrect (at -0.484 0 90) (size 0.59 0.64) (layers "B.Cu" "B.Paste" "B.Mask") (roundrect_rratio 0.25)
      (net 77 "VDDQ") (pintype "passive"))
    (pad "2" smd roundrect (at 0.484 0 90) (size 0.59 0.64) (layers "B.Cu" "B.Paste" "B.Mask") (roundrect_rratio 0.25)
      (net 9 "GND") (pintype "passive"))
  )

  (footprint "data-center-rdimm-ddr4-tester-footprints:C_0402_1005Metric" (layer "B.Cu")
    (at 170.136328 55.060008 90)
    (descr "Capacitor SMD 0402")
    (tags "capacitor SMD 0402")
    (property "Author" "Antmicro")
    (property "Dielectric" "X5R")
    (property "License" "Apache-2.0")
    (property "MPN" "GRM155R61H104KE14D")
    (property "Manufacturer" "Murata")
    (property "Sheetfile" "DDR4.kicad_sch")
    (property "Sheetname" "DDR4")
    (property "Val" "100n")
    (property "Voltage" "50V")
    (property "ki_description" " ")
    (attr smd)
    (fp_text reference "C167" (at 4.350008 0.363672 270) (layer "B.SilkS")
        (effects (font (size 0.7 0.7) (thickness 0.15)) (justify left bottom mirror))
    )
    (fp_text value "C_100n_0402" (at 0 -1.4 270) (layer "B.Fab") hide
        (effects (font (size 0.7 0.7) (thickness 0.15)) (justify left bottom mirror))
    )
    (fp_text user "Author: Antmicro" (at -0.932 -4.17 270) (layer "B.Fab") hide
        (effects (font (size 0.7 0.7) (thickness 0.15)) (justify left bottom mirror))
    )
    (fp_text user "License: Apache-2.0" (at -0.932 -5.17 270) (layer "B.Fab") hide
        (effects (font (size 0.7 0.7) (thickness 0.15)) (justify left bottom mirror))
    )
    (fp_text user "${REFERENCE}" (at -0.932 -3.168 270) (layer "B.Fab") hide
        (effects (font (size 0.7 0.7) (thickness 0.15)) (justify left bottom mirror))
    )
    (fp_rect (start -0.94 0.47) (end 0.94 -0.47)
      (stroke (width 0.05) (type solid)) (fill none) (layer "B.CrtYd"))
    (fp_rect (start -0.499 0.249) (end 0.499 -0.249)
      (stroke (width 0.15) (type solid)) (fill none) (layer "B.Fab"))
    (pad "1" smd roundrect (at -0.484 0 90) (size 0.59 0.64) (layers "B.Cu" "B.Paste" "B.Mask") (roundrect_rratio 0.25)
      (net 77 "VDDQ") (pintype "passive"))
    (pad "2" smd roundrect (at 0.484 0 90) (size 0.59 0.64) (layers "B.Cu" "B.Paste" "B.Mask") (roundrect_rratio 0.25)
      (net 9 "GND") (pintype "passive"))
  )

  (footprint "data-center-rdimm-ddr4-tester-footprints:C_0402_1005Metric" (layer "B.Cu")
    (at 167.586328 55.060008 90)
    (descr "Capacitor SMD 0402")
    (tags "capacitor SMD 0402")
    (property "Author" "Antmicro")
    (property "Dielectric" "X5R")
    (property "License" "Apache-2.0")
    (property "MPN" "GRM155R61H104KE14D")
    (property "Manufacturer" "Murata")
    (property "Sheetfile" "DDR4.kicad_sch")
    (property "Sheetname" "DDR4")
    (property "Val" "100n")
    (property "Voltage" "50V")
    (property "ki_description" " ")
    (attr smd)
    (fp_text reference "C168" (at 4.350008 0.363672 270) (layer "B.SilkS")
        (effects (font (size 0.7 0.7) (thickness 0.15)) (justify left bottom mirror))
    )
    (fp_text value "C_100n_0402" (at 0 -1.4 270) (layer "B.Fab") hide
        (effects (font (size 0.7 0.7) (thickness 0.15)) (justify left bottom mirror))
    )
    (fp_text user "Author: Antmicro" (at -0.932 -4.17 270) (layer "B.Fab") hide
        (effects (font (size 0.7 0.7) (thickness 0.15)) (justify left bottom mirror))
    )
    (fp_text user "License: Apache-2.0" (at -0.932 -5.17 270) (layer "B.Fab") hide
        (effects (font (size 0.7 0.7) (thickness 0.15)) (justify left bottom mirror))
    )
    (fp_text user "${REFERENCE}" (at -0.932 -3.168 270) (layer "B.Fab") hide
        (effects (font (size 0.7 0.7) (thickness 0.15)) (justify left bottom mirror))
    )
    (fp_rect (start -0.94 0.47) (end 0.94 -0.47)
      (stroke (width 0.05) (type solid)) (fill none) (layer "B.CrtYd"))
    (fp_rect (start -0.499 0.249) (end 0.499 -0.249)
      (stroke (width 0.15) (type solid)) (fill none) (layer "B.Fab"))
    (pad "1" smd roundrect (at -0.484 0 90) (size 0.59 0.64) (layers "B.Cu" "B.Paste" "B.Mask") (roundrect_rratio 0.25)
      (net 77 "VDDQ") (pintype "passive"))
    (pad "2" smd roundrect (at 0.484 0 90) (size 0.59 0.64) (layers "B.Cu" "B.Paste" "B.Mask") (roundrect_rratio 0.25)
      (net 9 "GND") (pintype "passive"))
  )

  (footprint "data-center-rdimm-ddr4-tester-footprints:C_0402_1005Metric" (layer "B.Cu")
    (at 165.886328 55.060008 90)
    (descr "Capacitor SMD 0402")
    (tags "capacitor SMD 0402")
    (property "Author" "Antmicro")
    (property "Dielectric" "X5R")
    (property "License" "Apache-2.0")
    (property "MPN" "GRM155R61H104KE14D")
    (property "Manufacturer" "Murata")
    (property "Sheetfile" "DDR4.kicad_sch")
    (property "Sheetname" "DDR4")
    (property "Val" "100n")
    (property "Voltage" "50V")
    (property "ki_description" " ")
    (attr smd)
    (fp_text reference "C169" (at 4.350008 0.363672 270) (layer "B.SilkS")
        (effects (font (size 0.7 0.7) (thickness 0.15)) (justify left bottom mirror))
    )
    (fp_text value "C_100n_0402" (at 0 -1.4 270) (layer "B.Fab") hide
        (effects (font (size 0.7 0.7) (thickness 0.15)) (justify left bottom mirror))
    )
    (fp_text user "Author: Antmicro" (at -0.932 -4.17 270) (layer "B.Fab") hide
        (effects (font (size 0.7 0.7) (thickness 0.15)) (justify left bottom mirror))
    )
    (fp_text user "${REFERENCE}" (at -0.932 -3.168 270) (layer "B.Fab") hide
        (effects (font (size 0.7 0.7) (thickness 0.15)) (justify left bottom mirror))
    )
    (fp_text user "License: Apache-2.0" (at -0.932 -5.17 270) (layer "B.Fab") hide
        (effects (font (size 0.7 0.7) (thickness 0.15)) (justify left bottom mirror))
    )
    (fp_rect (start -0.94 0.47) (end 0.94 -0.47)
      (stroke (width 0.05) (type solid)) (fill none) (layer "B.CrtYd"))
    (fp_rect (start -0.499 0.249) (end 0.499 -0.249)
      (stroke (width 0.15) (type solid)) (fill none) (layer "B.Fab"))
    (pad "1" smd roundrect (at -0.484 0 90) (size 0.59 0.64) (layers "B.Cu" "B.Paste" "B.Mask") (roundrect_rratio 0.25)
      (net 77 "VDDQ") (pintype "passive"))
    (pad "2" smd roundrect (at 0.484 0 90) (size 0.59 0.64) (layers "B.Cu" "B.Paste" "B.Mask") (roundrect_rratio 0.25)
      (net 9 "GND") (pintype "passive"))
  )

  (footprint "data-center-rdimm-ddr4-tester-footprints:C_0402_1005Metric" (layer "B.Cu")
    (at 164.186328 55.060008 90)
    (descr "Capacitor SMD 0402")
    (tags "capacitor SMD 0402")
    (property "Author" "Antmicro")
    (property "Dielectric" "X5R")
    (property "License" "Apache-2.0")
    (property "MPN" "GRM155R61H104KE14D")
    (property "Manufacturer" "Murata")
    (property "Sheetfile" "DDR4.kicad_sch")
    (property "Sheetname" "DDR4")
    (property "Val" "100n")
    (property "Voltage" "50V")
    (property "ki_description" " ")
    (attr smd)
    (fp_text reference "C170" (at 4.350008 0.363672 270) (layer "B.SilkS")
        (effects (font (size 0.7 0.7) (thickness 0.15)) (justify left bottom mirror))
    )
    (fp_text value "C_100n_0402" (at 0 -1.4 270) (layer "B.Fab") hide
        (effects (font (size 0.7 0.7) (thickness 0.15)) (justify left bottom mirror))
    )
    (fp_text user "Author: Antmicro" (at -0.932 -4.17 270) (layer "B.Fab") hide
        (effects (font (size 0.7 0.7) (thickness 0.15)) (justify left bottom mirror))
    )
    (fp_text user "${REFERENCE}" (at -0.932 -3.168 270) (layer "B.Fab") hide
        (effects (font (size 0.7 0.7) (thickness 0.15)) (justify left bottom mirror))
    )
    (fp_text user "License: Apache-2.0" (at -0.932 -5.17 270) (layer "B.Fab") hide
        (effects (font (size 0.7 0.7) (thickness 0.15)) (justify left bottom mirror))
    )
    (fp_rect (start -0.94 0.47) (end 0.94 -0.47)
      (stroke (width 0.05) (type solid)) (fill none) (layer "B.CrtYd"))
    (fp_rect (start -0.499 0.249) (end 0.499 -0.249)
      (stroke (width 0.15) (type solid)) (fill none) (layer "B.Fab"))
    (pad "1" smd roundrect (at -0.484 0 90) (size 0.59 0.64) (layers "B.Cu" "B.Paste" "B.Mask") (roundrect_rratio 0.25)
      (net 77 "VDDQ") (pintype "passive"))
    (pad "2" smd roundrect (at 0.484 0 90) (size 0.59 0.64) (layers "B.Cu" "B.Paste" "B.Mask") (roundrect_rratio 0.25)
      (net 9 "GND") (pintype "passive"))
  )

  (footprint "data-center-rdimm-ddr4-tester-footprints:C_0402_1005Metric" (layer "B.Cu")
    (at 164.186328 59.660008 -90)
    (descr "Capacitor SMD 0402")
    (tags "capacitor SMD 0402")
    (property "Author" "Antmicro")
    (property "Dielectric" "X5R")
    (property "License" "Apache-2.0")
    (property "MPN" "GRM155R61H104KE14D")
    (property "Manufacturer" "Murata")
    (property "Sheetfile" "DDR4.kicad_sch")
    (property "Sheetname" "DDR4")
    (property "Val" "100n")
    (property "Voltage" "50V")
    (property "ki_description" " ")
    (attr smd)
    (fp_text reference "C171" (at -1.420008 0.536328 90) (layer "B.SilkS")
        (effects (font (size 0.7 0.7) (thickness 0.15)) (justify left bottom mirror))
    )
    (fp_text value "C_100n_0402" (at 0 -1.4 90) (layer "B.Fab") hide
        (effects (font (size 0.7 0.7) (thickness 0.15)) (justify left bottom mirror))
    )
    (fp_text user "${REFERENCE}" (at -0.932 -3.168 90) (layer "B.Fab") hide
        (effects (font (size 0.7 0.7) (thickness 0.15)) (justify left bottom mirror))
    )
    (fp_text user "Author: Antmicro" (at -0.932 -4.17 90) (layer "B.Fab") hide
        (effects (font (size 0.7 0.7) (thickness 0.15)) (justify left bottom mirror))
    )
    (fp_text user "License: Apache-2.0" (at -0.932 -5.17 90) (layer "B.Fab") hide
        (effects (font (size 0.7 0.7) (thickness 0.15)) (justify left bottom mirror))
    )
    (fp_rect (start -0.94 0.47) (end 0.94 -0.47)
      (stroke (width 0.05) (type solid)) (fill none) (layer "B.CrtYd"))
    (fp_rect (start -0.499 0.249) (end 0.499 -0.249)
      (stroke (width 0.15) (type solid)) (fill none) (layer "B.Fab"))
    (pad "1" smd roundrect (at -0.484 0 270) (size 0.59 0.64) (layers "B.Cu" "B.Paste" "B.Mask") (roundrect_rratio 0.25)
      (net 77 "VDDQ") (pintype "passive"))
    (pad "2" smd roundrect (at 0.484 0 270) (size 0.59 0.64) (layers "B.Cu" "B.Paste" "B.Mask") (roundrect_rratio 0.25)
      (net 9 "GND") (pintype "passive"))
  )

  (footprint "data-center-rdimm-ddr4-tester-footprints:C_0402_1005Metric" (layer "B.Cu")
    (at 165.036328 57.610008 180)
    (descr "Capacitor SMD 0402")
    (tags "capacitor SMD 0402")
    (property "Author" "Antmicro")
    (property "Dielectric" "X5R")
    (property "License" "Apache-2.0")
    (property "MPN" "GRM155R61H104KE14D")
    (property "Manufacturer" "Murata")
    (property "Sheetfile" "DDR4.kicad_sch")
    (property "Sheetname" "DDR4")
    (property "Val" "100n")
    (property "Voltage" "50V")
    (property "ki_description" " ")
    (attr smd)
    (fp_text reference "C173" (at 1.056328 -0.349992) (layer "B.SilkS")
        (effects (font (size 0.7 0.7) (thickness 0.15)) (justify left bottom mirror))
    )
    (fp_text value "C_100n_0402" (at 0 -1.4) (layer "B.Fab") hide
        (effects (font (size 0.7 0.7) (thickness 0.15)) (justify left bottom mirror))
    )
    (fp_text user "${REFERENCE}" (at -0.932 -3.168) (layer "B.Fab") hide
        (effects (font (size 0.7 0.7) (thickness 0.15)) (justify left bottom mirror))
    )
    (fp_text user "License: Apache-2.0" (at -0.932 -5.17) (layer "B.Fab") hide
        (effects (font (size 0.7 0.7) (thickness 0.15)) (justify left bottom mirror))
    )
    (fp_text user "Author: Antmicro" (at -0.932 -4.17) (layer "B.Fab") hide
        (effects (font (size 0.7 0.7) (thickness 0.15)) (justify left bottom mirror))
    )
    (fp_rect (start -0.94 0.47) (end 0.94 -0.47)
      (stroke (width 0.05) (type solid)) (fill none) (layer "B.CrtYd"))
    (fp_rect (start -0.499 0.249) (end 0.499 -0.249)
      (stroke (width 0.15) (type solid)) (fill none) (layer "B.Fab"))
    (pad "1" smd roundrect (at -0.484 0 180) (size 0.59 0.64) (layers "B.Cu" "B.Paste" "B.Mask") (roundrect_rratio 0.25)
      (net 77 "VDDQ") (pintype "passive"))
    (pad "2" smd roundrect (at 0.484 0 180) (size 0.59 0.64) (layers "B.Cu" "B.Paste" "B.Mask") (roundrect_rratio 0.25)
      (net 9 "GND") (pintype "passive"))
  )

  (footprint "data-center-rdimm-ddr4-tester-footprints:C_0402_1005Metric" (layer "B.Cu")
    (at 170.136328 59.660008 -90)
    (descr "Capacitor SMD 0402")
    (tags "capacitor SMD 0402")
    (property "Author" "Antmicro")
    (property "Dielectric" "X5R")
    (property "License" "Apache-2.0")
    (property "MPN" "GRM155R61H104KE14D")
    (property "Manufacturer" "Murata")
    (property "Sheetfile" "DDR4.kicad_sch")
    (property "Sheetname" "DDR4")
    (property "Val" "100n")
    (property "Voltage" "50V")
    (property "ki_description" " ")
    (attr smd)
    (fp_text reference "C177" (at 0.809992 -0.363672 90) (layer "B.SilkS")
        (effects (font (size 0.7 0.7) (thickness 0.15)) (justify left bottom mirror))
    )
    (fp_text value "C_100n_0402" (at 0 -1.4 90) (layer "B.Fab") hide
        (effects (font (size 0.7 0.7) (thickness 0.15)) (justify left bottom mirror))
    )
    (fp_text user "License: Apache-2.0" (at -0.932 -5.17 90) (layer "B.Fab") hide
        (effects (font (size 0.7 0.7) (thickness 0.15)) (justify left bottom mirror))
    )
    (fp_text user "${REFERENCE}" (at -0.932 -3.168 90) (layer "B.Fab") hide
        (effects (font (size 0.7 0.7) (thickness 0.15)) (justify left bottom mirror))
    )
    (fp_text user "Author: Antmicro" (at -0.932 -4.17 90) (layer "B.Fab") hide
        (effects (font (size 0.7 0.7) (thickness 0.15)) (justify left bottom mirror))
    )
    (fp_rect (start -0.94 0.47) (end 0.94 -0.47)
      (stroke (width 0.05) (type solid)) (fill none) (layer "B.CrtYd"))
    (fp_rect (start -0.499 0.249) (end 0.499 -0.249)
      (stroke (width 0.15) (type solid)) (fill none) (layer "B.Fab"))
    (pad "1" smd roundrect (at -0.484 0 270) (size 0.59 0.64) (layers "B.Cu" "B.Paste" "B.Mask") (roundrect_rratio 0.25)
      (net 77 "VDDQ") (pintype "passive"))
    (pad "2" smd roundrect (at 0.484 0 270) (size 0.59 0.64) (layers "B.Cu" "B.Paste" "B.Mask") (roundrect_rratio 0.25)
      (net 9 "GND") (pintype "passive"))
  )

  (footprint "data-center-rdimm-ddr4-tester-footprints:C_0402_1005Metric" (layer "B.Cu")
    (at 171.836328 59.660008 -90)
    (descr "Capacitor SMD 0402")
    (tags "capacitor SMD 0402")
    (property "Author" "Antmicro")
    (property "Dielectric" "X5R")
    (property "License" "Apache-2.0")
    (property "MPN" "GRM155R61H104KE14D")
    (property "Manufacturer" "Murata")
    (property "Sheetfile" "DDR4.kicad_sch")
    (property "Sheetname" "DDR4")
    (property "Val" "100n")
    (property "Voltage" "50V")
    (property "ki_description" " ")
    (attr smd)
    (fp_text reference "C179" (at 0.809992 -0.363672 90) (layer "B.SilkS")
        (effects (font (size 0.7 0.7) (thickness 0.15)) (justify left bottom mirror))
    )
    (fp_text value "C_100n_0402" (at 0 -1.4 90) (layer "B.Fab") hide
        (effects (font (size 0.7 0.7) (thickness 0.15)) (justify left bottom mirror))
    )
    (fp_text user "License: Apache-2.0" (at -0.932 -5.17 90) (layer "B.Fab") hide
        (effects (font (size 0.7 0.7) (thickness 0.15)) (justify left bottom mirror))
    )
    (fp_text user "Author: Antmicro" (at -0.932 -4.17 90) (layer "B.Fab") hide
        (effects (font (size 0.7 0.7) (thickness 0.15)) (justify left bottom mirror))
    )
    (fp_text user "${REFERENCE}" (at -0.932 -3.168 90) (layer "B.Fab") hide
        (effects (font (size 0.7 0.7) (thickness 0.15)) (justify left bottom mirror))
    )
    (fp_rect (start -0.94 0.47) (end 0.94 -0.47)
      (stroke (width 0.05) (type solid)) (fill none) (layer "B.CrtYd"))
    (fp_rect (start -0.499 0.249) (end 0.499 -0.249)
      (stroke (width 0.15) (type solid)) (fill none) (layer "B.Fab"))
    (pad "1" smd roundrect (at -0.484 0 270) (size 0.59 0.64) (layers "B.Cu" "B.Paste" "B.Mask") (roundrect_rratio 0.25)
      (net 77 "VDDQ") (pintype "passive"))
    (pad "2" smd roundrect (at 0.484 0 270) (size 0.59 0.64) (layers "B.Cu" "B.Paste" "B.Mask") (roundrect_rratio 0.25)
      (net 9 "GND") (pintype "passive"))
  )

  (footprint "data-center-rdimm-ddr4-tester-footprints:C_0402_1005Metric" (layer "B.Cu")
    (at 173.536328 57.710008 180)
    (descr "Capacitor SMD 0402")
    (tags "capacitor SMD 0402")
    (property "Author" "Antmicro")
    (property "Dielectric" "X5R")
    (property "License" "Apache-2.0")
    (property "MPN" "GRM155R61H104KE14D")
    (property "Manufacturer" "Murata")
    (property "Sheetfile" "DDR4.kicad_sch")
    (property "Sheetname" "DDR4")
    (property "Val" "100n")
    (property "Voltage" "50V")
    (property "ki_description" " ")
    (attr smd)
    (fp_text reference "C181" (at 0.846328 -0.329992) (layer "B.SilkS")
        (effects (font (size 0.7 0.7) (thickness 0.15)) (justify left bottom mirror))
    )
    (fp_text value "C_100n_0402" (at 0 -1.4) (layer "B.Fab") hide
        (effects (font (size 0.7 0.7) (thickness 0.15)) (justify left bottom mirror))
    )
    (fp_text user "Author: Antmicro" (at -0.932 -4.17) (layer "B.Fab") hide
        (effects (font (size 0.7 0.7) (thickness 0.15)) (justify left bottom mirror))
    )
    (fp_text user "${REFERENCE}" (at -0.932 -3.168) (layer "B.Fab") hide
        (effects (font (size 0.7 0.7) (thickness 0.15)) (justify left bottom mirror))
    )
    (fp_text user "License: Apache-2.0" (at -0.932 -5.17) (layer "B.Fab") hide
        (effects (font (size 0.7 0.7) (thickness 0.15)) (justify left bottom mirror))
    )
    (fp_rect (start -0.94 0.47) (end 0.94 -0.47)
      (stroke (width 0.05) (type solid)) (fill none) (layer "B.CrtYd"))
    (fp_rect (start -0.499 0.249) (end 0.499 -0.249)
      (stroke (width 0.15) (type solid)) (fill none) (layer "B.Fab"))
    (pad "1" smd roundrect (at -0.484 0 180) (size 0.59 0.64) (layers "B.Cu" "B.Paste" "B.Mask") (roundrect_rratio 0.25)
      (net 77 "VDDQ") (pintype "passive"))
    (pad "2" smd roundrect (at 0.484 0 180) (size 0.59 0.64) (layers "B.Cu" "B.Paste" "B.Mask") (roundrect_rratio 0.25)
      (net 9 "GND") (pintype "passive"))
  )

  (footprint "data-center-rdimm-ddr4-tester-footprints:C_0402_1005Metric" (layer "B.Cu")
    (at 121.636328 54.660008 90)
    (descr "Capacitor SMD 0402")
    (tags "capacitor SMD 0402")
    (property "Author" "Antmicro")
    (property "Dielectric" "X5R")
    (property "License" "Apache-2.0")
    (property "MPN" "GRM155R61H104KE14D")
    (property "Manufacturer" "Murata")
    (property "Sheetfile" "DDR4.kicad_sch")
    (property "Sheetname" "DDR4")
    (property "Val" "100n")
    (property "Voltage" "50V")
    (property "ki_description" " ")
    (attr smd)
    (fp_text reference "C199" (at 3.940008 0.393672 270) (layer "B.SilkS")
        (effects (font (size 0.7 0.7) (thickness 0.15)) (justify left bottom mirror))
    )
    (fp_text value "C_100n_0402" (at 0 -1.4 270) (layer "B.Fab") hide
        (effects (font (size 0.7 0.7) (thickness 0.15)) (justify left bottom mirror))
    )
    (fp_text user "${REFERENCE}" (at -0.932 -3.168 270) (layer "B.Fab") hide
        (effects (font (size 0.7 0.7) (thickness 0.15)) (justify left bottom mirror))
    )
    (fp_text user "Author: Antmicro" (at -0.932 -4.17 270) (layer "B.Fab") hide
        (effects (font (size 0.7 0.7) (thickness 0.15)) (justify left bottom mirror))
    )
    (fp_text user "License: Apache-2.0" (at -0.932 -5.17 270) (layer "B.Fab") hide
        (effects (font (size 0.7 0.7) (thickness 0.15)) (justify left bottom mirror))
    )
    (fp_rect (start -0.94 0.47) (end 0.94 -0.47)
      (stroke (width 0.05) (type solid)) (fill none) (layer "B.CrtYd"))
    (fp_rect (start -0.499 0.249) (end 0.499 -0.249)
      (stroke (width 0.15) (type solid)) (fill none) (layer "B.Fab"))
    (pad "1" smd roundrect (at -0.484 0 90) (size 0.59 0.64) (layers "B.Cu" "B.Paste" "B.Mask") (roundrect_rratio 0.25)
      (net 184 "VPP") (pintype "passive"))
    (pad "2" smd roundrect (at 0.484 0 90) (size 0.59 0.64) (layers "B.Cu" "B.Paste" "B.Mask") (roundrect_rratio 0.25)
      (net 9 "GND") (pintype "passive"))
  )

  (footprint "data-center-rdimm-ddr4-tester-footprints:C_0402_1005Metric" (layer "B.Cu")
    (at 120.626328 54.660008 90)
    (descr "Capacitor SMD 0402")
    (tags "capacitor SMD 0402")
    (property "Author" "Antmicro")
    (property "Dielectric" "X5R")
    (property "License" "Apache-2.0")
    (property "MPN" "GRM155R61H104KE14D")
    (property "Manufacturer" "Murata")
    (property "Sheetfile" "DDR4.kicad_sch")
    (property "Sheetname" "DDR4")
    (property "Val" "100n")
    (property "Voltage" "50V")
    (property "ki_description" " ")
    (attr smd)
    (fp_text reference "C200" (at 3.940008 0.393672 270) (layer "B.SilkS")
        (effects (font (size 0.7 0.7) (thickness 0.15)) (justify left bottom mirror))
    )
    (fp_text value "C_100n_0402" (at 0 -1.4 270) (layer "B.Fab") hide
        (effects (font (size 0.7 0.7) (thickness 0.15)) (justify left bottom mirror))
    )
    (fp_text user "${REFERENCE}" (at -0.932 -3.168 270) (layer "B.Fab") hide
        (effects (font (size 0.7 0.7) (thickness 0.15)) (justify left bottom mirror))
    )
    (fp_text user "Author: Antmicro" (at -0.932 -4.17 270) (layer "B.Fab") hide
        (effects (font (size 0.7 0.7) (thickness 0.15)) (justify left bottom mirror))
    )
    (fp_text user "License: Apache-2.0" (at -0.932 -5.17 270) (layer "B.Fab") hide
        (effects (font (size 0.7 0.7) (thickness 0.15)) (justify left bottom mirror))
    )
    (fp_rect (start -0.94 0.47) (end 0.94 -0.47)
      (stroke (width 0.05) (type solid)) (fill none) (layer "B.CrtYd"))
    (fp_rect (start -0.499 0.249) (end 0.499 -0.249)
      (stroke (width 0.15) (type solid)) (fill none) (layer "B.Fab"))
    (pad "1" smd roundrect (at -0.484 0 90) (size 0.59 0.64) (layers "B.Cu" "B.Paste" "B.Mask") (roundrect_rratio 0.25)
      (net 184 "VPP") (pintype "passive"))
    (pad "2" smd roundrect (at 0.484 0 90) (size 0.59 0.64) (layers "B.Cu" "B.Paste" "B.Mask") (roundrect_rratio 0.25)
      (net 9 "GND") (pintype "passive"))
  )

  (footprint "data-center-rdimm-ddr4-tester-footprints:C_0402_1005Metric" (layer "B.Cu")
    (at 119.756328 59.750008 -90)
    (descr "Capacitor SMD 0402")
    (tags "capacitor SMD 0402")
    (property "Author" "Antmicro")
    (property "Dielectric" "X5R")
    (property "License" "Apache-2.0")
    (property "MPN" "GRM155R61H104KE14D")
    (property "Manufacturer" "Murata")
    (property "Sheetfile" "DDR4.kicad_sch")
    (property "Sheetname" "DDR4")
    (property "Val" "100n")
    (property "Voltage" "50V")
    (property "ki_description" " ")
    (attr smd)
    (fp_text reference "C201" (at 0.799992 -0.353672 90) (layer "B.SilkS")
        (effects (font (size 0.7 0.7) (thickness 0.15)) (justify left bottom mirror))
    )
    (fp_text value "C_100n_0402" (at 0 -1.4 90) (layer "B.Fab") hide
        (effects (font (size 0.7 0.7) (thickness 0.15)) (justify left bottom mirror))
    )
    (fp_text user "${REFERENCE}" (at -0.932 -3.168 90) (layer "B.Fab") hide
        (effects (font (size 0.7 0.7) (thickness 0.15)) (justify left bottom mirror))
    )
    (fp_text user "Author: Antmicro" (at -0.932 -4.17 90) (layer "B.Fab") hide
        (effects (font (size 0.7 0.7) (thickness 0.15)) (justify left bottom mirror))
    )
    (fp_text user "License: Apache-2.0" (at -0.932 -5.17 90) (layer "B.Fab") hide
        (effects (font (size 0.7 0.7) (thickness 0.15)) (justify left bottom mirror))
    )
    (fp_rect (start -0.94 0.47) (end 0.94 -0.47)
      (stroke (width 0.05) (type solid)) (fill none) (layer "B.CrtYd"))
    (fp_rect (start -0.499 0.249) (end 0.499 -0.249)
      (stroke (width 0.15) (type solid)) (fill none) (layer "B.Fab"))
    (pad "1" smd roundrect (at -0.484 0 270) (size 0.59 0.64) (layers "B.Cu" "B.Paste" "B.Mask") (roundrect_rratio 0.25)
      (net 184 "VPP") (pintype "passive"))
    (pad "2" smd roundrect (at 0.484 0 270) (size 0.59 0.64) (layers "B.Cu" "B.Paste" "B.Mask") (roundrect_rratio 0.25)
      (net 9 "GND") (pintype "passive"))
  )

  (footprint "data-center-rdimm-ddr4-tester-footprints:C_0402_1005Metric" (layer "B.Cu")
    (at 120.736328 59.760008 -90)
    (descr "Capacitor SMD 0402")
    (tags "capacitor SMD 0402")
    (property "Author" "Antmicro")
    (property "Dielectric" "X5R")
    (property "License" "Apache-2.0")
    (property "MPN" "GRM155R61H104KE14D")
    (property "Manufacturer" "Murata")
    (property "Sheetfile" "DDR4.kicad_sch")
    (property "Sheetname" "DDR4")
    (property "Val" "100n")
    (property "Voltage" "50V")
    (property "ki_description" " ")
    (attr smd)
    (fp_text reference "C202" (at 0.799992 -0.353672 90) (layer "B.SilkS")
        (effects (font (size 0.7 0.7) (thickness 0.15)) (justify left bottom mirror))
    )
    (fp_text value "C_100n_0402" (at 0 -1.4 90) (layer "B.Fab") hide
        (effects (font (size 0.7 0.7) (thickness 0.15)) (justify left bottom mirror))
    )
    (fp_text user "Author: Antmicro" (at -0.932 -4.17 90) (layer "B.Fab") hide
        (effects (font (size 0.7 0.7) (thickness 0.15)) (justify left bottom mirror))
    )
    (fp_text user "License: Apache-2.0" (at -0.932 -5.17 90) (layer "B.Fab") hide
        (effects (font (size 0.7 0.7) (thickness 0.15)) (justify left bottom mirror))
    )
    (fp_text user "${REFERENCE}" (at -0.932 -3.168 90) (layer "B.Fab") hide
        (effects (font (size 0.7 0.7) (thickness 0.15)) (justify left bottom mirror))
    )
    (fp_rect (start -0.94 0.47) (end 0.94 -0.47)
      (stroke (width 0.05) (type solid)) (fill none) (layer "B.CrtYd"))
    (fp_rect (start -0.499 0.249) (end 0.499 -0.249)
      (stroke (width 0.15) (type solid)) (fill none) (layer "B.Fab"))
    (pad "1" smd roundrect (at -0.484 0 270) (size 0.59 0.64) (layers "B.Cu" "B.Paste" "B.Mask") (roundrect_rratio 0.25)
      (net 184 "VPP") (pintype "passive"))
    (pad "2" smd roundrect (at 0.484 0 270) (size 0.59 0.64) (layers "B.Cu" "B.Paste" "B.Mask") (roundrect_rratio 0.25)
      (net 9 "GND") (pintype "passive"))
  )

  (footprint "data-center-rdimm-ddr4-tester-footprints:C_0402_1005Metric" (layer "B.Cu")
    (at 121.736328 59.760008 -90)
    (descr "Capacitor SMD 0402")
    (tags "capacitor SMD 0402")
    (property "Author" "Antmicro")
    (property "Dielectric" "X5R")
    (property "License" "Apache-2.0")
    (property "MPN" "GRM155R61H104KE14D")
    (property "Manufacturer" "Murata")
    (property "Sheetfile" "DDR4.kicad_sch")
    (property "Sheetname" "DDR4")
    (property "Val" "100n")
    (property "Voltage" "50V")
    (property "ki_description" " ")
    (attr smd)
    (fp_text reference "C203" (at 0.799992 -0.353672 90) (layer "B.SilkS")
        (effects (font (size 0.7 0.7) (thickness 0.15)) (justify left bottom mirror))
    )
    (fp_text value "C_100n_0402" (at 0 -1.4 90) (layer "B.Fab") hide
        (effects (font (size 0.7 0.7) (thickness 0.15)) (justify left bottom mirror))
    )
    (fp_text user "${REFERENCE}" (at -0.932 -3.168 90) (layer "B.Fab") hide
        (effects (font (size 0.7 0.7) (thickness 0.15)) (justify left bottom mirror))
    )
    (fp_text user "License: Apache-2.0" (at -0.932 -5.17 90) (layer "B.Fab") hide
        (effects (font (size 0.7 0.7) (thickness 0.15)) (justify left bottom mirror))
    )
    (fp_text user "Author: Antmicro" (at -0.932 -4.17 90) (layer "B.Fab") hide
        (effects (font (size 0.7 0.7) (thickness 0.15)) (justify left bottom mirror))
    )
    (fp_rect (start -0.94 0.47) (end 0.94 -0.47)
      (stroke (width 0.05) (type solid)) (fill none) (layer "B.CrtYd"))
    (fp_rect (start -0.499 0.249) (end 0.499 -0.249)
      (stroke (width 0.15) (type solid)) (fill none) (layer "B.Fab"))
    (pad "1" smd roundrect (at -0.484 0 270) (size 0.59 0.64) (layers "B.Cu" "B.Paste" "B.Mask") (roundrect_rratio 0.25)
      (net 184 "VPP") (pintype "passive"))
    (pad "2" smd roundrect (at 0.484 0 270) (size 0.59 0.64) (layers "B.Cu" "B.Paste" "B.Mask") (roundrect_rratio 0.25)
      (net 9 "GND") (pintype "passive"))
  )

  (footprint "data-center-rdimm-ddr4-tester-footprints:C_0402_1005Metric" (layer "B.Cu")
    (at 181.796328 54.090008 90)
    (descr "Capacitor SMD 0402")
    (tags "capacitor SMD 0402")
    (property "Author" "Antmicro")
    (property "Dielectric" "X5R")
    (property "License" "Apache-2.0")
    (property "MPN" "GRM155R61H104KE14D")
    (property "Manufacturer" "Murata")
    (property "Sheetfile" "DDR4.kicad_sch")
    (property "Sheetname" "DDR4")
    (property "Val" "100n")
    (property "Voltage" "50V")
    (property "ki_description" " ")
    (attr smd)
    (fp_text reference "C204" (at 4.060008 0.483672 270) (layer "B.SilkS")
        (effects (font (size 0.7 0.7) (thickness 0.15)) (justify left bottom mirror))
    )
    (fp_text value "C_100n_0402" (at 0 -1.4 270) (layer "B.Fab") hide
        (effects (font (size 0.7 0.7) (thickness 0.15)) (justify left bottom mirror))
    )
    (fp_text user "License: Apache-2.0" (at -0.932 -5.17 270) (layer "B.Fab") hide
        (effects (font (size 0.7 0.7) (thickness 0.15)) (justify left bottom mirror))
    )
    (fp_text user "Author: Antmicro" (at -0.932 -4.17 270) (layer "B.Fab") hide
        (effects (font (size 0.7 0.7) (thickness 0.15)) (justify left bottom mirror))
    )
    (fp_text user "${REFERENCE}" (at -0.932 -3.168 270) (layer "B.Fab") hide
        (effects (font (size 0.7 0.7) (thickness 0.15)) (justify left bottom mirror))
    )
    (fp_rect (start -0.94 0.47) (end 0.94 -0.47)
      (stroke (width 0.05) (type solid)) (fill none) (layer "B.CrtYd"))
    (fp_rect (start -0.499 0.249) (end 0.499 -0.249)
      (stroke (width 0.15) (type solid)) (fill none) (layer "B.Fab"))
    (pad "1" smd roundrect (at -0.484 0 90) (size 0.59 0.64) (layers "B.Cu" "B.Paste" "B.Mask") (roundrect_rratio 0.25)
      (net 186 "VTT") (pintype "passive"))
    (pad "2" smd roundrect (at 0.484 0 90) (size 0.59 0.64) (layers "B.Cu" "B.Paste" "B.Mask") (roundrect_rratio 0.25)
      (net 9 "GND") (pintype "passive"))
  )

  (footprint "data-center-rdimm-ddr4-tester-footprints:C_0402_1005Metric" (layer "B.Cu")
    (at 181.636328 60.670008 -90)
    (descr "Capacitor SMD 0402")
    (tags "capacitor SMD 0402")
    (property "Author" "Antmicro")
    (property "Dielectric" "X5R")
    (property "License" "Apache-2.0")
    (property "MPN" "GRM155R61H104KE14D")
    (property "Manufacturer" "Murata")
    (property "Sheetfile" "DDR4.kicad_sch")
    (property "Sheetname" "DDR4")
    (property "Val" "100n")
    (property "Voltage" "50V")
    (property "ki_description" " ")
    (attr smd)
    (fp_text reference "C205" (at 0.739992 -0.363672 90) (layer "B.SilkS")
        (effects (font (size 0.7 0.7) (thickness 0.15)) (justify left bottom mirror))
    )
    (fp_text value "C_100n_0402" (at 0 -1.4 90) (layer "B.Fab") hide
        (effects (font (size 0.7 0.7) (thickness 0.15)) (justify left bottom mirror))
    )
    (fp_text user "License: Apache-2.0" (at -0.932 -5.17 90) (layer "B.Fab") hide
        (effects (font (size 0.7 0.7) (thickness 0.15)) (justify left bottom mirror))
    )
    (fp_text user "Author: Antmicro" (at -0.932 -4.17 90) (layer "B.Fab") hide
        (effects (font (size 0.7 0.7) (thickness 0.15)) (justify left bottom mirror))
    )
    (fp_text user "${REFERENCE}" (at -0.932 -3.168 90) (layer "B.Fab") hide
        (effects (font (size 0.7 0.7) (thickness 0.15)) (justify left bottom mirror))
    )
    (fp_rect (start -0.94 0.47) (end 0.94 -0.47)
      (stroke (width 0.05) (type solid)) (fill none) (layer "B.CrtYd"))
    (fp_rect (start -0.499 0.249) (end 0.499 -0.249)
      (stroke (width 0.15) (type solid)) (fill none) (layer "B.Fab"))
    (pad "1" smd roundrect (at -0.484 0 270) (size 0.59 0.64) (layers "B.Cu" "B.Paste" "B.Mask") (roundrect_rratio 0.25)
      (net 186 "VTT") (pintype "passive"))
    (pad "2" smd roundrect (at 0.484 0 270) (size 0.59 0.64) (layers "B.Cu" "B.Paste" "B.Mask") (roundrect_rratio 0.25)
      (net 9 "GND") (pintype "passive"))
  )

  (footprint "data-center-rdimm-ddr4-tester-footprints:C_0402_1005Metric" (layer "B.Cu")
    (at 168.436328 57.660008)
    (descr "Capacitor SMD 0402")
    (tags "capacitor SMD 0402")
    (property "Author" "Antmicro")
    (property "Dielectric" "X5R")
    (property "License" "Apache-2.0")
    (property "MPN" "GRM155R61H104KE14D")
    (property "Manufacturer" "Murata")
    (property "Sheetfile" "DDR4.kicad_sch")
    (property "Sheetname" "DDR4")
    (property "Val" "100n")
    (property "Voltage" "50V")
    (property "ki_description" " ")
    (attr smd)
    (fp_text reference "C176" (at 1.063672 1.189992 180) (layer "B.SilkS")
        (effects (font (size 0.7 0.7) (thickness 0.15)) (justify left bottom mirror))
    )
    (fp_text value "C_100n_0402" (at 0 -1.4 180) (layer "B.Fab") hide
        (effects (font (size 0.7 0.7) (thickness 0.15)) (justify left bottom mirror))
    )
    (fp_text user "${REFERENCE}" (at -0.932 -3.168 180) (layer "B.Fab") hide
        (effects (font (size 0.7 0.7) (thickness 0.15)) (justify left bottom mirror))
    )
    (fp_text user "License: Apache-2.0" (at -0.932 -5.17 180) (layer "B.Fab") hide
        (effects (font (size 0.7 0.7) (thickness 0.15)) (justify left bottom mirror))
    )
    (fp_text user "Author: Antmicro" (at -0.932 -4.17 180) (layer "B.Fab") hide
        (effects (font (size 0.7 0.7) (thickness 0.15)) (justify left bottom mirror))
    )
    (fp_rect (start -0.94 0.47) (end 0.94 -0.47)
      (stroke (width 0.05) (type solid)) (fill none) (layer "B.CrtYd"))
    (fp_rect (start -0.499 0.249) (end 0.499 -0.249)
      (stroke (width 0.15) (type solid)) (fill none) (layer "B.Fab"))
    (pad "1" smd roundrect (at -0.484 0) (size 0.59 0.64) (layers "B.Cu" "B.Paste" "B.Mask") (roundrect_rratio 0.25)
      (net 77 "VDDQ") (pintype "passive"))
    (pad "2" smd roundrect (at 0.484 0) (size 0.59 0.64) (layers "B.Cu" "B.Paste" "B.Mask") (roundrect_rratio 0.25)
      (net 9 "GND") (pintype "passive"))
  )

  (footprint "data-center-rdimm-ddr4-tester-footprints:C_0402_1005Metric" (layer "B.Cu")
    (at 174.386328 55.060008 90)
    (descr "Capacitor SMD 0402")
    (tags "capacitor SMD 0402")
    (property "Author" "Antmicro")
    (property "Dielectric" "X5R")
    (property "License" "Apache-2.0")
    (property "MPN" "GRM155R61H104KE14D")
    (property "Manufacturer" "Murata")
    (property "Sheetfile" "DDR4.kicad_sch")
    (property "Sheetname" "DDR4")
    (property "Val" "100n")
    (property "Voltage" "50V")
    (property "ki_description" " ")
    (attr smd)
    (fp_text reference "C165" (at 4.350008 0.363672 270) (layer "B.SilkS")
        (effects (font (size 0.7 0.7) (thickness 0.15)) (justify left bottom mirror))
    )
    (fp_text value "C_100n_0402" (at 0 -1.4 270) (layer "B.Fab") hide
        (effects (font (size 0.7 0.7) (thickness 0.15)) (justify left bottom mirror))
    )
    (fp_text user "License: Apache-2.0" (at -0.932 -5.17 270) (layer "B.Fab") hide
        (effects (font (size 0.7 0.7) (thickness 0.15)) (justify left bottom mirror))
    )
    (fp_text user "${REFERENCE}" (at -0.932 -3.168 270) (layer "B.Fab") hide
        (effects (font (size 0.7 0.7) (thickness 0.15)) (justify left bottom mirror))
    )
    (fp_text user "Author: Antmicro" (at -0.932 -4.17 270) (layer "B.Fab") hide
        (effects (font (size 0.7 0.7) (thickness 0.15)) (justify left bottom mirror))
    )
    (fp_rect (start -0.94 0.47) (end 0.94 -0.47)
      (stroke (width 0.05) (type solid)) (fill none) (layer "B.CrtYd"))
    (fp_rect (start -0.499 0.249) (end 0.499 -0.249)
      (stroke (width 0.15) (type solid)) (fill none) (layer "B.Fab"))
    (pad "1" smd roundrect (at -0.484 0 90) (size 0.59 0.64) (layers "B.Cu" "B.Paste" "B.Mask") (roundrect_rratio 0.25)
      (net 77 "VDDQ") (pintype "passive"))
    (pad "2" smd roundrect (at 0.484 0 90) (size 0.59 0.64) (layers "B.Cu" "B.Paste" "B.Mask") (roundrect_rratio 0.25)
      (net 9 "GND") (pintype "passive"))
  )

  (footprint "data-center-rdimm-ddr4-tester-footprints:C_0402_1005Metric" (layer "B.Cu")
    (at 182.886328 54.760008 90)
    (descr "Capacitor SMD 0402")
    (tags "capacitor SMD 0402")
    (property "Author" "Antmicro")
    (property "Dielectric" "X5R")
    (property "License" "Apache-2.0")
    (property "MPN" "GRM155R61H104KE14D")
    (property "Manufacturer" "Murata")
    (property "Sheetfile" "DDR4.kicad_sch")
    (property "Sheetname" "DDR4")
    (property "Val" "100n")
    (property "Voltage" "50V")
    (property "ki_description" " ")
    (attr smd)
    (fp_text reference "C164" (at 4.060008 0.483672 270) (layer "B.SilkS")
        (effects (font (size 0.7 0.7) (thickness 0.15)) (justify left bottom mirror))
    )
    (fp_text value "C_100n_0402" (at 0 -1.4 270) (layer "B.Fab") hide
        (effects (font (size 0.7 0.7) (thickness 0.15)) (justify left bottom mirror))
    )
    (fp_text user "Author: Antmicro" (at -0.932 -4.17 270) (layer "B.Fab") hide
        (effects (font (size 0.7 0.7) (thickness 0.15)) (justify left bottom mirror))
    )
    (fp_text user "License: Apache-2.0" (at -0.932 -5.17 270) (layer "B.Fab") hide
        (effects (font (size 0.7 0.7) (thickness 0.15)) (justify left bottom mirror))
    )
    (fp_text user "${REFERENCE}" (at -0.932 -3.168 270) (layer "B.Fab") hide
        (effects (font (size 0.7 0.7) (thickness 0.15)) (justify left bottom mirror))
    )
    (fp_rect (start -0.94 0.47) (end 0.94 -0.47)
      (stroke (width 0.05) (type solid)) (fill none) (layer "B.CrtYd"))
    (fp_rect (start -0.499 0.249) (end 0.499 -0.249)
      (stroke (width 0.15) (type solid)) (fill none) (layer "B.Fab"))
    (pad "1" smd roundrect (at -0.484 0 90) (size 0.59 0.64) (layers "B.Cu" "B.Paste" "B.Mask") (roundrect_rratio 0.25)
      (net 77 "VDDQ") (pintype "passive"))
    (pad "2" smd roundrect (at 0.484 0 90) (size 0.59 0.64) (layers "B.Cu" "B.Paste" "B.Mask") (roundrect_rratio 0.25)
      (net 9 "GND") (pintype "passive"))
  )

  (footprint "data-center-rdimm-ddr4-tester-footprints:C_0402_1005Metric" (layer "B.Cu")
    (at 195.646328 54.760008 90)
    (descr "Capacitor SMD 0402")
    (tags "capacitor SMD 0402")
    (property "Author" "Antmicro")
    (property "Dielectric" "X5R")
    (property "License" "Apache-2.0")
    (property "MPN" "GRM155R61H104KE14D")
    (property "Manufacturer" "Murata")
    (property "Sheetfile" "DDR4.kicad_sch")
    (property "Sheetname" "DDR4")
    (property "Val" "100n")
    (property "Voltage" "50V")
    (property "ki_description" " ")
    (attr smd)
    (fp_text reference "C154" (at 4.050008 0.423672 270) (layer "B.SilkS")
        (effects (font (size 0.7 0.7) (thickness 0.15)) (justify left bottom mirror))
    )
    (fp_text value "C_100n_0402" (at 0 -1.4 270) (layer "B.Fab") hide
        (effects (font (size 0.7 0.7) (thickness 0.15)) (justify left bottom mirror))
    )
    (fp_text user "${REFERENCE}" (at -0.932 -3.168 270) (layer "B.Fab") hide
        (effects (font (size 0.7 0.7) (thickness 0.15)) (justify left bottom mirror))
    )
    (fp_text user "License: Apache-2.0" (at -0.932 -5.17 270) (layer "B.Fab") hide
        (effects (font (size 0.7 0.7) (thickness 0.15)) (justify left bottom mirror))
    )
    (fp_text user "Author: Antmicro" (at -0.932 -4.17 270) (layer "B.Fab") hide
        (effects (font (size 0.7 0.7) (thickness 0.15)) (justify left bottom mirror))
    )
    (fp_rect (start -0.94 0.47) (end 0.94 -0.47)
      (stroke (width 0.05) (type solid)) (fill none) (layer "B.CrtYd"))
    (fp_rect (start -0.499 0.249) (end 0.499 -0.249)
      (stroke (width 0.15) (type solid)) (fill none) (layer "B.Fab"))
    (pad "1" smd roundrect (at -0.484 0 90) (size 0.59 0.64) (layers "B.Cu" "B.Paste" "B.Mask") (roundrect_rratio 0.25)
      (net 77 "VDDQ") (pintype "passive"))
    (pad "2" smd roundrect (at 0.484 0 90) (size 0.59 0.64) (layers "B.Cu" "B.Paste" "B.Mask") (roundrect_rratio 0.25)
      (net 9 "GND") (pintype "passive"))
  )

  (footprint "data-center-rdimm-ddr4-tester-footprints:C_0402_1005Metric" (layer "B.Cu")
    (at 197.336328 54.760008 90)
    (descr "Capacitor SMD 0402")
    (tags "capacitor SMD 0402")
    (property "Author" "Antmicro")
    (property "Dielectric" "X5R")
    (property "License" "Apache-2.0")
    (property "MPN" "GRM155R61H104KE14D")
    (property "Manufacturer" "Murata")
    (property "Sheetfile" "DDR4.kicad_sch")
    (property "Sheetname" "DDR4")
    (property "Val" "100n")
    (property "Voltage" "50V")
    (property "ki_description" " ")
    (attr smd)
    (fp_text reference "C153" (at 4.050008 0.423672 270) (layer "B.SilkS")
        (effects (font (size 0.7 0.7) (thickness 0.15)) (justify left bottom mirror))
    )
    (fp_text value "C_100n_0402" (at 0 -1.4 270) (layer "B.Fab") hide
        (effects (font (size 0.7 0.7) (thickness 0.15)) (justify left bottom mirror))
    )
    (fp_text user "Author: Antmicro" (at -0.932 -4.17 270) (layer "B.Fab") hide
        (effects (font (size 0.7 0.7) (thickness 0.15)) (justify left bottom mirror))
    )
    (fp_text user "License: Apache-2.0" (at -0.932 -5.17 270) (layer "B.Fab") hide
        (effects (font (size 0.7 0.7) (thickness 0.15)) (justify left bottom mirror))
    )
    (fp_text user "${REFERENCE}" (at -0.932 -3.168 270) (layer "B.Fab") hide
        (effects (font (size 0.7 0.7) (thickness 0.15)) (justify left bottom mirror))
    )
    (fp_rect (start -0.94 0.47) (end 0.94 -0.47)
      (stroke (width 0.05) (type solid)) (fill none) (layer "B.CrtYd"))
    (fp_rect (start -0.499 0.249) (end 0.499 -0.249)
      (stroke (width 0.15) (type solid)) (fill none) (layer "B.Fab"))
    (pad "1" smd roundrect (at -0.484 0 90) (size 0.59 0.64) (layers "B.Cu" "B.Paste" "B.Mask") (roundrect_rratio 0.25)
      (net 77 "VDDQ") (pintype "passive"))
    (pad "2" smd roundrect (at 0.484 0 90) (size 0.59 0.64) (layers "B.Cu" "B.Paste" "B.Mask") (roundrect_rratio 0.25)
      (net 9 "GND") (pintype "passive"))
  )

  (footprint "data-center-rdimm-ddr4-tester-footprints:C_0402_1005Metric" (layer "B.Cu")
    (at 182.886328 59.297408 -90)
    (descr "Capacitor SMD 0402")
    (tags "capacitor SMD 0402")
    (property "Author" "Antmicro")
    (property "Dielectric" "X5R")
    (property "License" "Apache-2.0")
    (property "MPN" "GRM155R61H104KE14D")
    (property "Manufacturer" "Murata")
    (property "Sheetfile" "DDR4.kicad_sch")
    (property "Sheetname" "DDR4")
    (property "Val" "100n")
    (property "Voltage" "50V")
    (property "ki_description" " ")
    (attr smd)
    (fp_text reference "C208" (at 0.762592 -0.353672 90) (layer "B.SilkS")
        (effects (font (size 0.7 0.7) (thickness 0.15)) (justify left bottom mirror))
    )
    (fp_text value "C_100n_0402" (at 0 -1.4 90) (layer "B.Fab") hide
        (effects (font (size 0.7 0.7) (thickness 0.15)) (justify left bottom mirror))
    )
    (fp_text user "License: Apache-2.0" (at -0.932 -5.17 90) (layer "B.Fab") hide
        (effects (font (size 0.7 0.7) (thickness 0.15)) (justify left bottom mirror))
    )
    (fp_text user "${REFERENCE}" (at -0.932 -3.168 90) (layer "B.Fab") hide
        (effects (font (size 0.7 0.7) (thickness 0.15)) (justify left bottom mirror))
    )
    (fp_text user "Author: Antmicro" (at -0.932 -4.17 90) (layer "B.Fab") hide
        (effects (font (size 0.7 0.7) (thickness 0.15)) (justify left bottom mirror))
    )
    (fp_rect (start -0.94 0.47) (end 0.94 -0.47)
      (stroke (width 0.05) (type solid)) (fill none) (layer "B.CrtYd"))
    (fp_rect (start -0.499 0.249) (end 0.499 -0.249)
      (stroke (width 0.15) (type solid)) (fill none) (layer "B.Fab"))
    (pad "1" smd roundrect (at -0.484 0 270) (size 0.59 0.64) (layers "B.Cu" "B.Paste" "B.Mask") (roundrect_rratio 0.25)
      (net 77 "VDDQ") (pintype "passive"))
    (pad "2" smd roundrect (at 0.484 0 270) (size 0.59 0.64) (layers "B.Cu" "B.Paste" "B.Mask") (roundrect_rratio 0.25)
      (net 9 "GND") (pintype "passive"))
  )

  (footprint "data-center-rdimm-ddr4-tester-footprints:C_0402_1005Metric" (layer "B.Cu")
    (at 194.732928 57.951208 90)
    (descr "Capacitor SMD 0402")
    (tags "capacitor SMD 0402")
    (property "Author" "Antmicro")
    (property "Dielectric" "X5R")
    (property "License" "Apache-2.0")
    (property "MPN" "GRM155R61H104KE14D")
    (property "Manufacturer" "Murata")
    (property "Sheetfile" "DDR4.kicad_sch")
    (property "Sheetname" "DDR4")
    (property "Val" "100n")
    (property "Voltage" "50V")
    (property "ki_description" " ")
    (attr smd)
    (fp_text reference "C209" (at -0.878792 0.370872 270) (layer "B.SilkS")
        (effects (font (size 0.7 0.7) (thickness 0.15)) (justify left bottom mirror))
    )
    (fp_text value "C_100n_0402" (at 0 -1.4 270) (layer "B.Fab") hide
        (effects (font (size 0.7 0.7) (thickness 0.15)) (justify left bottom mirror))
    )
    (fp_text user "License: Apache-2.0" (at -0.932 -5.17 270) (layer "B.Fab") hide
        (effects (font (size 0.7 0.7) (thickness 0.15)) (justify left bottom mirror))
    )
    (fp_text user "${REFERENCE}" (at -0.932 -3.168 270) (layer "B.Fab") hide
        (effects (font (size 0.7 0.7) (thickness 0.15)) (justify left bottom mirror))
    )
    (fp_text user "Author: Antmicro" (at -0.932 -4.17 270) (layer "B.Fab") hide
        (effects (font (size 0.7 0.7) (thickness 0.15)) (justify left bottom mirror))
    )
    (fp_rect (start -0.94 0.47) (end 0.94 -0.47)
      (stroke (width 0.05) (type solid)) (fill none) (layer "B.CrtYd"))
    (fp_rect (start -0.499 0.249) (end 0.499 -0.249)
      (stroke (width 0.15) (type solid)) (fill none) (layer "B.Fab"))
    (pad "1" smd roundrect (at -0.484 0 90) (size 0.59 0.64) (layers "B.Cu" "B.Paste" "B.Mask") (roundrect_rratio 0.25)
      (net 77 "VDDQ") (pintype "passive"))
    (pad "2" smd roundrect (at 0.484 0 90) (size 0.59 0.64) (layers "B.Cu" "B.Paste" "B.Mask") (roundrect_rratio 0.25)
      (net 9 "GND") (pintype "passive"))
  )

  (footprint "data-center-rdimm-ddr4-tester-footprints:C_0402_1005Metric" (layer "B.Cu")
    (at 198.2 59)
    (descr "Capacitor SMD 0402")
    (tags "capacitor SMD 0402")
    (property "Author" "Antmicro")
    (property "Dielectric" "X5R")
    (property "License" "Apache-2.0")
    (property "MPN" "GRM155R61H104KE14D")
    (property "Manufacturer" "Murata")
    (property "Sheetfile" "DDR4.kicad_sch")
    (property "Sheetname" "DDR4")
    (property "Val" "100n")
    (property "Voltage" "50V")
    (property "ki_description" " ")
    (attr smd)
    (fp_text reference "C211" (at 1.4 1.31 180) (layer "B.SilkS")
        (effects (font (size 0.7 0.7) (thickness 0.15)) (justify left bottom mirror))
    )
    (fp_text value "C_100n_0402" (at 0 -1.4 180) (layer "B.Fab") hide
        (effects (font (size 0.7 0.7) (thickness 0.15)) (justify left bottom mirror))
    )
    (fp_text user "Author: Antmicro" (at -0.932 -4.17 180) (layer "B.Fab") hide
        (effects (font (size 0.7 0.7) (thickness 0.15)) (justify left bottom mirror))
    )
    (fp_text user "${REFERENCE}" (at -0.932 -3.168 180) (layer "B.Fab") hide
        (effects (font (size 0.7 0.7) (thickness 0.15)) (justify left bottom mirror))
    )
    (fp_text user "License: Apache-2.0" (at -0.932 -5.17 180) (layer "B.Fab") hide
        (effects (font (size 0.7 0.7) (thickness 0.15)) (justify left bottom mirror))
    )
    (fp_rect (start -0.94 0.47) (end 0.94 -0.47)
      (stroke (width 0.05) (type solid)) (fill none) (layer "B.CrtYd"))
    (fp_rect (start -0.499 0.249) (end 0.499 -0.249)
      (stroke (width 0.15) (type solid)) (fill none) (layer "B.Fab"))
    (pad "1" smd roundrect (at -0.484 0) (size 0.59 0.64) (layers "B.Cu" "B.Paste" "B.Mask") (roundrect_rratio 0.25)
      (net 77 "VDDQ") (pintype "passive"))
    (pad "2" smd roundrect (at 0.484 0) (size 0.59 0.64) (layers "B.Cu" "B.Paste" "B.Mask") (roundrect_rratio 0.25)
      (net 9 "GND") (pintype "passive"))
  )

  (footprint "data-center-rdimm-ddr4-tester-footprints:C_0402_1005Metric" (layer "B.Cu")
    (at 192.091328 57.951208 90)
    (descr "Capacitor SMD 0402")
    (tags "capacitor SMD 0402")
    (property "Author" "Antmicro")
    (property "Dielectric" "X5R")
    (property "License" "Apache-2.0")
    (property "MPN" "GRM155R61H104KE14D")
    (property "Manufacturer" "Murata")
    (property "Sheetfile" "DDR4.kicad_sch")
    (property "Sheetname" "DDR4")
    (property "Val" "100n")
    (property "Voltage" "50V")
    (property "ki_description" " ")
    (attr smd)
    (fp_text reference "C212" (at -0.878792 0.370872 270) (layer "B.SilkS")
        (effects (font (size 0.7 0.7) (thickness 0.15)) (justify left bottom mirror))
    )
    (fp_text value "C_100n_0402" (at 0 -1.4 270) (layer "B.Fab") hide
        (effects (font (size 0.7 0.7) (thickness 0.15)) (justify left bottom mirror))
    )
    (fp_text user "Author: Antmicro" (at -0.932 -4.17 270) (layer "B.Fab") hide
        (effects (font (size 0.7 0.7) (thickness 0.15)) (justify left bottom mirror))
    )
    (fp_text user "${REFERENCE}" (at -0.932 -3.168 270) (layer "B.Fab") hide
        (effects (font (size 0.7 0.7) (thickness 0.15)) (justify left bottom mirror))
    )
    (fp_text user "License: Apache-2.0" (at -0.932 -5.17 270) (layer "B.Fab") hide
        (effects (font (size 0.7 0.7) (thickness 0.15)) (justify left bottom mirror))
    )
    (fp_rect (start -0.94 0.47) (end 0.94 -0.47)
      (stroke (width 0.05) (type solid)) (fill none) (layer "B.CrtYd"))
    (fp_rect (start -0.499 0.249) (end 0.499 -0.249)
      (stroke (width 0.15) (type solid)) (fill none) (layer "B.Fab"))
    (pad "1" smd roundrect (at -0.484 0 90) (size 0.59 0.64) (layers "B.Cu" "B.Paste" "B.Mask") (roundrect_rratio 0.25)
      (net 77 "VDDQ") (pintype "passive"))
    (pad "2" smd roundrect (at 0.484 0 90) (size 0.59 0.64) (layers "B.Cu" "B.Paste" "B.Mask") (roundrect_rratio 0.25)
      (net 9 "GND") (pintype "passive"))
  )

  (footprint "data-center-rdimm-ddr4-tester-footprints:C_0402_1005Metric" (layer "B.Cu")
    (at 187.189128 57.951208 90)
    (descr "Capacitor SMD 0402")
    (tags "capacitor SMD 0402")
    (property "Author" "Antmicro")
    (property "Dielectric" "X5R")
    (property "License" "Apache-2.0")
    (property "MPN" "GRM155R61H104KE14D")
    (property "Manufacturer" "Murata")
    (property "Sheetfile" "DDR4.kicad_sch")
    (property "Sheetname" "DDR4")
    (property "Val" "100n")
    (property "Voltage" "50V")
    (property "ki_description" " ")
    (attr smd)
    (fp_text reference "C213" (at -0.878792 0.370872 270) (layer "B.SilkS")
        (effects (font (size 0.7 0.7) (thickness 0.15)) (justify left bottom mirror))
    )
    (fp_text value "C_100n_0402" (at 0 -1.4 270) (layer "B.Fab") hide
        (effects (font (size 0.7 0.7) (thickness 0.15)) (justify left bottom mirror))
    )
    (fp_text user "Author: Antmicro" (at -0.932 -4.17 270) (layer "B.Fab") hide
        (effects (font (size 0.7 0.7) (thickness 0.15)) (justify left bottom mirror))
    )
    (fp_text user "${REFERENCE}" (at -0.932 -3.168 270) (layer "B.Fab") hide
        (effects (font (size 0.7 0.7) (thickness 0.15)) (justify left bottom mirror))
    )
    (fp_text user "License: Apache-2.0" (at -0.932 -5.17 270) (layer "B.Fab") hide
        (effects (font (size 0.7 0.7) (thickness 0.15)) (justify left bottom mirror))
    )
    (fp_rect (start -0.94 0.47) (end 0.94 -0.47)
      (stroke (width 0.05) (type solid)) (fill none) (layer "B.CrtYd"))
    (fp_rect (start -0.499 0.249) (end 0.499 -0.249)
      (stroke (width 0.15) (type solid)) (fill none) (layer "B.Fab"))
    (pad "1" smd roundrect (at -0.484 0 90) (size 0.59 0.64) (layers "B.Cu" "B.Paste" "B.Mask") (roundrect_rratio 0.25)
      (net 77 "VDDQ") (pintype "passive"))
    (pad "2" smd roundrect (at 0.484 0 90) (size 0.59 0.64) (layers "B.Cu" "B.Paste" "B.Mask") (roundrect_rratio 0.25)
      (net 9 "GND") (pintype "passive"))
  )

  (footprint "data-center-rdimm-ddr4-tester-footprints:C_0402_1005Metric" (layer "B.Cu")
    (at 189.779928 57.951208 90)
    (descr "Capacitor SMD 0402")
    (tags "capacitor SMD 0402")
    (property "Author" "Antmicro")
    (property "Dielectric" "X5R")
    (property "License" "Apache-2.0")
    (property "MPN" "GRM155R61H104KE14D")
    (property "Manufacturer" "Murata")
    (property "Sheetfile" "DDR4.kicad_sch")
    (property "Sheetname" "DDR4")
    (property "Val" "100n")
    (property "Voltage" "50V")
    (property "ki_description" " ")
    (attr smd)
    (fp_text reference "C214" (at -0.878792 0.370872 270) (layer "B.SilkS")
        (effects (font (size 0.7 0.7) (thickness 0.15)) (justify left bottom mirror))
    )
    (fp_text value "C_100n_0402" (at 0 -1.4 270) (layer "B.Fab") hide
        (effects (font (size 0.7 0.7) (thickness 0.15)) (justify left bottom mirror))
    )
    (fp_text user "License: Apache-2.0" (at -0.932 -5.17 270) (layer "B.Fab") hide
        (effects (font (size 0.7 0.7) (thickness 0.15)) (justify left bottom mirror))
    )
    (fp_text user "Author: Antmicro" (at -0.932 -4.17 270) (layer "B.Fab") hide
        (effects (font (size 0.7 0.7) (thickness 0.15)) (justify left bottom mirror))
    )
    (fp_text user "${REFERENCE}" (at -0.932 -3.168 270) (layer "B.Fab") hide
        (effects (font (size 0.7 0.7) (thickness 0.15)) (justify left bottom mirror))
    )
    (fp_rect (start -0.94 0.47) (end 0.94 -0.47)
      (stroke (width 0.05) (type solid)) (fill none) (layer "B.CrtYd"))
    (fp_rect (start -0.499 0.249) (end 0.499 -0.249)
      (stroke (width 0.15) (type solid)) (fill none) (layer "B.Fab"))
    (pad "1" smd roundrect (at -0.484 0 90) (size 0.59 0.64) (layers "B.Cu" "B.Paste" "B.Mask") (roundrect_rratio 0.25)
      (net 77 "VDDQ") (pintype "passive"))
    (pad "2" smd roundrect (at 0.484 0 90) (size 0.59 0.64) (layers "B.Cu" "B.Paste" "B.Mask") (roundrect_rratio 0.25)
      (net 9 "GND") (pintype "passive"))
  )

  (footprint "data-center-rdimm-ddr4-tester-footprints:C_0402_1005Metric" (layer "B.Cu")
    (at 184.649128 57.951208 90)
    (descr "Capacitor SMD 0402")
    (tags "capacitor SMD 0402")
    (property "Author" "Antmicro")
    (property "Dielectric" "X5R")
    (property "License" "Apache-2.0")
    (property "MPN" "GRM155R61H104KE14D")
    (property "Manufacturer" "Murata")
    (property "Sheetfile" "DDR4.kicad_sch")
    (property "Sheetname" "DDR4")
    (property "Val" "100n")
    (property "Voltage" "50V")
    (property "ki_description" " ")
    (attr smd)
    (fp_text reference "C210" (at -0.878792 0.370872 270) (layer "B.SilkS")
        (effects (font (size 0.7 0.7) (thickness 0.15)) (justify left bottom mirror))
    )
    (fp_text value "C_100n_0402" (at 0 -1.4 270) (layer "B.Fab") hide
        (effects (font (size 0.7 0.7) (thickness 0.15)) (justify left bottom mirror))
    )
    (fp_text user "${REFERENCE}" (at -0.932 -3.168 270) (layer "B.Fab") hide
        (effects (font (size 0.7 0.7) (thickness 0.15)) (justify left bottom mirror))
    )
    (fp_text user "Author: Antmicro" (at -0.932 -4.17 270) (layer "B.Fab") hide
        (effects (font (size 0.7 0.7) (thickness 0.15)) (justify left bottom mirror))
    )
    (fp_text user "License: Apache-2.0" (at -0.932 -5.17 270) (layer "B.Fab") hide
        (effects (font (size 0.7 0.7) (thickness 0.15)) (justify left bottom mirror))
    )
    (fp_rect (start -0.94 0.47) (end 0.94 -0.47)
      (stroke (width 0.05) (type solid)) (fill none) (layer "B.CrtYd"))
    (fp_rect (start -0.499 0.249) (end 0.499 -0.249)
      (stroke (width 0.15) (type solid)) (fill none) (layer "B.Fab"))
    (pad "1" smd roundrect (at -0.484 0 90) (size 0.59 0.64) (layers "B.Cu" "B.Paste" "B.Mask") (roundrect_rratio 0.25)
      (net 77 "VDDQ") (pintype "passive"))
    (pad "2" smd roundrect (at 0.484 0 90) (size 0.59 0.64) (layers "B.Cu" "B.Paste" "B.Mask") (roundrect_rratio 0.25)
      (net 9 "GND") (pintype "passive"))
  )

  (footprint "data-center-rdimm-ddr4-tester-footprints:R_0402_1005Metric" (layer "B.Cu")
    (at 122.736328 103.500008 -90)
    (descr "Resistor SMD 0402")
    (tags "resistor SMD 0402")
    (property "Author" "Antmicro")
    (property "Current" "1A")
    (property "License" "Apache-2.0")
    (property "MPN" "ERJ2GE0R00X")
    (property "Manufacturer" "Panasonic")
    (property "Sheetfile" "supply.kicad_sch")
    (property "Sheetname" "Supply")
    (property "Tolerance" "")
    (property "Val" "0R")
    (property "ki_description" "0R resistor in 0402 package with unspecified tolerance")
    (attr smd)
    (fp_text reference "R47" (at -0.980008 0.576328 90) (layer "B.SilkS")
        (effects (font (size 0.7 0.7) (thickness 0.15)) (justify left bottom mirror))
    )
    (fp_text value "R_0R_0402" (at 0 -1.4 90) (layer "B.Fab") hide
        (effects (font (size 0.7 0.7) (thickness 0.15)) (justify left bottom mirror))
    )
    (fp_text user "${REFERENCE}" (at -0.95 -3.168 90) (layer "B.Fab") hide
        (effects (font (size 0.7 0.7) (thickness 0.15)) (justify left bottom mirror))
    )
    (fp_text user "Author: Antmicro" (at -0.95 -4.169 90) (layer "B.Fab") hide
        (effects (font (size 0.7 0.7) (thickness 0.15)) (justify left bottom mirror))
    )
    (fp_text user "License: Apache-2.0" (at -0.95 -5.169 90) (layer "B.Fab") hide
        (effects (font (size 0.7 0.7) (thickness 0.15)) (justify left bottom mirror))
    )
    (fp_rect (start -0.93 0.47) (end 0.93 -0.47)
      (stroke (width 0.05) (type solid)) (fill none) (layer "B.CrtYd"))
    (fp_rect (start -0.5 0.25) (end 0.5 -0.25)
      (stroke (width 0.15) (type solid)) (fill none) (layer "B.Fab"))
    (pad "1" smd roundrect (at -0.485 0 270) (size 0.59 0.64) (layers "B.Cu" "B.Paste" "B.Mask") (roundrect_rratio 0.25)
      (net 153 "/Supply/VCC_IO_EN") (pintype "passive"))
    (pad "2" smd roundrect (at 0.485 0 270) (size 0.59 0.64) (layers "B.Cu" "B.Paste" "B.Mask") (roundrect_rratio 0.25)
      (net 642 "Net-(U9-EN)") (pintype "passive"))
  )

  (footprint "data-center-rdimm-ddr4-tester-footprints:R_0402_1005Metric" (layer "B.Cu")
    (at 134.386328 94.310008 90)
    (descr "Resistor SMD 0402")
    (tags "resistor SMD 0402")
    (property "Author" "Antmicro")
    (property "Current" "1A")
    (property "License" "Apache-2.0")
    (property "MPN" "ERJ2GE0R00X")
    (property "Manufacturer" "Panasonic")
    (property "Sheetfile" "supply.kicad_sch")
    (property "Sheetname" "Supply")
    (property "Tolerance" "")
    (property "Val" "0R")
    (property "ki_description" "0R resistor in 0402 package with unspecified tolerance")
    (attr smd)
    (fp_text reference "R48" (at 1.100008 1.313672 270) (layer "B.SilkS")
        (effects (font (size 0.7 0.7) (thickness 0.15)) (justify left bottom mirror))
    )
    (fp_text value "R_0R_0402" (at 0 -1.4 270) (layer "B.Fab") hide
        (effects (font (size 0.7 0.7) (thickness 0.15)) (justify left bottom mirror))
    )
    (fp_text user "Author: Antmicro" (at -0.95 -4.169 270) (layer "B.Fab") hide
        (effects (font (size 0.7 0.7) (thickness 0.15)) (justify left bottom mirror))
    )
    (fp_text user "${REFERENCE}" (at -0.95 -3.168 270) (layer "B.Fab") hide
        (effects (font (size 0.7 0.7) (thickness 0.15)) (justify left bottom mirror))
    )
    (fp_text user "License: Apache-2.0" (at -0.95 -5.169 270) (layer "B.Fab") hide
        (effects (font (size 0.7 0.7) (thickness 0.15)) (justify left bottom mirror))
    )
    (fp_rect (start -0.93 0.47) (end 0.93 -0.47)
      (stroke (width 0.05) (type solid)) (fill none) (layer "B.CrtYd"))
    (fp_rect (start -0.5 0.25) (end 0.5 -0.25)
      (stroke (width 0.15) (type solid)) (fill none) (layer "B.Fab"))
    (pad "1" smd roundrect (at -0.485 0 90) (size 0.59 0.64) (layers "B.Cu" "B.Paste" "B.Mask") (roundrect_rratio 0.25)
      (net 152 "/Supply/VCC_AUX_EN") (pintype "passive"))
    (pad "2" smd roundrect (at 0.485 0 90) (size 0.59 0.64) (layers "B.Cu" "B.Paste" "B.Mask") (roundrect_rratio 0.25)
      (net 643 "Net-(U12-EN)") (pintype "passive"))
  )

  (footprint "data-center-rdimm-ddr4-tester-footprints:Fiducial_1mm_Mask2mm" (layer "B.Cu")
    (at 252 50 180)
    (descr "Circular Fiducial, 1mm bare copper, 3mm soldermask opening")
    (tags "fiducial")
    (property "Author" "Antmicro")
    (property "License" "Apache-2.0")
    (property "MPN" "")
    (property "Manufacturer" "")
    (property "Sheetfile" "data-center-rdimm-ddr4-tester.kicad_sch")
    (property "Sheetname" "")
    (property "exclude_from_bom" "")
    (property "ki_description" "Fiducial Marker for use with single board only")
    (attr exclude_from_pos_files exclude_from_bom)
    (fp_text reference "FID6" (at -0.99 1.4) (layer "B.SilkS")
        (effects (font (size 0.7 0.7) (thickness 0.15)) (justify left bottom mirror))
    )
    (fp_text value "Fiducial_1mm_Mask2mm" (at 0 -2.2) (layer "B.Fab")
        (effects (font (size 0.7 0.7) (thickness 0.15)) (justify left bottom mirror))
    )
    (fp_text user "License: Apache-2.0" (at -1.25 -7.003) (layer "B.Fab") hide
        (effects (font (size 0.7 0.7) (thickness 0.15)) (justify left bottom mirror))
    )
    (fp_text user "Author: Antmicro" (at -1.25 -5.803) (layer "B.Fab") hide
        (effects (font (size 0.7 0.7) (thickness 0.15)) (justify left bottom mirror))
    )
    (fp_text user "${REFERENCE}" (at -1.25 -4.603) (layer "B.Fab") hide
        (effects (font (size 0.7 0.7) (thickness 0.15)) (justify left bottom mirror))
    )
    (fp_circle (center 0 0) (end 1.24 0)
      (stroke (width 0.05) (type solid)) (fill none) (layer "B.CrtYd"))
    (fp_circle (center 0 0) (end 0.999 0)
      (stroke (width 0.15) (type solid)) (fill none) (layer "B.Fab"))
    (pad "" smd circle (at 0 0 180) (size 1 1) (layers "B.Cu" "B.Mask")
      (solder_mask_margin 0.5) (clearance 0.5))
  )

  (footprint "data-center-rdimm-ddr4-tester-footprints:C_0201" (layer "B.Cu")
    (at 192.125 95.625)
    (descr "Capacitor SMD 0201")
    (tags "capacitor SMD 0201")
    (property "Author" "Antmicro")
    (property "Dielectric" "")
    (property "License" "Apache-2.0")
    (property "MPN" "CC0201KRX6S5BB104")
    (property "Manufacturer" "Yaego")
    (property "Sheetfile" "fpga-power.kicad_sch")
    (property "Sheetname" "FPGA power")
    (property "Val" "100n")
    (property "Voltage" "")
    (property "ki_description" " ")
    (attr smd)
    (fp_text reference "C244" (at 5.465 0.305 180) (layer "B.SilkS")
        (effects (font (size 0.7 0.7) (thickness 0.15)) (justify left bottom mirror))
    )
    (fp_text value "C_100n_0201" (at 0 -1.4 180) (layer "B.Fab") hide
        (effects (font (size 0.7 0.7) (thickness 0.15)) (justify left bottom mirror))
    )
    (fp_text user "${REFERENCE}" (at -0.72 -3.4 180) (layer "B.Fab") hide
        (effects (font (size 0.7 0.7) (thickness 0.15)) (justify left bottom mirror))
    )
    (fp_text user "Author: Antmicro" (at -0.72 -5.4 180) (layer "B.Fab") hide
        (effects (font (size 0.7 0.7) (thickness 0.15)) (justify left bottom mirror))
    )
    (fp_text user "License: Apache-2.0" (at -0.72 -4.4 180) (layer "B.Fab") hide
        (effects (font (size 0.7 0.7) (thickness 0.15)) (justify left bottom mirror))
    )
    (fp_rect (start -0.72 0.38) (end 0.72 -0.38)
      (stroke (width 0.05) (type solid)) (fill none) (layer "B.CrtYd"))
    (fp_rect (start 0.3 -0.15) (end -0.301 0.149)
      (stroke (width 0.15) (type solid)) (fill none) (layer "B.Fab"))
    (pad "" smd roundrect (at -0.349 0.002) (size 0.318 0.36) (layers "B.Paste") (roundrect_rratio 0.25))
    (pad "" smd roundrect (at 0.341 0.002) (size 0.318 0.36) (layers "B.Paste") (roundrect_rratio 0.25))
    (pad "1" smd roundrect (at -0.321 0.002) (size 0.46 0.4) (layers "B.Cu" "B.Mask") (roundrect_rratio 0.25)
      (net 147 "1V0_SYS") (pintype "passive"))
    (pad "2" smd roundrect (at 0.32 0.002) (size 0.46 0.4) (layers "B.Cu" "B.Mask") (roundrect_rratio 0.25)
      (net 9 "GND") (pintype "passive"))
  )

  (footprint "data-center-rdimm-ddr4-tester-footprints:C_0402_1005Metric" (layer "B.Cu")
    (at 122.4 117.55)
    (descr "Capacitor SMD 0402")
    (tags "capacitor SMD 0402")
    (property "Author" "Antmicro")
    (property "Dielectric" "X5R")
    (property "License" "Apache-2.0")
    (property "MPN" "GRM155R61H104KE14D")
    (property "Manufacturer" "Murata")
    (property "Sheetfile" "supply.kicad_sch")
    (property "Sheetname" "Supply")
    (property "Val" "100n")
    (property "Voltage" "50V")
    (property "ki_description" " ")
    (attr smd)
    (fp_text reference "C285" (at 1.57 -0.6 180) (layer "B.SilkS")
        (effects (font (size 0.7 0.7) (thickness 0.15)) (justify left bottom mirror))
    )
    (fp_text value "C_100n_0402" (at 0 -1.4 180) (layer "B.Fab") hide
        (effects (font (size 0.7 0.7) (thickness 0.15)) (justify left bottom mirror))
    )
    (fp_text user "License: Apache-2.0" (at -0.932 -5.17 180) (layer "B.Fab") hide
        (effects (font (size 0.7 0.7) (thickness 0.15)) (justify left bottom mirror))
    )
    (fp_text user "Author: Antmicro" (at -0.932 -4.17 180) (layer "B.Fab") hide
        (effects (font (size 0.7 0.7) (thickness 0.15)) (justify left bottom mirror))
    )
    (fp_text user "${REFERENCE}" (at -0.932 -3.168 180) (layer "B.Fab") hide
        (effects (font (size 0.7 0.7) (thickness 0.15)) (justify left bottom mirror))
    )
    (fp_rect (start -0.94 0.47) (end 0.94 -0.47)
      (stroke (width 0.05) (type solid)) (fill none) (layer "B.CrtYd"))
    (fp_rect (start -0.499 0.249) (end 0.499 -0.249)
      (stroke (width 0.15) (type solid)) (fill none) (layer "B.Fab"))
    (pad "1" smd roundrect (at -0.484 0) (size 0.59 0.64) (layers "B.Cu" "B.Paste" "B.Mask") (roundrect_rratio 0.25)
      (net 307 "5V0_SYS") (pintype "passive"))
    (pad "2" smd roundrect (at 0.484 0) (size 0.59 0.64) (layers "B.Cu" "B.Paste" "B.Mask") (roundrect_rratio 0.25)
      (net 9 "GND") (pintype "passive"))
  )

  (footprint "data-center-rdimm-ddr4-tester-footprints:C_0201" (layer "B.Cu")
    (at 187.1 97.425 180)
    (descr "Capacitor SMD 0201")
    (tags "capacitor SMD 0201")
    (property "Author" "Antmicro")
    (property "Dielectric" "")
    (property "License" "Apache-2.0")
    (property "MPN" "CC0201KRX6S5BB104")
    (property "Manufacturer" "Yaego")
    (property "Sheetfile" "fpga-power.kicad_sch")
    (property "Sheetname" "FPGA power")
    (property "Val" "100n")
    (property "Voltage" "")
    (property "ki_description" " ")
    (attr smd)
    (fp_text reference "C86" (at -1.12 -1.135) (layer "B.SilkS")
        (effects (font (size 0.7 0.7) (thickness 0.15)) (justify left bottom mirror))
    )
    (fp_text value "C_100n_0201" (at 0 -1.4) (layer "B.Fab") hide
        (effects (font (size 0.7 0.7) (thickness 0.15)) (justify left bottom mirror))
    )
    (fp_text user "License: Apache-2.0" (at -0.72 -4.4) (layer "B.Fab") hide
        (effects (font (size 0.7 0.7) (thickness 0.15)) (justify left bottom mirror))
    )
    (fp_text user "Author: Antmicro" (at -0.72 -5.4) (layer "B.Fab") hide
        (effects (font (size 0.7 0.7) (thickness 0.15)) (justify left bottom mirror))
    )
    (fp_text user "${REFERENCE}" (at -0.72 -3.4) (layer "B.Fab") hide
        (effects (font (size 0.7 0.7) (thickness 0.15)) (justify left bottom mirror))
    )
    (fp_rect (start -0.72 0.38) (end 0.72 -0.38)
      (stroke (width 0.05) (type solid)) (fill none) (layer "B.CrtYd"))
    (fp_rect (start 0.3 -0.15) (end -0.301 0.149)
      (stroke (width 0.15) (type solid)) (fill none) (layer "B.Fab"))
    (pad "" smd roundrect (at -0.349 0.002 180) (size 0.318 0.36) (layers "B.Paste") (roundrect_rratio 0.25))
    (pad "" smd roundrect (at 0.341 0.002 180) (size 0.318 0.36) (layers "B.Paste") (roundrect_rratio 0.25))
    (pad "1" smd roundrect (at -0.321 0.002 180) (size 0.46 0.4) (layers "B.Cu" "B.Mask") (roundrect_rratio 0.25)
      (net 143 "3V3_SYS") (pintype "passive"))
    (pad "2" smd roundrect (at 0.32 0.002 180) (size 0.46 0.4) (layers "B.Cu" "B.Mask") (roundrect_rratio 0.25)
      (net 9 "GND") (pintype "passive"))
  )

  (footprint "data-center-rdimm-ddr4-tester-footprints:C_0201" (layer "B.Cu")
    (at 178.65 78.55)
    (descr "Capacitor SMD 0201")
    (tags "capacitor SMD 0201")
    (property "Author" "Antmicro")
    (property "Dielectric" "")
    (property "License" "Apache-2.0")
    (property "MPN" "CC0201KRX6S5BB104")
    (property "Manufacturer" "Yaego")
    (property "Sheetfile" "fpga-power.kicad_sch")
    (property "Sheetname" "FPGA power")
    (property "Val" "100n")
    (property "Voltage" "")
    (property "ki_description" " ")
    (attr smd)
    (fp_text reference "C297" (at -0.54 0.37 180) (layer "B.SilkS")
        (effects (font (size 0.7 0.7) (thickness 0.15)) (justify left bottom mirror))
    )
    (fp_text value "C_100n_0201" (at 0 -1.4 180) (layer "B.Fab") hide
        (effects (font (size 0.7 0.7) (thickness 0.15)) (justify left bottom mirror))
    )
    (fp_text user "Author: Antmicro" (at -0.72 -5.4 180) (layer "B.Fab") hide
        (effects (font (size 0.7 0.7) (thickness 0.15)) (justify left bottom mirror))
    )
    (fp_text user "License: Apache-2.0" (at -0.72 -4.4 180) (layer "B.Fab") hide
        (effects (font (size 0.7 0.7) (thickness 0.15)) (justify left bottom mirror))
    )
    (fp_text user "${REFERENCE}" (at -0.72 -3.4 180) (layer "B.Fab") hide
        (effects (font (size 0.7 0.7) (thickness 0.15)) (justify left bottom mirror))
    )
    (fp_rect (start -0.72 0.38) (end 0.72 -0.38)
      (stroke (width 0.05) (type solid)) (fill none) (layer "B.CrtYd"))
    (fp_rect (start 0.3 -0.15) (end -0.301 0.149)
      (stroke (width 0.15) (type solid)) (fill none) (layer "B.Fab"))
    (pad "" smd roundrect (at -0.349 0.002) (size 0.318 0.36) (layers "B.Paste") (roundrect_rratio 0.25))
    (pad "" smd roundrect (at 0.341 0.002) (size 0.318 0.36) (layers "B.Paste") (roundrect_rratio 0.25))
    (pad "1" smd roundrect (at -0.321 0.002) (size 0.46 0.4) (layers "B.Cu" "B.Mask") (roundrect_rratio 0.25)
      (net 77 "VDDQ") (pintype "passive"))
    (pad "2" smd roundrect (at 0.32 0.002) (size 0.46 0.4) (layers "B.Cu" "B.Mask") (roundrect_rratio 0.25)
      (net 9 "GND") (pintype "passive"))
  )

  (footprint "data-center-rdimm-ddr4-tester-footprints:C_0402_1005Metric" (layer "B.Cu")
    (at 192.2 101.7)
    (descr "Capacitor SMD 0402")
    (tags "capacitor SMD 0402")
    (property "Author" "Antmicro")
    (property "Dielectric" "")
    (property "License" "Apache-2.0")
    (property "MPN" "GRM155R61A475MEAAD")
    (property "Manufacturer" "Murata")
    (property "Sheetfile" "fpga-power.kicad_sch")
    (property "Sheetname" "FPGA power")
    (property "Val" "4u7")
    (property "Voltage" "")
    (property "ki_description" " ")
    (attr smd)
    (fp_text reference "C245" (at 1.08 1.3 180) (layer "B.SilkS")
        (effects (font (size 0.7 0.7) (thickness 0.15)) (justify left bottom mirror))
    )
    (fp_text value "C_4u7_0402" (at 0 -1.4 180) (layer "B.Fab") hide
        (effects (font (size 0.7 0.7) (thickness 0.15)) (justify left bottom mirror))
    )
    (fp_text user "License: Apache-2.0" (at -0.932 -5.17 180) (layer "B.Fab") hide
        (effects (font (size 0.7 0.7) (thickness 0.15)) (justify left bottom mirror))
    )
    (fp_text user "Author: Antmicro" (at -0.932 -4.17 180) (layer "B.Fab") hide
        (effects (font (size 0.7 0.7) (thickness 0.15)) (justify left bottom mirror))
    )
    (fp_text user "${REFERENCE}" (at -0.932 -3.168 180) (layer "B.Fab") hide
        (effects (font (size 0.7 0.7) (thickness 0.15)) (justify left bottom mirror))
    )
    (fp_rect (start -0.94 0.47) (end 0.94 -0.47)
      (stroke (width 0.05) (type solid)) (fill none) (layer "B.CrtYd"))
    (fp_rect (start -0.499 0.249) (end 0.499 -0.249)
      (stroke (width 0.15) (type solid)) (fill none) (layer "B.Fab"))
    (pad "1" smd roundrect (at -0.484 0) (size 0.59 0.64) (layers "B.Cu" "B.Paste" "B.Mask") (roundrect_rratio 0.25)
      (net 147 "1V0_SYS") (pintype "passive"))
    (pad "2" smd roundrect (at 0.484 0) (size 0.59 0.64) (layers "B.Cu" "B.Paste" "B.Mask") (roundrect_rratio 0.25)
      (net 9 "GND") (pintype "passive"))
  )

  (footprint "data-center-rdimm-ddr4-tester-footprints:C_0201" (layer "B.Cu")
    (at 180.25 89.925 -90)
    (descr "Capacitor SMD 0201")
    (tags "capacitor SMD 0201")
    (property "Author" "Antmicro")
    (property "Dielectric" "")
    (property "License" "Apache-2.0")
    (property "MPN" "CC0201KRX6S5BB104")
    (property "Manufacturer" "Yaego")
    (property "Sheetfile" "fpga-power.kicad_sch")
    (property "Sheetname" "FPGA power")
    (property "Val" "100n")
    (property "Voltage" "")
    (property "ki_description" " ")
    (attr smd)
    (fp_text reference "C79" (at -0.945 0.51 90) (layer "B.SilkS")
        (effects (font (size 0.7 0.7) (thickness 0.15)) (justify left bottom mirror))
    )
    (fp_text value "C_100n_0201" (at 0 -1.4 90) (layer "B.Fab") hide
        (effects (font (size 0.7 0.7) (thickness 0.15)) (justify left bottom mirror))
    )
    (fp_text user "Author: Antmicro" (at -0.72 -5.4 90) (layer "B.Fab") hide
        (effects (font (size 0.7 0.7) (thickness 0.15)) (justify left bottom mirror))
    )
    (fp_text user "License: Apache-2.0" (at -0.72 -4.4 90) (layer "B.Fab") hide
        (effects (font (size 0.7 0.7) (thickness 0.15)) (justify left bottom mirror))
    )
    (fp_text user "${REFERENCE}" (at -0.72 -3.4 90) (layer "B.Fab") hide
        (effects (font (size 0.7 0.7) (thickness 0.15)) (justify left bottom mirror))
    )
    (fp_rect (start -0.72 0.38) (end 0.72 -0.38)
      (stroke (width 0.05) (type solid)) (fill none) (layer "B.CrtYd"))
    (fp_rect (start 0.3 -0.15) (end -0.301 0.149)
      (stroke (width 0.15) (type solid)) (fill none) (layer "B.Fab"))
    (pad "" smd roundrect (at -0.349 0.002 270) (size 0.318 0.36) (layers "B.Paste") (roundrect_rratio 0.25))
    (pad "" smd roundrect (at 0.341 0.002 270) (size 0.318 0.36) (layers "B.Paste") (roundrect_rratio 0.25))
    (pad "1" smd roundrect (at -0.321 0.002 270) (size 0.46 0.4) (layers "B.Cu" "B.Mask") (roundrect_rratio 0.25)
      (net 77 "VDDQ") (pintype "passive"))
    (pad "2" smd roundrect (at 0.32 0.002 270) (size 0.46 0.4) (layers "B.Cu" "B.Mask") (roundrect_rratio 0.25)
      (net 9 "GND") (pintype "passive"))
  )

  (footprint "data-center-rdimm-ddr4-tester-footprints:C_0201" (layer "B.Cu")
    (at 194.1 95.6 180)
    (descr "Capacitor SMD 0201")
    (tags "capacitor SMD 0201")
    (property "Author" "Antmicro")
    (property "Dielectric" "")
    (property "License" "Apache-2.0")
    (property "MPN" "CC0201KRX6S5BB104")
    (property "Manufacturer" "Yaego")
    (property "Sheetfile" "fpga-power.kicad_sch")
    (property "Sheetname" "FPGA power")
    (property "Val" "100n")
    (property "Voltage" "")
    (property "ki_description" " ")
    (attr smd)
    (fp_text reference "C251" (at -6.28 -0.36) (layer "B.SilkS")
        (effects (font (size 0.7 0.7) (thickness 0.15)) (justify left bottom mirror))
    )
    (fp_text value "C_100n_0201" (at 0 -1.4) (layer "B.Fab") hide
        (effects (font (size 0.7 0.7) (thickness 0.15)) (justify left bottom mirror))
    )
    (fp_text user "Author: Antmicro" (at -0.72 -5.4) (layer "B.Fab") hide
        (effects (font (size 0.7 0.7) (thickness 0.15)) (justify left bottom mirror))
    )
    (fp_text user "${REFERENCE}" (at -0.72 -3.4) (layer "B.Fab") hide
        (effects (font (size 0.7 0.7) (thickness 0.15)) (justify left bottom mirror))
    )
    (fp_text user "License: Apache-2.0" (at -0.72 -4.4) (layer "B.Fab") hide
        (effects (font (size 0.7 0.7) (thickness 0.15)) (justify left bottom mirror))
    )
    (fp_rect (start -0.72 0.38) (end 0.72 -0.38)
      (stroke (width 0.05) (type solid)) (fill none) (layer "B.CrtYd"))
    (fp_rect (start 0.3 -0.15) (end -0.301 0.149)
      (stroke (width 0.15) (type solid)) (fill none) (layer "B.Fab"))
    (pad "" smd roundrect (at -0.349 0.002 180) (size 0.318 0.36) (layers "B.Paste") (roundrect_rratio 0.25))
    (pad "" smd roundrect (at 0.341 0.002 180) (size 0.318 0.36) (layers "B.Paste") (roundrect_rratio 0.25))
    (pad "1" smd roundrect (at -0.321 0.002 180) (size 0.46 0.4) (layers "B.Cu" "B.Mask") (roundrect_rratio 0.25)
      (net 306 "1V2_SYS") (pintype "passive"))
    (pad "2" smd roundrect (at 0.32 0.002 180) (size 0.46 0.4) (layers "B.Cu" "B.Mask") (roundrect_rratio 0.25)
      (net 9 "GND") (pintype "passive"))
  )

  (footprint "data-center-rdimm-ddr4-tester-footprints:R_0402_1005Metric" (layer "B.Cu")
    (at 176.25 129.105 180)
    (descr "Resistor SMD 0402")
    (tags "resistor SMD 0402")
    (property "Author" "Antmicro")
    (property "DNP" "DNP")
    (property "License" "Apache-2.0")
    (property "MPN" "CR0402-FX-1002GLF")
    (property "Manufacturer" "Bourns")
    (property "Sheetfile" "ethernet.kicad_sch")
    (property "Sheetname" "Ethernet")
    (property "Tolerance" "1%")
    (property "Val" "10k")
    (property "dnp" "")
    (property "exclude_from_bom" "")
    (property "ki_description" "10k resistor in 0402 package with 1% tolerance")
    (attr exclude_from_pos_files exclude_from_bom)
    (fp_text reference "R181" (at 0.73 -0.445) (layer "B.SilkS")
        (effects (font (size 0.7 0.7) (thickness 0.15)) (justify left bottom mirror))
    )
    (fp_text value "R_10k_0402" (at 0 -1.4) (layer "B.Fab") hide
        (effects (font (size 0.7 0.7) (thickness 0.15)) (justify left bottom mirror))
    )
    (fp_text user "License: Apache-2.0" (at -0.95 -5.169) (layer "B.Fab") hide
        (effects (font (size 0.7 0.7) (thickness 0.15)) (justify left bottom mirror))
    )
    (fp_text user "Author: Antmicro" (at -0.95 -4.169) (layer "B.Fab") hide
        (effects (font (size 0.7 0.7) (thickness 0.15)) (justify left bottom mirror))
    )
    (fp_text user "${REFERENCE}" (at -0.95 -3.168) (layer "B.Fab") hide
        (effects (font (size 0.7 0.7) (thickness 0.15)) (justify left bottom mirror))
    )
    (fp_rect (start -0.93 0.47) (end 0.93 -0.47)
      (stroke (width 0.05) (type solid)) (fill none) (layer "B.CrtYd"))
    (fp_rect (start -0.5 0.25) (end 0.5 -0.25)
      (stroke (width 0.15) (type solid)) (fill none) (layer "B.Fab"))
    (pad "1" smd roundrect (at -0.485 0 180) (size 0.59 0.64) (layers "B.Cu" "B.Paste" "B.Mask") (roundrect_rratio 0.25)
      (net 622 "/Ethernet/TPL") (pintype "passive"))
    (pad "2" smd roundrect (at 0.485 0 180) (size 0.59 0.64) (layers "B.Cu" "B.Paste" "B.Mask") (roundrect_rratio 0.25)
      (net 360 "/Ethernet/VDD") (pintype "passive"))
  )

  (footprint "data-center-rdimm-ddr4-tester-footprints:C_0402_1005Metric" (layer "B.Cu")
    (at 216.087 89.607 90)
    (descr "Capacitor SMD 0402")
    (tags "capacitor SMD 0402")
    (property "Author" "Antmicro")
    (property "Dielectric" "X5R")
    (property "License" "Apache-2.0")
    (property "MPN" "GRM155R61H104KE14D")
    (property "Manufacturer" "Murata")
    (property "Sheetfile" "fpga-power.kicad_sch")
    (property "Sheetname" "FPGA power")
    (property "Val" "100n")
    (property "Voltage" "50V")
    (property "ki_description" " ")
    (attr smd)
    (fp_text reference "C314" (at 1.317 1.333 270) (layer "B.SilkS")
        (effects (font (size 0.7 0.7) (thickness 0.15)) (justify left bottom mirror))
    )
    (fp_text value "C_100n_0402" (at 0 -1.4 270) (layer "B.Fab") hide
        (effects (font (size 0.7 0.7) (thickness 0.15)) (justify left bottom mirror))
    )
    (fp_text user "${REFERENCE}" (at -0.932 -3.168 270) (layer "B.Fab") hide
        (effects (font (size 0.7 0.7) (thickness 0.15)) (justify left bottom mirror))
    )
    (fp_text user "Author: Antmicro" (at -0.932 -4.17 270) (layer "B.Fab") hide
        (effects (font (size 0.7 0.7) (thickness 0.15)) (justify left bottom mirror))
    )
    (fp_text user "License: Apache-2.0" (at -0.932 -5.17 270) (layer "B.Fab") hide
        (effects (font (size 0.7 0.7) (thickness 0.15)) (justify left bottom mirror))
    )
    (fp_rect (start -0.94 0.47) (end 0.94 -0.47)
      (stroke (width 0.05) (type solid)) (fill none) (layer "B.CrtYd"))
    (fp_rect (start -0.499 0.249) (end 0.499 -0.249)
      (stroke (width 0.15) (type solid)) (fill none) (layer "B.Fab"))
    (pad "1" smd roundrect (at -0.484 0 90) (size 0.59 0.64) (layers "B.Cu" "B.Paste" "B.Mask") (roundrect_rratio 0.25)
      (net 306 "1V2_SYS") (pintype "passive"))
    (pad "2" smd roundrect (at 0.484 0 90) (size 0.59 0.64) (layers "B.Cu" "B.Paste" "B.Mask") (roundrect_rratio 0.25)
      (net 9 "GND") (pintype "passive"))
  )

  (footprint "data-center-rdimm-ddr4-tester-footprints:R_0603_1608Metric" (layer "B.Cu")
    (at 189.26 84.89 180)
    (descr "Resistor SMD 0603")
    (tags "resistor SMD 0603")
    (property "Author" "Antmicro")
    (property "License" "Apache-2.0")
    (property "MPN" "CR0603-FX-80R6ELF")
    (property "Manufacturer" "Bourns")
    (property "Sheetfile" "fpga-banks-16-34.kicad_sch")
    (property "Sheetname" "FPGA banks 16-34")
    (property "Tolerance" "1%")
    (property "Val" "80R6")
    (property "ki_description" "80R6 resistor in 0603 package with 1% tolerance")
    (attr smd)
    (fp_text reference "R63" (at 0.98 -0.23) (layer "B.SilkS")
        (effects (font (size 0.7 0.7) (thickness 0.15)) (justify left bottom mirror))
    )
    (fp_text value "R_80R6_0603" (at 0 -1.6) (layer "B.Fab") hide
        (effects (font (size 0.7 0.7) (thickness 0.15)) (justify left bottom mirror))
    )
    (fp_text user "Author: Antmicro" (at -1.25 -4.9) (layer "B.Fab") hide
        (effects (font (size 0.7 0.7) (thickness 0.15)) (justify left bottom mirror))
    )
    (fp_text user "License: Apache-2.0" (at -1.25 -5.9) (layer "B.Fab") hide
        (effects (font (size 0.7 0.7) (thickness 0.15)) (justify left bottom mirror))
    )
    (fp_text user "${REFERENCE}" (at -1.25 -3.898) (layer "B.Fab") hide
        (effects (font (size 0.7 0.7) (thickness 0.15)) (justify left bottom mirror))
    )
    (fp_line (start -0.3 -0.3) (end 0.3 -0.3)
      (stroke (width 0.15) (type solid)) (layer "B.SilkS"))
    (fp_line (start -0.3 0.3) (end 0.3 0.3)
      (stroke (width 0.15) (type solid)) (layer "B.SilkS"))
    (fp_rect (start -1.25 0.7) (end 1.25 -0.7)
      (stroke (width 0.05) (type solid)) (fill none) (layer "B.CrtYd"))
    (fp_rect (start -0.8 0.4) (end 0.8 -0.4)
      (stroke (width 0.15) (type solid)) (fill none) (layer "B.Fab"))
    (pad "1" smd roundrect (at -0.7 0 180) (size 0.6 0.8) (layers "B.Cu" "B.Paste" "B.Mask") (roundrect_rratio 0.2)
      (net 309 "VRN") (pintype "passive"))
    (pad "2" smd roundrect (at 0.7 0 180) (size 0.6 0.8) (layers "B.Cu" "B.Paste" "B.Mask") (roundrect_rratio 0.2)
      (net 77 "VDDQ") (pintype "passive"))
  )

  (footprint "data-center-rdimm-ddr4-tester-footprints:VQFN-20_5x5x1mm_P0.65mm" (layer "B.Cu")
    (at 181.01 128.61 -90)
    (property "Author" "Antmicro")
    (property "License" "Apache-2.0")
    (property "MPN" "TPS2372-3RGWR")
    (property "Manufacturer" "Texas Instruments")
    (property "Sheetfile" "ethernet.kicad_sch")
    (property "Sheetname" "Ethernet")
    (property "ki_description" "IEEE 802.3bt PoE high-power PD interface with automatic MPS & autoclass")
    (property "ki_keywords" "IEEE 802.3bt PoE high-power PD interface with automatic MPS & autoclass")
    (attr smd)
    (fp_text reference "U13" (at 2.91 2.48 180) (layer "B.SilkS")
        (effects (font (size 0.7 0.7) (thickness 0.15)) (justify left bottom mirror))
    )
    (fp_text value "TPS2372-3RGWR" (at 0 -3.883 90) (layer "B.Fab") hide
        (effects (font (size 0.7 0.7) (thickness 0.15)) (justify left bottom mirror))
    )
    (fp_text user "License: Apache-2.0" (at -2.5 -7.884 90) (layer "B.Fab") hide
        (effects (font (size 0.7 0.7) (thickness 0.15)) (justify left bottom mirror))
    )
    (fp_text user "Author: Antmicro" (at -2.5 -6.884 90) (layer "B.Fab") hide
        (effects (font (size 0.7 0.7) (thickness 0.15)) (justify left bottom mirror))
    )
    (fp_text user "${REFERENCE}" (at -2.5 -5.884 90) (layer "B.Fab") hide
        (effects (font (size 0.7 0.7) (thickness 0.15)) (justify left bottom mirror))
    )
    (fp_poly
      (pts
        (xy -1.081 -0.088)
        (xy -0.11 -0.088)
        (xy -0.11 -1.08)
        (xy -1.081 -1.08)
      )

      (stroke (width 0.01) (type solid)) (fill solid) (layer "B.Paste"))
    (fp_poly
      (pts
        (xy -1.081 1.081)
        (xy -0.11 1.081)
        (xy -0.11 0.09)
        (xy -1.081 0.09)
      )

      (stroke (width 0.01) (type solid)) (fill solid) (layer "B.Paste"))
    (fp_poly
      (pts
        (xy 0.108 -0.088)
        (xy 1.08 -0.088)
        (xy 1.08 -1.08)
        (xy 0.108 -1.08)
      )

      (stroke (width 0.01) (type solid)) (fill solid) (layer "B.Paste"))
    (fp_poly
      (pts
        (xy 0.108 1.081)
        (xy 1.08 1.081)
        (xy 1.08 0.09)
        (xy 0.108 0.09)
      )

      (stroke (width 0.01) (type solid)) (fill solid) (layer "B.Paste"))
    (fp_line (start -2.5 -2.499) (end -2.5 -1.789)
      (stroke (width 0.15) (type solid)) (layer "B.SilkS"))
    (fp_line (start -2.5 -2.499) (end -1.79 -2.499)
      (stroke (width 0.15) (type solid)) (layer "B.SilkS"))
    (fp_line (start -1.625 2.5) (end -2.5 2.5)
      (stroke (width 0.15) (type solid)) (layer "B.SilkS"))
    (fp_line (start 2.499 -2.499) (end 1.789 -2.499)
      (stroke (width 0.15) (type solid)) (layer "B.SilkS"))
    (fp_line (start 2.499 -2.499) (end 2.499 -1.789)
      (stroke (width 0.15) (type solid)) (layer "B.SilkS"))
    (fp_line (start 2.499 2.5) (end 1.789 2.5)
      (stroke (width 0.15) (type solid)) (layer "B.SilkS"))
    (fp_line (start 2.499 2.5) (end 2.499 1.79)
      (stroke (width 0.15) (type solid)) (layer "B.SilkS"))
    (fp_circle (center -2.775 1.875) (end -2.725 1.825)
      (stroke (width 0.15) (type solid)) (fill solid) (layer "B.SilkS"))
    (fp_rect (start -2.95 2.95) (end 2.95 -2.95)
      (stroke (width 0.05) (type solid)) (fill none) (layer "B.CrtYd"))
    (fp_line (start -2.5 -2.499) (end -2.5 1.65)
      (stroke (width 0.15) (type solid)) (layer "B.Fab"))
    (fp_line (start -2.5 1.65) (end -1.65 2.5)
      (stroke (width 0.15) (type solid)) (layer "B.Fab"))
    (fp_line (start 2.499 -2.499) (end -2.5 -2.499)
      (stroke (width 0.15) (type solid)) (layer "B.Fab"))
    (fp_line (start 2.499 -2.499) (end 2.499 2.5)
      (stroke (width 0.15) (type solid)) (layer "B.Fab"))
    (fp_line (start 2.499 2.5) (end -1.65 2.5)
      (stroke (width 0.15) (type solid)) (layer "B.Fab"))
    (pad "1" smd roundrect (at -2.327 1.301 270) (size 0.75 0.31) (layers "B.Cu" "B.Paste" "B.Mask") (roundrect_rratio 0.25)
      (net 360 "/Ethernet/VDD") (pinfunction "VDD") (pintype "power_in"))
    (pad "2" smd roundrect (at -2.327 0.652 270) (size 0.75 0.31) (layers "B.Cu" "B.Paste" "B.Mask") (roundrect_rratio 0.25)
      (net 610 "/Ethernet/DEN") (pinfunction "DEN") (pintype "input"))
    (pad "3" smd roundrect (at -2.327 0 270) (size 0.75 0.31) (layers "B.Cu" "B.Paste" "B.Mask") (roundrect_rratio 0.25)
      (net 611 "/Ethernet/CLSA") (pinfunction "CLSA") (pintype "input"))
    (pad "4" smd roundrect (at -2.327 -0.65 270) (size 0.75 0.31) (layers "B.Cu" "B.Paste" "B.Mask") (roundrect_rratio 0.25)
      (net 381 "/Ethernet/VSS") (pinfunction "VSSA") (pintype "power_in"))
    (pad "5" smd roundrect (at -2.327 -1.3 270) (size 0.75 0.31) (layers "B.Cu" "B.Paste" "B.Mask") (roundrect_rratio 0.25)
      (net 381 "/Ethernet/VSS") (pinfunction "VSSB") (pintype "power_in"))
    (pad "6" smd roundrect (at -1.301 -2.325 270) (size 0.31 0.75) (layers "B.Cu" "B.Paste" "B.Mask") (roundrect_rratio 0.25)
      (net 618 "/Ethernet/CLSB") (pinfunction "CLSB") (pintype "input"))
    (pad "7" smd roundrect (at -0.652 -2.325 270) (size 0.31 0.75) (layers "B.Cu" "B.Paste" "B.Mask") (roundrect_rratio 0.25)
      (net 617 "/Ethernet/REF") (pinfunction "REF") (pintype "input"))
    (pad "8" smd roundrect (at 0 -2.325 270) (size 0.31 0.75) (layers "B.Cu" "B.Paste" "B.Mask") (roundrect_rratio 0.25)
      (net 612 "/Ethernet/AMPS_CTL") (pinfunction "AMPS_CTL") (pintype "input"))
    (pad "9" smd roundrect (at 0.65 -2.325 270) (size 0.31 0.75) (layers "B.Cu" "B.Paste" "B.Mask") (roundrect_rratio 0.25)
      (net 629 "/Ethernet/MPS_DUTY") (pinfunction "MPS_DUTY") (pintype "input"))
    (pad "10" smd roundrect (at 1.3 -2.325 270) (size 0.31 0.75) (layers "B.Cu" "B.Paste" "B.Mask") (roundrect_rratio 0.25)
      (net 701 "unconnected-(U13-~{AUTCLS}-Pad10)") (pinfunction "~{AUTCLS}") (pintype "input+no_connect"))
    (pad "11" smd roundrect (at 2.325 -1.3 270) (size 0.75 0.31) (layers "B.Cu" "B.Paste" "B.Mask") (roundrect_rratio 0.25)
      (net 604 "GNDD") (pinfunction "RTNA") (pintype "output"))
    (pad "12" smd roundrect (at 2.325 -0.65 270) (size 0.75 0.31) (layers "B.Cu" "B.Paste" "B.Mask") (roundrect_rratio 0.25)
      (net 604 "GNDD") (pinfunction "RTNB") (pintype "output"))
    (pad "13" smd roundrect (at 2.325 0 270) (size 0.75 0.31) (layers "B.Cu" "B.Paste" "B.Mask") (roundrect_rratio 0.25)
      (net 620 "/Ethernet/PG") (pinfunction "PG") (pintype "output"))
    (pad "14" smd roundrect (at 2.325 0.652 270) (size 0.75 0.31) (layers "B.Cu" "B.Paste" "B.Mask") (roundrect_rratio 0.25)
      (net 702 "unconnected-(U13-NC-Pad14)") (pinfunction "NC") (pintype "no_connect"))
    (pad "15" smd roundrect (at 2.325 1.301 270) (size 0.75 0.31) (layers "B.Cu" "B.Paste" "B.Mask") (roundrect_rratio 0.25)
      (net 703 "unconnected-(U13-NC-Pad15)") (pinfunction "NC") (pintype "no_connect"))
    (pad "16" smd roundrect (at 1.3 2.327 270) (size 0.31 0.75) (layers "B.Cu" "B.Paste" "B.Mask") (roundrect_rratio 0.25)
      (net 621 "/Ethernet/IRSHDL_EN") (pinfunction "IRSHDL_EN") (pintype "output"))
    (pad "17" smd roundrect (at 0.65 2.327 270) (size 0.31 0.75) (layers "B.Cu" "B.Paste" "B.Mask") (roundrect_rratio 0.25)
      (net 622 "/Ethernet/TPL") (pinfunction "TPL") (pintype "output"))
    (pad "18" smd roundrect (at 0 2.327 270) (size 0.31 0.75) (layers "B.Cu" "B.Paste" "B.Mask") (roundrect_rratio 0.25)
      (net 619 "/Ethernet/TPH") (pinfunction "TPH") (pintype "output"))
    (pad "19" smd roundrect (at -0.652 2.327 270) (size 0.31 0.75) (layers "B.Cu" "B.Paste" "B.Mask") (roundrect_rratio 0.25)
      (net 659 "Net-(U13-~{BT})") (pinfunction "~{BT}") (pintype "output"))
    (pad "20" smd roundrect (at -1.301 2.327 270) (size 0.31 0.75) (layers "B.Cu" "B.Paste" "B.Mask") (roundrect_rratio 0.25)
      (net 704 "unconnected-(U13-NC-Pad20)") (pinfunction "NC") (pintype "no_connect"))
    (pad "21" smd rect (at 0 0 270) (size 2.2 2.2) (layers "B.Cu" "B.Mask")
      (net 381 "/Ethernet/VSS") (pinfunction "PAD_VSSC") (pintype "power_in"))
  )

  (footprint "data-center-rdimm-ddr4-tester-footprints:R_0402_1005Metric" (layer "B.Cu")
    (at 226.25 122.85 -90)
    (descr "Resistor SMD 0402")
    (tags "resistor SMD 0402")
    (property "Author" "Antmicro")
    (property "Current" "1A")
    (property "DNP" "DNP")
    (property "License" "Apache-2.0")
    (property "MPN" "ERJ2GE0R00X")
    (property "Manufacturer" "Panasonic")
    (property "Sheetfile" "supply.kicad_sch")
    (property "Sheetname" "Supply")
    (property "Tolerance" "")
    (property "Val" "0R")
    (property "dnp" "")
    (property "exclude_from_bom" "")
    (property "ki_description" "0R resistor in 0402 package with unspecified tolerance")
    (attr exclude_from_pos_files exclude_from_bom)
    (fp_text reference "R219" (at -1.4 0.56 90) (layer "B.SilkS")
        (effects (font (size 0.7 0.7) (thickness 0.15)) (justify left bottom mirror))
    )
    (fp_text value "R_0R_0402" (at 0 -1.4 90) (layer "B.Fab") hide
        (effects (font (size 0.7 0.7) (thickness 0.15)) (justify left bottom mirror))
    )
    (fp_text user "License: Apache-2.0" (at -0.95 -5.169 90) (layer "B.Fab") hide
        (effects (font (size 0.7 0.7) (thickness 0.15)) (justify left bottom mirror))
    )
    (fp_text user "Author: Antmicro" (at -0.95 -4.169 90) (layer "B.Fab") hide
        (effects (font (size 0.7 0.7) (thickness 0.15)) (justify left bottom mirror))
    )
    (fp_text user "${REFERENCE}" (at -0.95 -3.168 90) (layer "B.Fab") hide
        (effects (font (size 0.7 0.7) (thickness 0.15)) (justify left bottom mirror))
    )
    (fp_rect (start -0.93 0.47) (end 0.93 -0.47)
      (stroke (width 0.05) (type solid)) (fill none) (layer "B.CrtYd"))
    (fp_rect (start -0.5 0.25) (end 0.5 -0.25)
      (stroke (width 0.15) (type solid)) (fill none) (layer "B.Fab"))
    (pad "1" smd roundrect (at -0.485 0 270) (size 0.59 0.64) (layers "B.Cu" "B.Paste" "B.Mask") (roundrect_rratio 0.25)
      (net 119 "/Supply/~{INT}") (pintype "passive"))
    (pad "2" smd roundrect (at 0.485 0 270) (size 0.59 0.64) (layers "B.Cu" "B.Paste" "B.Mask") (roundrect_rratio 0.25)
      (net 860 "/Supply/~{CLR}") (pintype "passive"))
  )

  (footprint "data-center-rdimm-ddr4-tester-footprints:C_0201" (layer "B.Cu")
    (at 173.225 91.225 -90)
    (descr "Capacitor SMD 0201")
    (tags "capacitor SMD 0201")
    (property "Author" "Antmicro")
    (property "Dielectric" "")
    (property "License" "Apache-2.0")
    (property "MPN" "CC0201KRX6S5BB104")
    (property "Manufacturer" "Yaego")
    (property "Sheetfile" "fpga-power.kicad_sch")
    (property "Sheetname" "FPGA power")
    (property "Val" "100n")
    (property "Voltage" "")
    (property "ki_description" " ")
    (attr smd)
    (fp_text reference "C279" (at -1.505 0.525 90) (layer "B.SilkS")
        (effects (font (size 0.7 0.7) (thickness 0.15)) (justify left bottom mirror))
    )
    (fp_text value "C_100n_0201" (at 0 -1.4 90) (layer "B.Fab") hide
        (effects (font (size 0.7 0.7) (thickness 0.15)) (justify left bottom mirror))
    )
    (fp_text user "Author: Antmicro" (at -0.72 -5.4 90) (layer "B.Fab") hide
        (effects (font (size 0.7 0.7) (thickness 0.15)) (justify left bottom mirror))
    )
    (fp_text user "License: Apache-2.0" (at -0.72 -4.4 90) (layer "B.Fab") hide
        (effects (font (size 0.7 0.7) (thickness 0.15)) (justify left bottom mirror))
    )
    (fp_text user "${REFERENCE}" (at -0.72 -3.4 90) (layer "B.Fab") hide
        (effects (font (size 0.7 0.7) (thickness 0.15)) (justify left bottom mirror))
    )
    (fp_rect (start -0.72 0.38) (end 0.72 -0.38)
      (stroke (width 0.05) (type solid)) (fill none) (layer "B.CrtYd"))
    (fp_rect (start 0.3 -0.15) (end -0.301 0.149)
      (stroke (width 0.15) (type solid)) (fill none) (layer "B.Fab"))
    (pad "" smd roundrect (at -0.349 0.002 270) (size 0.318 0.36) (layers "B.Paste") (roundrect_rratio 0.25))
    (pad "" smd roundrect (at 0.341 0.002 270) (size 0.318 0.36) (layers "B.Paste") (roundrect_rratio 0.25))
    (pad "1" smd roundrect (at -0.321 0.002 270) (size 0.46 0.4) (layers "B.Cu" "B.Mask") (roundrect_rratio 0.25)
      (net 77 "VDDQ") (pintype "passive"))
    (pad "2" smd roundrect (at 0.32 0.002 270) (size 0.46 0.4) (layers "B.Cu" "B.Mask") (roundrect_rratio 0.25)
      (net 9 "GND") (pintype "passive"))
  )

  (footprint "data-center-rdimm-ddr4-tester-footprints:DFN3538" (layer "B.Cu")
    (at 182.71 119.7 90)
    (property "Author" "Antmicro")
    (property "License" "Apache-2.0")
    (property "MPN" "CD-MMBL110S")
    (property "Manufacturer" "Bourns")
    (property "Sheetfile" "ethernet.kicad_sch")
    (property "Sheetname" "Ethernet")
    (property "ki_description" "Bridge Rectifiers 1000V 1A MMBL DFN3538")
    (attr smd)
    (fp_text reference "D12" (at 2.21 1.03 unlocked) (layer "B.SilkS")
        (effects (font (size 0.7 0.7) (thickness 0.15)) (justify left bottom mirror))
    )
    (fp_text value "CD-MMBL110S" (at 0 -3.5 270 unlocked) (layer "B.Fab") hide
        (effects (font (size 0.7 0.7) (thickness 0.15)) (justify left bottom mirror))
    )
    (fp_text user "~" (at -0.31 -2.59 270 unlocked) (layer "B.SilkS")
        (effects (font (size 0.7 0.7) (thickness 0.15)) (justify left bottom mirror))
    )
    (fp_text user "Author: Antmicro" (at -2.1 -5.599 270) (layer "B.Fab") hide
        (effects (font (size 0.7 0.7) (thickness 0.15)) (justify left bottom mirror))
    )
    (fp_text user "${REFERENCE}" (at -2.1 -4.599 270) (layer "B.Fab") hide
        (effects (font (size 0.7 0.7) (thickness 0.15)) (justify left bottom mirror))
    )
    (fp_text user "License: Apache-2.0" (at -2.1 -6.599 270) (layer "B.Fab") hide
        (effects (font (size 0.7 0.7) (thickness 0.15)) (justify left bottom mirror))
    )
    (fp_line (start -1.8 -2.05) (end -1.6 -2.05)
      (stroke (width 0.15) (type solid)) (layer "B.SilkS"))
    (fp_line (start -1.8 1.5) (end -1.8 -2.05)
      (stroke (width 0.15) (type solid)) (layer "B.SilkS"))
    (fp_line (start -0.95 -2.05) (end 0.95 -2.05)
      (stroke (width 0.15) (type solid)) (layer "B.SilkS"))
    (fp_line (start -0.95 2) (end 0.95 2)
      (stroke (width 0.15) (type solid)) (layer "B.SilkS"))
    (fp_line (start -0.902 2.25) (end -0.6 2.25)
      (stroke (width 0.15) (type solid)) (layer "B.SilkS"))
    (fp_line (start 0.748 2.452) (end 0.748 2.15)
      (stroke (width 0.15) (type solid)) (layer "B.SilkS"))
    (fp_line (start 0.9 2.301) (end 0.598 2.301)
      (stroke (width 0.15) (type solid)) (layer "B.SilkS"))
    (fp_line (start 1.6 -2.05) (end 1.8 -2.05)
      (stroke (width 0.15) (type solid)) (layer "B.SilkS"))
    (fp_line (start 1.6 2) (end 1.8 2)
      (stroke (width 0.15) (type solid)) (layer "B.SilkS"))
    (fp_line (start 1.8 2) (end 1.8 -2.05)
      (stroke (width 0.15) (type solid)) (layer "B.SilkS"))
    (fp_rect (start -2.1 2.6) (end 2.1 -2.6)
      (stroke (width 0.05) (type solid)) (fill none) (layer "B.CrtYd"))
    (fp_line (start -1.051 2) (end -1.801 1.25)
      (stroke (width 0.15) (type solid)) (layer "B.Fab"))
    (fp_rect (start 1.8 -2.048) (end -1.8 2)
      (stroke (width 0.15) (type solid)) (fill none) (layer "B.Fab"))
    (pad "1" smd roundrect (at -1.27 1.85) (size 1.4 0.48) (layers "B.Cu" "B.Paste" "B.Mask") (roundrect_rratio 0.25)
      (net 807 "/Ethernet/VSS_RAW") (pinfunction "1") (pintype "output"))
    (pad "2" smd roundrect (at 1.27 1.85) (size 1.4 0.48) (layers "B.Cu" "B.Paste" "B.Mask") (roundrect_rratio 0.25)
      (net 808 "/Ethernet/VDD_RAW") (pinfunction "2") (pintype "output"))
    (pad "3" smd roundrect (at -1.27 -1.85) (size 1.4 0.48) (layers "B.Cu" "B.Paste" "B.Mask") (roundrect_rratio 0.25)
      (net 606 "/Ethernet/PAIR_36") (pinfunction "3") (pintype "input"))
    (pad "4" smd roundrect (at 1.27 -1.85) (size 1.4 0.48) (layers "B.Cu" "B.Paste" "B.Mask") (roundrect_rratio 0.25)
      (net 605 "/Ethernet/PAIR_12") (pinfunction "4") (pintype "input"))
  )

  (footprint "data-center-rdimm-ddr4-tester-footprints:R_0402_1005Metric" (layer "B.Cu")
    (at 131.425 103.65 90)
    (descr "Resistor SMD 0402")
    (tags "resistor SMD 0402")
    (property "Author" "Antmicro")
    (property "License" "Apache-2.0")
    (property "MPN" "CR0402-FX-1002GLF")
    (property "Manufacturer" "Bourns")
    (property "Sheetfile" "supply.kicad_sch")
    (property "Sheetname" "Supply")
    (property "Tolerance" "1%")
    (property "Val" "10k")
    (property "ki_description" "10k resistor in 0402 package with 1% tolerance")
    (attr smd)
    (fp_text reference "R213" (at 1.75 1.255 270) (layer "B.SilkS")
        (effects (font (size 0.7 0.7) (thickness 0.15)) (justify left bottom mirror))
    )
    (fp_text value "R_10k_0402" (at 0 -1.4 270) (layer "B.Fab") hide
        (effects (font (size 0.7 0.7) (thickness 0.15)) (justify left bottom mirror))
    )
    (fp_text user "${REFERENCE}" (at -0.95 -3.168 270) (layer "B.Fab") hide
        (effects (font (size 0.7 0.7) (thickness 0.15)) (justify left bottom mirror))
    )
    (fp_text user "Author: Antmicro" (at -0.95 -4.169 270) (layer "B.Fab") hide
        (effects (font (size 0.7 0.7) (thickness 0.15)) (justify left bottom mirror))
    )
    (fp_text user "License: Apache-2.0" (at -0.95 -5.169 270) (layer "B.Fab") hide
        (effects (font (size 0.7 0.7) (thickness 0.15)) (justify left bottom mirror))
    )
    (fp_rect (start -0.93 0.47) (end 0.93 -0.47)
      (stroke (width 0.05) (type solid)) (fill none) (layer "B.CrtYd"))
    (fp_rect (start -0.5 0.25) (end 0.5 -0.25)
      (stroke (width 0.15) (type solid)) (fill none) (layer "B.Fab"))
    (pad "1" smd roundrect (at -0.485 0 90) (size 0.59 0.64) (layers "B.Cu" "B.Paste" "B.Mask") (roundrect_rratio 0.25)
      (net 790 "/Supply/PWR_SEQ_EN") (pintype "passive"))
    (pad "2" smd roundrect (at 0.485 0 90) (size 0.59 0.64) (layers "B.Cu" "B.Paste" "B.Mask") (roundrect_rratio 0.25)
      (net 9 "GND") (pintype "passive"))
  )

  (footprint "data-center-rdimm-ddr4-tester-footprints:R_0402_1005Metric" (layer "B.Cu")
    (at 228.55 122)
    (descr "Resistor SMD 0402")
    (tags "resistor SMD 0402")
    (property "Author" "Antmicro")
    (property "License" "Apache-2.0")
    (property "MPN" "CR0402-FX-1002GLF")
    (property "Manufacturer" "Bourns")
    (property "Sheetfile" "supply.kicad_sch")
    (property "Sheetname" "Supply")
    (property "Tolerance" "1%")
    (property "Val" "10k")
    (property "ki_description" "10k resistor in 0402 package with 1% tolerance")
    (attr smd)
    (fp_text reference "R218" (at 1.5 -1.52 180) (layer "B.SilkS")
        (effects (font (size 0.7 0.7) (thickness 0.15)) (justify left bottom mirror))
    )
    (fp_text value "R_10k_0402" (at 0 -1.4 180) (layer "B.Fab") hide
        (effects (font (size 0.7 0.7) (thickness 0.15)) (justify left bottom mirror))
    )
    (fp_text user "Author: Antmicro" (at -0.95 -4.169 180) (layer "B.Fab") hide
        (effects (font (size 0.7 0.7) (thickness 0.15)) (justify left bottom mirror))
    )
    (fp_text user "License: Apache-2.0" (at -0.95 -5.169 180) (layer "B.Fab") hide
        (effects (font (size 0.7 0.7) (thickness 0.15)) (justify left bottom mirror))
    )
    (fp_text user "${REFERENCE}" (at -0.95 -3.168 180) (layer "B.Fab") hide
        (effects (font (size 0.7 0.7) (thickness 0.15)) (justify left bottom mirror))
    )
    (fp_rect (start -0.93 0.47) (end 0.93 -0.47)
      (stroke (width 0.05) (type solid)) (fill none) (layer "B.CrtYd"))
    (fp_rect (start -0.5 0.25) (end 0.5 -0.25)
      (stroke (width 0.15) (type solid)) (fill none) (layer "B.Fab"))
    (pad "1" smd roundrect (at -0.485 0) (size 0.59 0.64) (layers "B.Cu" "B.Paste" "B.Mask") (roundrect_rratio 0.25)
      (net 119 "/Supply/~{INT}") (pintype "passive"))
    (pad "2" smd roundrect (at 0.485 0) (size 0.59 0.64) (layers "B.Cu" "B.Paste" "B.Mask") (roundrect_rratio 0.25)
      (net 859 "/Supply/OUT") (pintype "passive"))
  )

  (footprint "data-center-rdimm-ddr4-tester-footprints:SOT-753" (layer "B.Cu")
    (at 120.16 96.84)
    (property "Author" "Antmicro")
    (property "License" "Apache-2.0")
    (property "MPN" "SN74AHCT1G125DBVR")
    (property "Manufacturer" "Texas Instruments")
    (property "Sheetfile" "supply.kicad_sch")
    (property "Sheetname" "Supply")
    (attr smd)
    (fp_text reference "U23" (at -1.65 0.78 180) (layer "B.SilkS")
        (effects (font (size 0.7 0.7) (thickness 0.15)) (justify left bottom mirror))
    )
    (fp_text value "SN74AHCT1G125_SOT" (at 0 -2.9 180) (layer "B.Fab") hide
        (effects (font (size 0.7 0.7) (thickness 0.15)) (justify left bottom mirror))
    )
    (fp_text user "License: Apache-2.0" (at -1.651 -8.425 180) (layer "B.Fab") hide
        (effects (font (size 0.7 0.7) (thickness 0.15)) (justify left bottom mirror))
    )
    (fp_text user "${REFERENCE}" (at -1.651 -6.025 180) (layer "B.Fab") hide
        (effects (font (size 0.7 0.7) (thickness 0.15)) (justify left bottom mirror))
    )
    (fp_text user "Author: Antmicro" (at -1.651 -7.225 180) (layer "B.Fab") hide
        (effects (font (size 0.7 0.7) (thickness 0.15)) (justify left bottom mirror))
    )
    (fp_line (start -1.651 1) (end -1.651 0.701)
      (stroke (width 0.15) (type solid)) (layer "B.SilkS"))
    (fp_line (start -1.648 -1) (end -1.648 -0.677)
      (stroke (width 0.15) (type solid)) (layer "B.SilkS"))
    (fp_line (start -1.5 -1) (end -1.648 -1)
      (stroke (width 0.15) (type solid)) (layer "B.SilkS"))
    (fp_line (start -1.5 1) (end -1.651 1)
      (stroke (width 0.15) (type solid)) (layer "B.SilkS"))
    (fp_line (start 1.5 -0.998) (end 1.648 -0.998)
      (stroke (width 0.15) (type solid)) (layer "B.SilkS"))
    (fp_line (start 1.5 1) (end 1.648 1)
      (stroke (width 0.15) (type solid)) (layer "B.SilkS"))
    (fp_line (start 1.648 -0.998) (end 1.648 -0.699)
      (stroke (width 0.15) (type solid)) (layer "B.SilkS"))
    (fp_line (start 1.648 1) (end 1.648 0.677)
      (stroke (width 0.15) (type solid)) (layer "B.SilkS"))
    (fp_circle (center -1.5 -1.35) (end -1.46 -1.4)
      (stroke (width 0.15) (type solid)) (fill solid) (layer "B.SilkS"))
    (fp_rect (start -1.7 1.901) (end 1.699 -1.898)
      (stroke (width 0.05) (type solid)) (fill none) (layer "B.CrtYd"))
    (fp_line (start -1.526 -0.623) (end -1.526 0.875)
      (stroke (width 0.15) (type solid)) (layer "B.Fab"))
    (fp_line (start -1.526 -0.623) (end -1.351 -0.873)
      (stroke (width 0.15) (type solid)) (layer "B.Fab"))
    (fp_line (start -1.526 0.875) (end 1.523 0.875)
      (stroke (width 0.15) (type solid)) (layer "B.Fab"))
    (fp_line (start -1.351 -0.873) (end 1.523 -0.873)
      (stroke (width 0.15) (type solid)) (layer "B.Fab"))
    (fp_line (start 1.523 0.875) (end 1.523 -0.873)
      (stroke (width 0.15) (type solid)) (layer "B.Fab"))
    (pad "1" smd roundrect (at -0.951 -1.35) (size 0.6 1.05) (layers "B.Cu" "B.Paste" "B.Mask") (roundrect_rratio 0.25)
      (net 799 "FPGA_SLP_S4") (pinfunction "~{OE}") (pintype "input"))
    (pad "2" smd roundrect (at 0 -1.35) (size 0.6 1.05) (layers "B.Cu" "B.Paste" "B.Mask") (roundrect_rratio 0.25)
      (net 152 "/Supply/VCC_AUX_EN") (pinfunction "A") (pintype "input"))
    (pad "3" smd roundrect (at 0.949 -1.35) (size 0.6 1.05) (layers "B.Cu" "B.Paste" "B.Mask") (roundrect_rratio 0.25)
      (net 9 "GND") (pinfunction "GND") (pintype "power_in"))
    (pad "4" smd roundrect (at 0.949 1.351) (size 0.6 1.05) (layers "B.Cu" "B.Paste" "B.Mask") (roundrect_rratio 0.25)
      (net 794 "/Supply/SLP_S4") (pinfunction "Y") (pintype "output"))
    (pad "5" smd roundrect (at -0.951 1.351) (size 0.6 1.05) (layers "B.Cu" "B.Paste" "B.Mask") (roundrect_rratio 0.25)
      (net 307 "5V0_SYS") (pinfunction "V_{CC}") (pintype "power_in"))
  )

  (footprint "data-center-rdimm-ddr4-tester-footprints:C_0201" (layer "B.Cu")
    (at 173.65 94.65)
    (descr "Capacitor SMD 0201")
    (tags "capacitor SMD 0201")
    (property "Author" "Antmicro")
    (property "Dielectric" "")
    (property "License" "Apache-2.0")
    (property "MPN" "CC0201KRX6S5BB104")
    (property "Manufacturer" "Yaego")
    (property "Sheetfile" "fpga-power.kicad_sch")
    (property "Sheetname" "FPGA power")
    (property "Val" "100n")
    (property "Voltage" "")
    (property "ki_description" " ")
    (attr smd)
    (fp_text reference "C294" (at 1.36 1.1 180) (layer "B.SilkS")
        (effects (font (size 0.7 0.7) (thickness 0.15)) (justify left bottom mirror))
    )
    (fp_text value "C_100n_0201" (at 0 -1.4 180) (layer "B.Fab") hide
        (effects (font (size 0.7 0.7) (thickness 0.15)) (justify left bottom mirror))
    )
    (fp_text user "Author: Antmicro" (at -0.72 -5.4 180) (layer "B.Fab") hide
        (effects (font (size 0.7 0.7) (thickness 0.15)) (justify left bottom mirror))
    )
    (fp_text user "License: Apache-2.0" (at -0.72 -4.4 180) (layer "B.Fab") hide
        (effects (font (size 0.7 0.7) (thickness 0.15)) (justify left bottom mirror))
    )
    (fp_text user "${REFERENCE}" (at -0.72 -3.4 180) (layer "B.Fab") hide
        (effects (font (size 0.7 0.7) (thickness 0.15)) (justify left bottom mirror))
    )
    (fp_rect (start -0.72 0.38) (end 0.72 -0.38)
      (stroke (width 0.05) (type solid)) (fill none) (layer "B.CrtYd"))
    (fp_rect (start 0.3 -0.15) (end -0.301 0.149)
      (stroke (width 0.15) (type solid)) (fill none) (layer "B.Fab"))
    (pad "" smd roundrect (at -0.349 0.002) (size 0.318 0.36) (layers "B.Paste") (roundrect_rratio 0.25))
    (pad "" smd roundrect (at 0.341 0.002) (size 0.318 0.36) (layers "B.Paste") (roundrect_rratio 0.25))
    (pad "1" smd roundrect (at -0.321 0.002) (size 0.46 0.4) (layers "B.Cu" "B.Mask") (roundrect_rratio 0.25)
      (net 77 "VDDQ") (pintype "passive"))
    (pad "2" smd roundrect (at 0.32 0.002) (size 0.46 0.4) (layers "B.Cu" "B.Mask") (roundrect_rratio 0.25)
      (net 9 "GND") (pintype "passive"))
  )

  (footprint "data-center-rdimm-ddr4-tester-footprints:C_0201" (layer "B.Cu")
    (at 174.65 102.6 180)
    (descr "Capacitor SMD 0201")
    (tags "capacitor SMD 0201")
    (property "Author" "Antmicro")
    (property "Dielectric" "")
    (property "License" "Apache-2.0")
    (property "MPN" "CC0201KRX6S5BB104")
    (property "Manufacturer" "Yaego")
    (property "Sheetfile" "fpga-power.kicad_sch")
    (property "Sheetname" "FPGA power")
    (property "Val" "100n")
    (property "Voltage" "")
    (property "ki_description" " ")
    (attr smd)
    (fp_text reference "C84" (at -1.06 0.5) (layer "B.SilkS")
        (effects (font (size 0.7 0.7) (thickness 0.15)) (justify left bottom mirror))
    )
    (fp_text value "C_100n_0201" (at 0 -1.4) (layer "B.Fab") hide
        (effects (font (size 0.7 0.7) (thickness 0.15)) (justify left bottom mirror))
    )
    (fp_text user "${REFERENCE}" (at -0.72 -3.4) (layer "B.Fab") hide
        (effects (font (size 0.7 0.7) (thickness 0.15)) (justify left bottom mirror))
    )
    (fp_text user "License: Apache-2.0" (at -0.72 -4.4) (layer "B.Fab") hide
        (effects (font (size 0.7 0.7) (thickness 0.15)) (justify left bottom mirror))
    )
    (fp_text user "Author: Antmicro" (at -0.72 -5.4) (layer "B.Fab") hide
        (effects (font (size 0.7 0.7) (thickness 0.15)) (justify left bottom mirror))
    )
    (fp_rect (start -0.72 0.38) (end 0.72 -0.38)
      (stroke (width 0.05) (type solid)) (fill none) (layer "B.CrtYd"))
    (fp_rect (start 0.3 -0.15) (end -0.301 0.149)
      (stroke (width 0.15) (type solid)) (fill none) (layer "B.Fab"))
    (pad "" smd roundrect (at -0.349 0.002 180) (size 0.318 0.36) (layers "B.Paste") (roundrect_rratio 0.25))
    (pad "" smd roundrect (at 0.341 0.002 180) (size 0.318 0.36) (layers "B.Paste") (roundrect_rratio 0.25))
    (pad "1" smd roundrect (at -0.321 0.002 180) (size 0.46 0.4) (layers "B.Cu" "B.Mask") (roundrect_rratio 0.25)
      (net 143 "3V3_SYS") (pintype "passive"))
    (pad "2" smd roundrect (at 0.32 0.002 180) (size 0.46 0.4) (layers "B.Cu" "B.Mask") (roundrect_rratio 0.25)
      (net 9 "GND") (pintype "passive"))
  )

  (footprint "data-center-rdimm-ddr4-tester-footprints:R_0402_1005Metric" (layer "B.Cu")
    (at 132.575 108.815 90)
    (descr "Resistor SMD 0402")
    (tags "resistor SMD 0402")
    (property "Author" "Antmicro")
    (property "License" "Apache-2.0")
    (property "MPN" "CR0402-FX-1003GLF")
    (property "Manufacturer" "Bourns")
    (property "Sheetfile" "supply.kicad_sch")
    (property "Sheetname" "Supply")
    (property "Tolerance" "1%")
    (property "Val" "100k")
    (property "ki_description" "100k resistor in 0402 package with 1% tolerance")
    (attr smd)
    (fp_text reference "R192" (at -0.815 0.435 270) (layer "B.SilkS")
        (effects (font (size 0.7 0.7) (thickness 0.15)) (justify left bottom mirror))
    )
    (fp_text value "R_100k_0402" (at 0 -1.4 270) (layer "B.Fab") hide
        (effects (font (size 0.7 0.7) (thickness 0.15)) (justify left bottom mirror))
    )
    (fp_text user "License: Apache-2.0" (at -0.95 -5.169 270) (layer "B.Fab") hide
        (effects (font (size 0.7 0.7) (thickness 0.15)) (justify left bottom mirror))
    )
    (fp_text user "Author: Antmicro" (at -0.95 -4.169 270) (layer "B.Fab") hide
        (effects (font (size 0.7 0.7) (thickness 0.15)) (justify left bottom mirror))
    )
    (fp_text user "${REFERENCE}" (at -0.95 -3.168 270) (layer "B.Fab") hide
        (effects (font (size 0.7 0.7) (thickness 0.15)) (justify left bottom mirror))
    )
    (fp_rect (start -0.93 0.47) (end 0.93 -0.47)
      (stroke (width 0.05) (type solid)) (fill none) (layer "B.CrtYd"))
    (fp_rect (start -0.5 0.25) (end 0.5 -0.25)
      (stroke (width 0.15) (type solid)) (fill none) (layer "B.Fab"))
    (pad "1" smd roundrect (at -0.485 0 90) (size 0.59 0.64) (layers "B.Cu" "B.Paste" "B.Mask") (roundrect_rratio 0.25)
      (net 307 "5V0_SYS") (pintype "passive"))
    (pad "2" smd roundrect (at 0.485 0 90) (size 0.59 0.64) (layers "B.Cu" "B.Paste" "B.Mask") (roundrect_rratio 0.25)
      (net 583 "Net-(Q11-D)") (pintype "passive"))
  )

  (footprint "data-center-rdimm-ddr4-tester-footprints:R_0402_1005Metric" (layer "B.Cu")
    (at 241.4 80.4 180)
    (descr "Resistor SMD 0402")
    (tags "resistor SMD 0402")
    (property "Author" "Antmicro")
    (property "License" "Apache-2.0")
    (property "MPN" "CR0402-FX-3300GLF")
    (property "Manufacturer" "Bourns")
    (property "Sheetfile" "interfaces.kicad_sch")
    (property "Sheetname" "Interfaces")
    (property "Tolerance" "1%")
    (property "Val" "330R")
    (property "ki_description" "330R resistor in 0402 package with 1% tolerance")
    (attr smd)
    (fp_text reference "R188" (at -1.67 -1.31) (layer "B.SilkS")
        (effects (font (size 0.7 0.7) (thickness 0.15)) (justify left bottom mirror))
    )
    (fp_text value "R_330R_0402" (at 0 -1.4) (layer "B.Fab") hide
        (effects (font (size 0.7 0.7) (thickness 0.15)) (justify left bottom mirror))
    )
    (fp_text user "${REFERENCE}" (at -0.95 -3.168) (layer "B.Fab") hide
        (effects (font (size 0.7 0.7) (thickness 0.15)) (justify left bottom mirror))
    )
    (fp_text user "License: Apache-2.0" (at -0.95 -5.169) (layer "B.Fab") hide
        (effects (font (size 0.7 0.7) (thickness 0.15)) (justify left bottom mirror))
    )
    (fp_text user "Author: Antmicro" (at -0.95 -4.169) (layer "B.Fab") hide
        (effects (font (size 0.7 0.7) (thickness 0.15)) (justify left bottom mirror))
    )
    (fp_rect (start -0.93 0.47) (end 0.93 -0.47)
      (stroke (width 0.05) (type solid)) (fill none) (layer "B.CrtYd"))
    (fp_rect (start -0.5 0.25) (end 0.5 -0.25)
      (stroke (width 0.15) (type solid)) (fill none) (layer "B.Fab"))
    (pad "1" smd roundrect (at -0.485 0 180) (size 0.59 0.64) (layers "B.Cu" "B.Paste" "B.Mask") (roundrect_rratio 0.25)
      (net 102 "Net-(D17-C_{G})") (pintype "passive"))
    (pad "2" smd roundrect (at 0.485 0 180) (size 0.59 0.64) (layers "B.Cu" "B.Paste" "B.Mask") (roundrect_rratio 0.25)
      (net 581 "Net-(Q9-D)") (pintype "passive"))
  )

  (footprint "data-center-rdimm-ddr4-tester-footprints:C_0402_1005Metric" (layer "B.Cu")
    (at 138.5 82.25 180)
    (descr "Capacitor SMD 0402")
    (tags "capacitor SMD 0402")
    (property "Author" "Antmicro")
    (property "Dielectric" "X5R")
    (property "License" "Apache-2.0")
    (property "MPN" "GRM155R61H104KE14D")
    (property "Manufacturer" "Murata")
    (property "Sheetfile" "supply.kicad_sch")
    (property "Sheetname" "Supply")
    (property "Val" "100n")
    (property "Voltage" "50V")
    (property "ki_description" " ")
    (attr smd)
    (fp_text reference "C284" (at -3.7 -0.42) (layer "B.SilkS")
        (effects (font (size 0.7 0.7) (thickness 0.15)) (justify left bottom mirror))
    )
    (fp_text value "C_100n_0402" (at 0 -1.4) (layer "B.Fab") hide
        (effects (font (size 0.7 0.7) (thickness 0.15)) (justify left bottom mirror))
    )
    (fp_text user "${REFERENCE}" (at -0.932 -3.168) (layer "B.Fab") hide
        (effects (font (size 0.7 0.7) (thickness 0.15)) (justify left bottom mirror))
    )
    (fp_text user "License: Apache-2.0" (at -0.932 -5.17) (layer "B.Fab") hide
        (effects (font (size 0.7 0.7) (thickness 0.15)) (justify left bottom mirror))
    )
    (fp_text user "Author: Antmicro" (at -0.932 -4.17) (layer "B.Fab") hide
        (effects (font (size 0.7 0.7) (thickness 0.15)) (justify left bottom mirror))
    )
    (fp_rect (start -0.94 0.47) (end 0.94 -0.47)
      (stroke (width 0.05) (type solid)) (fill none) (layer "B.CrtYd"))
    (fp_rect (start -0.499 0.249) (end 0.499 -0.249)
      (stroke (width 0.15) (type solid)) (fill none) (layer "B.Fab"))
    (pad "1" smd roundrect (at -0.484 0 180) (size 0.59 0.64) (layers "B.Cu" "B.Paste" "B.Mask") (roundrect_rratio 0.25)
      (net 307 "5V0_SYS") (pintype "passive"))
    (pad "2" smd roundrect (at 0.484 0 180) (size 0.59 0.64) (layers "B.Cu" "B.Paste" "B.Mask") (roundrect_rratio 0.25)
      (net 9 "GND") (pintype "passive"))
  )

  (footprint "data-center-rdimm-ddr4-tester-footprints:C_0402_1005Metric" (layer "B.Cu")
    (at 194.125 102.775 180)
    (descr "Capacitor SMD 0402")
    (tags "capacitor SMD 0402")
    (property "Author" "Antmicro")
    (property "Dielectric" "")
    (property "License" "Apache-2.0")
    (property "MPN" "GRM155R61A475MEAAD")
    (property "Manufacturer" "Murata")
    (property "Sheetfile" "fpga-power.kicad_sch")
    (property "Sheetname" "FPGA power")
    (property "Val" "4u7")
    (property "Voltage" "")
    (property "ki_description" " ")
    (attr smd)
    (fp_text reference "C256" (at -3.615 -0.345) (layer "B.SilkS")
        (effects (font (size 0.7 0.7) (thickness 0.15)) (justify left bottom mirror))
    )
    (fp_text value "C_4u7_0402" (at 0 -1.4) (layer "B.Fab") hide
        (effects (font (size 0.7 0.7) (thickness 0.15)) (justify left bottom mirror))
    )
    (fp_text user "${REFERENCE}" (at -0.932 -3.168) (layer "B.Fab") hide
        (effects (font (size 0.7 0.7) (thickness 0.15)) (justify left bottom mirror))
    )
    (fp_text user "Author: Antmicro" (at -0.932 -4.17) (layer "B.Fab") hide
        (effects (font (size 0.7 0.7) (thickness 0.15)) (justify left bottom mirror))
    )
    (fp_text user "License: Apache-2.0" (at -0.932 -5.17) (layer "B.Fab") hide
        (effects (font (size 0.7 0.7) (thickness 0.15)) (justify left bottom mirror))
    )
    (fp_rect (start -0.94 0.47) (end 0.94 -0.47)
      (stroke (width 0.05) (type solid)) (fill none) (layer "B.CrtYd"))
    (fp_rect (start -0.499 0.249) (end 0.499 -0.249)
      (stroke (width 0.15) (type solid)) (fill none) (layer "B.Fab"))
    (pad "1" smd roundrect (at -0.484 0 180) (size 0.59 0.64) (layers "B.Cu" "B.Paste" "B.Mask") (roundrect_rratio 0.25)
      (net 306 "1V2_SYS") (pintype "passive"))
    (pad "2" smd roundrect (at 0.484 0 180) (size 0.59 0.64) (layers "B.Cu" "B.Paste" "B.Mask") (roundrect_rratio 0.25)
      (net 9 "GND") (pintype "passive"))
  )

  (footprint "data-center-rdimm-ddr4-tester-footprints:PowerDI5" (layer "B.Cu")
    (at 182.15 112.85 180)
    (property "Author" "Antmicro")
    (property "License" "Apache-2.0")
    (property "MPN" "PDS760-13")
    (property "Manufacturer" "Diodes Incorporated")
    (property "Sheetfile" "ethernet.kicad_sch")
    (property "Sheetname" "Ethernet")
    (property "ki_description" "PDS760 Series 60 V 7 A Surface Mount Schottky Barrier Rectifier - PowerDI-5")
    (property "ki_keywords" "PDS760 Series 60 V 7 A Surface Mount Schottky Barrier Rectifier - PowerDI-5")
    (attr smd)
    (fp_text reference "D16" (at 0 2.55) (layer "B.SilkS")
        (effects (font (size 0.7 0.7) (thickness 0.15)) (justify left bottom mirror))
    )
    (fp_text value "PDS760" (at 0 -3.4) (layer "B.Fab") hide
        (effects (font (size 0.7 0.7) (thickness 0.15)) (justify right bottom mirror))
    )
    (fp_text user "Author: Antmicro" (at -3.302 -19.728) (layer "B.Fab") hide
        (effects (font (size 0.7 0.7) (thickness 0.15)) (justify left bottom mirror))
    )
    (fp_text user "${REFERENCE}" (at -3.302 -18.527) (layer "B.Fab") hide
        (effects (font (size 0.7 0.7) (thickness 0.15)) (justify left bottom mirror))
    )
    (fp_text user "License: Apache-2.0" (at -3.302 -20.928) (layer "B.Fab") hide
        (effects (font (size 0.7 0.7) (thickness 0.15)) (justify left bottom mirror))
    )
    (fp_line (start -2.7 -2.023) (end -2.7 -1.823)
      (stroke (width 0.12) (type solid)) (layer "B.SilkS"))
    (fp_line (start -2.7 1.8) (end -2.7 2)
      (stroke (width 0.12) (type solid)) (layer "B.SilkS"))
    (fp_line (start -2.7 2) (end 2.7 2)
      (stroke (width 0.12) (type solid)) (layer "B.SilkS"))
    (fp_line (start 2.7 -2.023) (end -2.7 -2.023)
      (stroke (width 0.12) (type solid)) (layer "B.SilkS"))
    (fp_line (start 2.7 -1.823) (end 2.7 -2.023)
      (stroke (width 0.12) (type solid)) (layer "B.SilkS"))
    (fp_line (start 2.7 2) (end 2.7 1.8)
      (stroke (width 0.12) (type solid)) (layer "B.SilkS"))
    (fp_rect (start -3.702 2.3) (end 3.7 -2.3)
      (stroke (width 0.05) (type solid)) (fill none) (layer "B.CrtYd"))
    (pad "A" smd roundrect (at -2.862 -0.941 270) (size 1.39 1.4) (layers "B.Cu" "B.Paste" "B.Mask") (roundrect_rratio 0.25)
      (net 864 "VIN_POE") (pinfunction "A") (pintype "passive"))
    (pad "A" smd roundrect (at -2.862 0.94 90) (size 1.39 1.4) (layers "B.Cu" "B.Paste" "B.Mask") (roundrect_rratio 0.25)
      (net 864 "VIN_POE") (pinfunction "A") (pintype "passive"))
    (pad "C" smd roundrect (at 1.1 0 270) (size 3.36 4.86) (layers "B.Cu" "B.Paste" "B.Mask") (roundrect_rratio 0.05)
      (net 103 "VIN") (pinfunction "C") (pintype "passive"))
  )

  (footprint "data-center-rdimm-ddr4-tester-footprints:R_0603_1608Metric" (layer "B.Cu")
    (at 158.75 132.775 180)
    (descr "Resistor SMD 0603")
    (tags "resistor SMD 0603")
    (property "Author" "Antmicro")
    (property "License" "Apache-2.0")
    (property "MPN" "CR0603-FX-1001ELF")
    (property "Manufacturer" "Bourns")
    (property "Sheetfile" "ethernet.kicad_sch")
    (property "Sheetname" "Ethernet")
    (property "Tolerance" "1%")
    (property "Val" "1k")
    (property "ki_description" "1k resistor in 0603 package with 1% tolerance")
    (attr smd)
    (fp_text reference "R184" (at -0.74 -1.305) (layer "B.SilkS")
        (effects (font (size 0.7 0.7) (thickness 0.15)) (justify left bottom mirror))
    )
    (fp_text value "R_1k_0603" (at 0 -1.6) (layer "B.Fab") hide
        (effects (font (size 0.7 0.7) (thickness 0.15)) (justify left bottom mirror))
    )
    (fp_text user "${REFERENCE}" (at -1.25 -3.898) (layer "B.Fab") hide
        (effects (font (size 0.7 0.7) (thickness 0.15)) (justify left bottom mirror))
    )
    (fp_text user "License: Apache-2.0" (at -1.25 -5.9) (layer "B.Fab") hide
        (effects (font (size 0.7 0.7) (thickness 0.15)) (justify left bottom mirror))
    )
    (fp_text user "Author: Antmicro" (at -1.25 -4.9) (layer "B.Fab") hide
        (effects (font (size 0.7 0.7) (thickness 0.15)) (justify left bottom mirror))
    )
    (fp_line (start -0.3 -0.3) (end 0.3 -0.3)
      (stroke (width 0.15) (type solid)) (layer "B.SilkS"))
    (fp_line (start -0.3 0.3) (end 0.3 0.3)
      (stroke (width 0.15) (type solid)) (layer "B.SilkS"))
    (fp_rect (start -1.25 0.7) (end 1.25 -0.7)
      (stroke (width 0.05) (type solid)) (fill none) (layer "B.CrtYd"))
    (fp_rect (start -0.8 0.4) (end 0.8 -0.4)
      (stroke (width 0.15) (type solid)) (fill none) (layer "B.Fab"))
    (pad "1" smd roundrect (at -0.7 0 180) (size 0.6 0.8) (layers "B.Cu" "B.Paste" "B.Mask") (roundrect_rratio 0.2)
      (net 628 "Net-(IC2-Pad2)") (pintype "passive"))
    (pad "2" smd roundrect (at 0.7 0 180) (size 0.6 0.8) (layers "B.Cu" "B.Paste" "B.Mask") (roundrect_rratio 0.2)
      (net 9 "GND") (pintype "passive"))
  )

  (footprint "data-center-rdimm-ddr4-tester-footprints:SOT-143-4" (layer "B.Cu")
    (at 130.075 108.86 90)
    (descr "http://datasheets.maximintegrated.com/en/ds/MAX6816-MAX6818.pdf")
    (property "Author" "Antmicro")
    (property "License" "Apache-2.0")
    (property "MPN" "MAX812REUS+T")
    (property "Manufacturer" "Maxim Integrated")
    (property "Sheetfile" "supply.kicad_sch")
    (property "Sheetname" "Supply")
    (property "ki_description" "Supervisory Circuits 4-Pin uP Voltage Monitors with Manual Reset Input")
    (attr smd)
    (fp_text reference "U18" (at -1.31 1.855 270) (layer "B.SilkS")
        (effects (font (size 0.7 0.7) (thickness 0.15)) (justify left bottom mirror))
    )
    (fp_text value "MAX812REUS+T" (at 0 -2.999 270) (layer "B.Fab") hide
        (effects (font (size 0.7 0.7) (thickness 0.15)) (justify left bottom mirror))
    )
    (fp_text user "License: Apache-2.0" (at -1.601 -7.4 270) (layer "B.Fab") hide
        (effects (font (size 0.7 0.7) (thickness 0.15)) (justify left bottom mirror))
    )
    (fp_text user "${REFERENCE}" (at -1.601 -4.998 270) (layer "B.Fab") hide
        (effects (font (size 0.7 0.7) (thickness 0.15)) (justify left bottom mirror))
    )
    (fp_text user "Author: Antmicro" (at -1.601 -6.2 270) (layer "B.Fab") hide
        (effects (font (size 0.7 0.7) (thickness 0.15)) (justify left bottom mirror))
    )
    (fp_line (start -1.601 0.802) (end -1.601 -1.7)
      (stroke (width 0.15) (type solid)) (layer "B.SilkS"))
    (fp_line (start 1.6 0.802) (end 1.6 -0.8)
      (stroke (width 0.15) (type solid)) (layer "B.SilkS"))
    (fp_circle (center -2.1 -1.7) (end -2.05 -1.7)
      (stroke (width 0.15) (type solid)) (fill solid) (layer "B.SilkS"))
    (fp_rect (start -1.776 1.896) (end 1.773 -1.895)
      (stroke (width 0.05) (type solid)) (fill none) (layer "B.CrtYd"))
    (fp_line (start -1.46 -0.65) (end -1.46 0.652)
      (stroke (width 0.15) (type solid)) (layer "B.Fab"))
    (fp_line (start -1.46 -0.65) (end 1.459 -0.65)
      (stroke (width 0.15) (type solid)) (layer "B.Fab"))
    (fp_line (start 1.459 0.652) (end -1.46 0.652)
      (stroke (width 0.15) (type solid)) (layer "B.Fab"))
    (fp_line (start 1.459 0.652) (end 1.459 -0.65)
      (stroke (width 0.15) (type solid)) (layer "B.Fab"))
    (pad "1" smd roundrect (at -0.76 -0.998 90) (size 0.94 1.31) (layers "B.Cu" "B.Paste" "B.Mask") (roundrect_rratio 0.25)
      (net 9 "GND") (pinfunction "GND") (pintype "power_in"))
    (pad "2" smd roundrect (at 0.959 -0.998 90) (size 0.55 1.31) (layers "B.Cu" "B.Paste" "B.Mask") (roundrect_rratio 0.25)
      (net 798 "/Supply/FPGA_PWR_DIS") (pinfunction "~{RST}") (pintype "output"))
    (pad "3" smd roundrect (at 0.959 1 90) (size 0.55 1.31) (layers "B.Cu" "B.Paste" "B.Mask") (roundrect_rratio 0.25)
      (net 583 "Net-(Q11-D)") (pinfunction "~{MR}") (pintype "input"))
    (pad "4" smd roundrect (at -0.96 1 90) (size 0.55 1.31) (layers "B.Cu" "B.Paste" "B.Mask") (roundrect_rratio 0.25)
      (net 307 "5V0_SYS") (pinfunction "VCC") (pintype "power_in"))
  )

  (footprint "data-center-rdimm-ddr4-tester-footprints:WQFN-56-1EP_5x11x1mm_P0.5mm" (layer "B.Cu")
    (at 159.1645 106.6705 -90)
    (property "Author" "Antmicro")
    (property "License" "Apache-2.0")
    (property "MPN" "TS3L500RHUR")
    (property "Manufacturer" "Texas Instruments")
    (property "Sheetfile" "ethernet.kicad_sch")
    (property "Sheetname" "Ethernet")
    (property "ki_description" "3.3-V, 2:1 (SPDT), 8-channel gigachannel LAN switch with LED switch & enhanced ESD protection")
    (attr smd)
    (fp_text reference "U16" (at -2.2805 5.9445 180) (layer "B.SilkS")
        (effects (font (size 0.7 0.7) (thickness 0.15)) (justify left bottom mirror))
    )
    (fp_text value "TS3L500RHUR" (at -0.02 -7.02 90) (layer "B.Fab") hide
        (effects (font (size 0.7 0.7) (thickness 0.15)) (justify left bottom mirror))
    )
    (fp_text user "Author: Antmicro" (at -0.482 -14.749 90) (layer "B.Fab") hide
        (effects (font (size 0.7 0.7) (thickness 0.15)) (justify left bottom mirror))
    )
    (fp_text user "${REFERENCE}" (at -0.482 -13.749 90) (layer "B.Fab") hide
        (effects (font (size 0.7 0.7) (thickness 0.15)) (justify left bottom mirror))
    )
    (fp_text user "License: Apache-2.0" (at -0.482 -15.749 90) (layer "B.Fab") hide
        (effects (font (size 0.7 0.7) (thickness 0.15)) (justify left bottom mirror))
    )
    (fp_line (start -2.956 5.218) (end -3.356 5.218)
      (stroke (width 0.15) (type solid)) (layer "B.SilkS"))
    (fp_line (start -2.956 5.955) (end -2.956 5.218)
      (stroke (width 0.15) (type solid)) (layer "B.SilkS"))
    (fp_line (start -2.218 5.955) (end -2.956 5.955)
      (stroke (width 0.15) (type solid)) (layer "B.SilkS"))
    (fp_line (start 2.955 5.218) (end 2.955 5.955)
      (stroke (width 0.15) (type solid)) (layer "B.SilkS"))
    (fp_line (start 2.955 5.955) (end 2.219 5.955)
      (stroke (width 0.15) (type solid)) (layer "B.SilkS"))
    (fp_circle (center -3.5 4.749) (end -3.45 4.699)
      (stroke (width 0.15) (type solid)) (fill solid) (layer "B.SilkS"))
    (fp_rect (start -3.15 6.15) (end 3.15 -6.15)
      (stroke (width 0.05) (type solid)) (fill none) (layer "B.CrtYd"))
    (fp_line (start -2.576 -5.576) (end 2.575 -5.576)
      (stroke (width 0.15) (type solid)) (layer "B.Fab"))
    (fp_line (start -2.576 4.305) (end -2.576 -5.576)
      (stroke (width 0.15) (type solid)) (layer "B.Fab"))
    (fp_line (start -2.576 4.305) (end -1.305 5.575)
      (stroke (width 0.15) (type solid)) (layer "B.Fab"))
    (fp_line (start 2.575 -5.576) (end 2.575 5.575)
      (stroke (width 0.15) (type solid)) (layer "B.Fab"))
    (fp_line (start 2.575 5.575) (end -1.305 5.575)
      (stroke (width 0.15) (type solid)) (layer "B.Fab"))
    (pad "1" smd roundrect (at -2.474 4.749 180) (size 0.28 0.85) (layers "B.Cu" "B.Paste" "B.Mask") (roundrect_rratio 0.25)
      (net 9 "GND") (pinfunction "GND") (pintype "power_in"))
    (pad "2" smd roundrect (at -2.474 4.25 180) (size 0.28 0.85) (layers "B.Cu" "B.Paste" "B.Mask") (roundrect_rratio 0.25)
      (net 170 "/Ethernet/ETH1_P") (pinfunction "A0") (pintype "bidirectional"))
    (pad "3" smd roundrect (at -2.474 3.75 180) (size 0.28 0.85) (layers "B.Cu" "B.Paste" "B.Mask") (roundrect_rratio 0.25)
      (net 173 "/Ethernet/ETH1_N") (pinfunction "A1") (pintype "bidirectional"))
    (pad "4" smd roundrect (at -2.474 3.25 180) (size 0.28 0.85) (layers "B.Cu" "B.Paste" "B.Mask") (roundrect_rratio 0.25)
      (net 143 "3V3_SYS") (pinfunction "VCC") (pintype "passive"))
    (pad "5" smd roundrect (at -2.474 2.75 180) (size 0.28 0.85) (layers "B.Cu" "B.Paste" "B.Mask") (roundrect_rratio 0.25)
      (net 914 "unconnected-(U16-NC-Pad5)") (pinfunction "NC") (pintype "no_connect"))
    (pad "6" smd roundrect (at -2.474 2.25 180) (size 0.28 0.85) (layers "B.Cu" "B.Paste" "B.Mask") (roundrect_rratio 0.25)
      (net 9 "GND") (pinfunction "GND") (pintype "passive"))
    (pad "7" smd roundrect (at -2.474 1.75 180) (size 0.28 0.85) (layers "B.Cu" "B.Paste" "B.Mask") (roundrect_rratio 0.25)
      (net 169 "/Ethernet/ETH2_P") (pinfunction "A2") (pintype "bidirectional"))
    (pad "8" smd roundrect (at -2.474 1.25 180) (size 0.28 0.85) (layers "B.Cu" "B.Paste" "B.Mask") (roundrect_rratio 0.25)
      (net 172 "/Ethernet/ETH2_N") (pinfunction "A3") (pintype "bidirectional"))
    (pad "9" smd roundrect (at -2.474 0.75 180) (size 0.28 0.85) (layers "B.Cu" "B.Paste" "B.Mask") (roundrect_rratio 0.25)
      (net 9 "GND") (pinfunction "GND") (pintype "passive"))
    (pad "10" smd roundrect (at -2.474 0.25 180) (size 0.28 0.85) (layers "B.Cu" "B.Paste" "B.Mask") (roundrect_rratio 0.25)
      (net 143 "3V3_SYS") (pinfunction "VCC") (pintype "power_in"))
    (pad "11" smd roundrect (at -2.474 -0.25 180) (size 0.28 0.85) (layers "B.Cu" "B.Paste" "B.Mask") (roundrect_rratio 0.25)
      (net 168 "/Ethernet/ETH3_P") (pinfunction "A4") (pintype "bidirectional"))
    (pad "12" smd roundrect (at -2.474 -0.75 180) (size 0.28 0.85) (layers "B.Cu" "B.Paste" "B.Mask") (roundrect_rratio 0.25)
      (net 174 "/Ethernet/ETH3_N") (pinfunction "A5") (pintype "bidirectional"))
    (pad "13" smd roundrect (at -2.474 -1.25 180) (size 0.28 0.85) (layers "B.Cu" "B.Paste" "B.Mask") (roundrect_rratio 0.25)
      (net 9 "GND") (pinfunction "GND") (pintype "passive"))
    (pad "14" smd roundrect (at -2.474 -1.75 180) (size 0.28 0.85) (layers "B.Cu" "B.Paste" "B.Mask") (roundrect_rratio 0.25)
      (net 171 "/Ethernet/ETH4_P") (pinfunction "A6") (pintype "bidirectional"))
    (pad "15" smd roundrect (at -2.474 -2.25 180) (size 0.28 0.85) (layers "B.Cu" "B.Paste" "B.Mask") (roundrect_rratio 0.25)
      (net 175 "/Ethernet/ETH4_N") (pinfunction "A7") (pintype "bidirectional"))
    (pad "16" smd roundrect (at -2.474 -2.75 180) (size 0.28 0.85) (layers "B.Cu" "B.Paste" "B.Mask") (roundrect_rratio 0.25)
      (net 9 "GND") (pinfunction "GND") (pintype "passive"))
    (pad "17" smd roundrect (at -2.474 -3.25 180) (size 0.28 0.85) (layers "B.Cu" "B.Paste" "B.Mask") (roundrect_rratio 0.25)
      (net 662 "Net-(U16-SEL)") (pinfunction "SEL") (pintype "input"))
    (pad "18" smd roundrect (at -2.474 -3.75 180) (size 0.28 0.85) (layers "B.Cu" "B.Paste" "B.Mask") (roundrect_rratio 0.25)
      (net 143 "3V3_SYS") (pinfunction "VCC") (pintype "passive"))
    (pad "19" smd roundrect (at -2.474 -4.25 180) (size 0.28 0.85) (layers "B.Cu" "B.Paste" "B.Mask") (roundrect_rratio 0.25)
      (net 9 "GND") (pinfunction "LED0") (pintype "bidirectional"))
    (pad "20" smd roundrect (at -2.474 -4.75 180) (size 0.28 0.85) (layers "B.Cu" "B.Paste" "B.Mask") (roundrect_rratio 0.25)
      (net 16 "LED_LINK") (pinfunction "LED1") (pintype "bidirectional"))
    (pad "21" smd roundrect (at -1.751 -5.475 270) (size 0.28 0.85) (layers "B.Cu" "B.Paste" "B.Mask") (roundrect_rratio 0.25)
      (net 9 "GND") (pinfunction "GND") (pintype "passive"))
    (pad "22" smd roundrect (at -1.251 -5.475 270) (size 0.28 0.85) (layers "B.Cu" "B.Paste" "B.Mask") (roundrect_rratio 0.25)
      (net 915 "unconnected-(U16-0LED1-Pad22)") (pinfunction "0LED1") (pintype "bidirectional+no_connect"))
    (pad "23" smd roundrect (at -0.751 -5.475 270) (size 0.28 0.85) (layers "B.Cu" "B.Paste" "B.Mask") (roundrect_rratio 0.25)
      (net 736 "EXT_LED_LINK") (pinfunction "1LED1") (pintype "bidirectional"))
    (pad "24" smd roundrect (at -0.25 -5.475 270) (size 0.28 0.85) (layers "B.Cu" "B.Paste" "B.Mask") (roundrect_rratio 0.25)
      (net 9 "GND") (pinfunction "GND") (pintype "passive"))
    (pad "25" smd roundrect (at 0.251 -5.475 270) (size 0.28 0.85) (layers "B.Cu" "B.Paste" "B.Mask") (roundrect_rratio 0.25)
      (net 916 "unconnected-(U16-0LED2-Pad25)") (pinfunction "0LED2") (pintype "bidirectional+no_connect"))
    (pad "26" smd roundrect (at 0.751 -5.475 270) (size 0.28 0.85) (layers "B.Cu" "B.Paste" "B.Mask") (roundrect_rratio 0.25)
      (net 537 "INT_LED_LINK") (pinfunction "1LED2") (pintype "bidirectional"))
    (pad "27" smd roundrect (at 1.251 -5.475 270) (size 0.28 0.85) (layers "B.Cu" "B.Paste" "B.Mask") (roundrect_rratio 0.25)
      (net 143 "3V3_SYS") (pinfunction "VCC") (pintype "passive"))
    (pad "28" smd roundrect (at 1.75 -5.475 270) (size 0.28 0.85) (layers "B.Cu" "B.Paste" "B.Mask") (roundrect_rratio 0.25)
      (net 9 "GND") (pinfunction "GND") (pintype "passive"))
    (pad "29" smd roundrect (at 2.474 -4.75 180) (size 0.28 0.85) (layers "B.Cu" "B.Paste" "B.Mask") (roundrect_rratio 0.25)
      (net 547 "/Ethernet/INT_ETH4_N") (pinfunction "7B2") (pintype "bidirectional"))
    (pad "30" smd roundrect (at 2.474 -4.25 180) (size 0.28 0.85) (layers "B.Cu" "B.Paste" "B.Mask") (roundrect_rratio 0.25)
      (net 548 "/Ethernet/INT_ETH4_P") (pinfunction "6B2") (pintype "bidirectional"))
    (pad "31" smd roundrect (at 2.474 -3.75 180) (size 0.28 0.85) (layers "B.Cu" "B.Paste" "B.Mask") (roundrect_rratio 0.25)
      (net 741 "EXT_ETH4_N") (pinfunction "7B1") (pintype "bidirectional"))
    (pad "32" smd roundrect (at 2.474 -3.25 180) (size 0.28 0.85) (layers "B.Cu" "B.Paste" "B.Mask") (roundrect_rratio 0.25)
      (net 740 "EXT_ETH4_P") (pinfunction "6B1") (pintype "bidirectional"))
    (pad "33" smd roundrect (at 2.474 -2.75 180) (size 0.28 0.85) (layers "B.Cu" "B.Paste" "B.Mask") (roundrect_rratio 0.25)
      (net 9 "GND") (pinfunction "GND") (pintype "passive"))
    (pad "34" smd roundrect (at 2.474 -2.25 180) (size 0.28 0.85) (layers "B.Cu" "B.Paste" "B.Mask") (roundrect_rratio 0.25)
      (net 558 "/Ethernet/INT_ETH3_N") (pinfunction "5B2") (pintype "bidirectional"))
    (pad "35" smd roundrect (at 2.474 -1.75 180) (size 0.28 0.85) (layers "B.Cu" "B.Paste" "B.Mask") (roundrect_rratio 0.25)
      (net 559 "/Ethernet/INT_ETH3_P") (pinfunction "4B2") (pintype "bidirectional"))
    (pad "36" smd roundrect (at 2.474 -1.25 180) (size 0.28 0.85) (layers "B.Cu" "B.Paste" "B.Mask") (roundrect_rratio 0.25)
      (net 757 "EXT_ETH3_N") (pinfunction "5B1") (pintype "bidirectional"))
    (pad "37" smd roundrect (at 2.474 -0.75 180) (size 0.28 0.85) (layers "B.Cu" "B.Paste" "B.Mask") (roundrect_rratio 0.25)
      (net 756 "EXT_ETH3_P") (pinfunction "4B1") (pintype "bidirectional"))
    (pad "38" smd roundrect (at 2.474 -0.25 180) (size 0.28 0.85) (layers "B.Cu" "B.Paste" "B.Mask") (roundrect_rratio 0.25)
      (net 143 "3V3_SYS") (pinfunction "VCC") (pintype "passive"))
    (pad "39" smd roundrect (at 2.474 0.25 180) (size 0.28 0.85) (layers "B.Cu" "B.Paste" "B.Mask") (roundrect_rratio 0.25)
      (net 9 "GND") (pinfunction "GND") (pintype "passive"))
    (pad "40" smd roundrect (at 2.474 0.75 180) (size 0.28 0.85) (layers "B.Cu" "B.Paste" "B.Mask") (roundrect_rratio 0.25)
      (net 567 "/Ethernet/INT_ETH2_N") (pinfunction "3B2") (pintype "bidirectional"))
    (pad "41" smd roundrect (at 2.474 1.25 180) (size 0.28 0.85) (layers "B.Cu" "B.Paste" "B.Mask") (roundrect_rratio 0.25)
      (net 568 "/Ethernet/INT_ETH2_P") (pinfunction "2B2") (pintype "bidirectional"))
    (pad "42" smd roundrect (at 2.474 1.75 180) (size 0.28 0.85) (layers "B.Cu" "B.Paste" "B.Mask") (roundrect_rratio 0.25)
      (net 739 "EXT_ETH2_N") (pinfunction "3B1") (pintype "bidirectional"))
    (pad "43" smd roundrect (at 2.474 2.25 180) (size 0.28 0.85) (layers "B.Cu" "B.Paste" "B.Mask") (roundrect_rratio 0.25)
      (net 738 "EXT_ETH2_P") (pinfunction "2B1") (pintype "bidirectional"))
    (pad "44" smd roundrect (at 2.474 2.75 180) (size 0.28 0.85) (layers "B.Cu" "B.Paste" "B.Mask") (roundrect_rratio 0.25)
      (net 9 "GND") (pinfunction "GND") (pintype "passive"))
    (pad "45" smd roundrect (at 2.474 3.25 180) (size 0.28 0.85) (layers "B.Cu" "B.Paste" "B.Mask") (roundrect_rratio 0.25)
      (net 630 "/Ethernet/INT_ETH1_N") (pinfunction "1B2") (pintype "bidirectional"))
    (pad "46" smd roundrect (at 2.474 3.75 180) (size 0.28 0.85) (layers "B.Cu" "B.Paste" "B.Mask") (roundrect_rratio 0.25)
      (net 631 "/Ethernet/INT_ETH1_P") (pinfunction "0B2") (pintype "bidirectional"))
    (pad "47" smd roundrect (at 2.474 4.25 180) (size 0.28 0.85) (layers "B.Cu" "B.Paste" "B.Mask") (roundrect_rratio 0.25)
      (net 755 "EXT_ETH1_N") (pinfunction "1B1") (pintype "bidirectional"))
    (pad "48" smd roundrect (at 2.474 4.749 180) (size 0.28 0.85) (layers "B.Cu" "B.Paste" "B.Mask") (roundrect_rratio 0.25)
      (net 754 "EXT_ETH1_P") (pinfunction "0B1") (pintype "bidirectional"))
    (pad "49" smd roundrect (at 1.75 5.474 270) (size 0.28 0.85) (layers "B.Cu" "B.Paste" "B.Mask") (roundrect_rratio 0.25)
      (net 9 "GND") (pinfunction "GND") (pintype "passive"))
    (pad "50" smd roundrect (at 1.251 5.474 270) (size 0.28 0.85) (layers "B.Cu" "B.Paste" "B.Mask") (roundrect_rratio 0.25)
      (net 143 "3V3_SYS") (pinfunction "VCC") (pintype "passive"))
    (pad "51" smd roundrect (at 0.751 5.474 270) (size 0.28 0.85) (layers "B.Cu" "B.Paste" "B.Mask") (roundrect_rratio 0.25)
      (net 546 "INT_LED_SPD") (pinfunction "2LED2") (pintype "bidirectional"))
    (pad "52" smd roundrect (at 0.251 5.474 270) (size 0.28 0.85) (layers "B.Cu" "B.Paste" "B.Mask") (roundrect_rratio 0.25)
      (net 737 "EXT_LED_SPD") (pinfunction "2LED1") (pintype "bidirectional"))
    (pad "53" smd roundrect (at -0.25 5.474 270) (size 0.28 0.85) (layers "B.Cu" "B.Paste" "B.Mask") (roundrect_rratio 0.25)
      (net 9 "GND") (pinfunction "GND") (pintype "passive"))
    (pad "54" smd roundrect (at -0.751 5.474 270) (size 0.28 0.85) (layers "B.Cu" "B.Paste" "B.Mask") (roundrect_rratio 0.25)
      (net 17 "LED_SPD") (pinfunction "LED2") (pintype "bidirectional"))
    (pad "55" smd roundrect (at -1.251 5.474 270) (size 0.28 0.85) (layers "B.Cu" "B.Paste" "B.Mask") (roundrect_rratio 0.25)
      (net 9 "GND") (pinfunction "GND") (pintype "passive"))
    (pad "56" smd roundrect (at -1.751 5.474 270) (size 0.28 0.85) (layers "B.Cu" "B.Paste" "B.Mask") (roundrect_rratio 0.25)
      (net 143 "3V3_SYS") (pinfunction "VCC") (pintype "passive"))
    (pad "57" smd roundrect (at -0.65 -3.2 270) (size 1 1) (layers "B.Cu" "B.Paste" "B.Mask") (roundrect_rratio 0.05)
      (net 9 "GND") (pinfunction "EP") (pintype "unspecified"))
    (pad "57" smd roundrect (at -0.65 -1.95 270) (size 1 1) (layers "B.Cu" "B.Paste" "B.Mask") (roundrect_rratio 0.05)
      (net 9 "GND") (pinfunction "EP") (pintype "unspecified"))
    (pad "57" smd roundrect (at -0.65 -0.65 270) (size 1 1) (layers "B.Cu" "B.Paste" "B.Mask") (roundrect_rratio 0.05)
      (net 9 "GND") (pinfunction "EP") (pintype "unspecified"))
    (pad "57" smd roundrect (at -0.65 0.65 270) (size 1 1) (layers "B.Cu" "B.Paste" "B.Mask") (roundrect_rratio 0.05)
      (net 9 "GND") (pinfunction "EP") (pintype "unspecified"))
    (pad "57" smd roundrect (at -0.65 1.9 270) (size 1 1) (layers "B.Cu" "B.Paste" "B.Mask") (roundrect_rratio 0.05)
      (net 9 "GND") (pinfunction "EP") (pintype "unspecified"))
    (pad "57" smd roundrect (at -0.65 3.2 270) (size 1 1) (layers "B.Cu" "B.Paste" "B.Mask") (roundrect_rratio 0.05)
      (net 9 "GND") (pinfunction "EP") (pintype "unspecified"))
    (pad "57" smd roundrect (at 0 0 270) (size 2.4 8.400001) (layers "B.Cu" "B.Mask") (roundrect_rratio 0.05)
      (net 9 "GND") (pinfunction "EP") (pintype "unspecified"))
    (pad "57" smd roundrect (at 0.65 -3.2 270) (size 1 1) (layers "B.Cu" "B.Paste" "B.Mask") (roundrect_rratio 0.05)
      (net 9 "GND") (pinfunction "EP") (pintype "unspecified"))
    (pad "57" smd roundrect (at 0.65 -1.95 270) (size 1 1) (layers "B.Cu" "B.Paste" "B.Mask") (roundrect_rratio 0.05)
      (net 9 "GND") (pinfunction "EP") (pintype "unspecified"))
    (pad "57" smd roundrect (at 0.65 -0.65 270) (size 1 1) (layers "B.Cu" "B.Paste" "B.Mask") (roundrect_rratio 0.05)
      (net 9 "GND") (pinfunction "EP") (pintype "unspecified"))
    (pad "57" smd roundrect (at 0.65 0.65 270) (size 1 1) (layers "B.Cu" "B.Paste" "B.Mask") (roundrect_rratio 0.05)
      (net 9 "GND") (pinfunction "EP") (pintype "unspecified"))
    (pad "57" smd roundrect (at 0.65 1.9 270) (size 1 1) (layers "B.Cu" "B.Paste" "B.Mask") (roundrect_rratio 0.05)
      (net 9 "GND") (pinfunction "EP") (pintype "unspecified"))
    (pad "57" smd roundrect (at 0.65 3.2 270) (size 1 1) (layers "B.Cu" "B.Paste" "B.Mask") (roundrect_rratio 0.05)
      (net 9 "GND") (pinfunction "EP") (pintype "unspecified"))
  )

  (footprint "data-center-rdimm-ddr4-tester-footprints:C_0201" (layer "B.Cu")
    (at 186.6 100.64)
    (descr "Capacitor SMD 0201")
    (tags "capacitor SMD 0201")
    (property "Author" "Antmicro")
    (property "Dielectric" "")
    (property "License" "Apache-2.0")
    (property "MPN" "CC0201KRX6S5BB104")
    (property "Manufacturer" "Yaego")
    (property "Sheetfile" "fpga-power.kicad_sch")
    (property "Sheetname" "FPGA power")
    (property "Val" "100n")
    (property "Voltage" "")
    (property "ki_description" " ")
    (attr smd)
    (fp_text reference "C304" (at 1.48 -0.31 180) (layer "B.SilkS")
        (effects (font (size 0.7 0.7) (thickness 0.15)) (justify left bottom mirror))
    )
    (fp_text value "C_100n_0201" (at 0 -1.4 180) (layer "B.Fab") hide
        (effects (font (size 0.7 0.7) (thickness 0.15)) (justify left bottom mirror))
    )
    (fp_text user "${REFERENCE}" (at -0.72 -3.4 180) (layer "B.Fab") hide
        (effects (font (size 0.7 0.7) (thickness 0.15)) (justify left bottom mirror))
    )
    (fp_text user "License: Apache-2.0" (at -0.72 -4.4 180) (layer "B.Fab") hide
        (effects (font (size 0.7 0.7) (thickness 0.15)) (justify left bottom mirror))
    )
    (fp_text user "Author: Antmicro" (at -0.72 -5.4 180) (layer "B.Fab") hide
        (effects (font (size 0.7 0.7) (thickness 0.15)) (justify left bottom mirror))
    )
    (fp_rect (start -0.72 0.38) (end 0.72 -0.38)
      (stroke (width 0.05) (type solid)) (fill none) (layer "B.CrtYd"))
    (fp_rect (start 0.3 -0.15) (end -0.301 0.149)
      (stroke (width 0.15) (type solid)) (fill none) (layer "B.Fab"))
    (pad "" smd roundrect (at -0.349 0.002) (size 0.318 0.36) (layers "B.Paste") (roundrect_rratio 0.25))
    (pad "" smd roundrect (at 0.341 0.002) (size 0.318 0.36) (layers "B.Paste") (roundrect_rratio 0.25))
    (pad "1" smd roundrect (at -0.321 0.002) (size 0.46 0.4) (layers "B.Cu" "B.Mask") (roundrect_rratio 0.25)
      (net 143 "3V3_SYS") (pintype "passive"))
    (pad "2" smd roundrect (at 0.32 0.002) (size 0.46 0.4) (layers "B.Cu" "B.Mask") (roundrect_rratio 0.25)
      (net 9 "GND") (pintype "passive"))
  )

  (footprint "data-center-rdimm-ddr4-tester-footprints:C_0201" (layer "B.Cu")
    (at 177.575 87.1 90)
    (descr "Capacitor SMD 0201")
    (tags "capacitor SMD 0201")
    (property "Author" "Antmicro")
    (property "Dielectric" "")
    (property "License" "Apache-2.0")
    (property "MPN" "CC0201KRX6S5BB104")
    (property "Manufacturer" "Yaego")
    (property "Sheetfile" "fpga-power.kicad_sch")
    (property "Sheetname" "FPGA power")
    (property "Val" "100n")
    (property "Voltage" "")
    (property "ki_description" " ")
    (attr smd)
    (fp_text reference "C231" (at 1.38 -0.345 270) (layer "B.SilkS")
        (effects (font (size 0.7 0.7) (thickness 0.15)) (justify left bottom mirror))
    )
    (fp_text value "C_100n_0201" (at 0 -1.4 270) (layer "B.Fab") hide
        (effects (font (size 0.7 0.7) (thickness 0.15)) (justify left bottom mirror))
    )
    (fp_text user "Author: Antmicro" (at -0.72 -5.4 270) (layer "B.Fab") hide
        (effects (font (size 0.7 0.7) (thickness 0.15)) (justify left bottom mirror))
    )
    (fp_text user "License: Apache-2.0" (at -0.72 -4.4 270) (layer "B.Fab") hide
        (effects (font (size 0.7 0.7) (thickness 0.15)) (justify left bottom mirror))
    )
    (fp_text user "${REFERENCE}" (at -0.72 -3.4 270) (layer "B.Fab") hide
        (effects (font (size 0.7 0.7) (thickness 0.15)) (justify left bottom mirror))
    )
    (fp_rect (start -0.72 0.38) (end 0.72 -0.38)
      (stroke (width 0.05) (type solid)) (fill none) (layer "B.CrtYd"))
    (fp_rect (start 0.3 -0.15) (end -0.301 0.149)
      (stroke (width 0.15) (type solid)) (fill none) (layer "B.Fab"))
    (pad "" smd roundrect (at -0.349 0.002 90) (size 0.318 0.36) (layers "B.Paste") (roundrect_rratio 0.25))
    (pad "" smd roundrect (at 0.341 0.002 90) (size 0.318 0.36) (layers "B.Paste") (roundrect_rratio 0.25))
    (pad "1" smd roundrect (at -0.321 0.002 90) (size 0.46 0.4) (layers "B.Cu" "B.Mask") (roundrect_rratio 0.25)
      (net 77 "VDDQ") (pintype "passive"))
    (pad "2" smd roundrect (at 0.32 0.002 90) (size 0.46 0.4) (layers "B.Cu" "B.Mask") (roundrect_rratio 0.25)
      (net 9 "GND") (pintype "passive"))
  )

  (footprint "data-center-rdimm-ddr4-tester-footprints:C_0201" (layer "B.Cu")
    (at 171.175 81.35 -90)
    (descr "Capacitor SMD 0201")
    (tags "capacitor SMD 0201")
    (property "Author" "Antmicro")
    (property "Dielectric" "")
    (property "License" "Apache-2.0")
    (property "MPN" "CC0201KRX6S5BB104")
    (property "Manufacturer" "Yaego")
    (property "Sheetfile" "fpga-power.kicad_sch")
    (property "Sheetname" "FPGA power")
    (property "Val" "100n")
    (property "Voltage" "")
    (property "ki_description" " ")
    (attr smd)
    (fp_text reference "C91" (at -1.06 0.465 90) (layer "B.SilkS")
        (effects (font (size 0.7 0.7) (thickness 0.15)) (justify left bottom mirror))
    )
    (fp_text value "C_100n_0201" (at 0 -1.4 90) (layer "B.Fab") hide
        (effects (font (size 0.7 0.7) (thickness 0.15)) (justify left bottom mirror))
    )
    (fp_text user "${REFERENCE}" (at -0.72 -3.4 90) (layer "B.Fab") hide
        (effects (font (size 0.7 0.7) (thickness 0.15)) (justify left bottom mirror))
    )
    (fp_text user "License: Apache-2.0" (at -0.72 -4.4 90) (layer "B.Fab") hide
        (effects (font (size 0.7 0.7) (thickness 0.15)) (justify left bottom mirror))
    )
    (fp_text user "Author: Antmicro" (at -0.72 -5.4 90) (layer "B.Fab") hide
        (effects (font (size 0.7 0.7) (thickness 0.15)) (justify left bottom mirror))
    )
    (fp_rect (start -0.72 0.38) (end 0.72 -0.38)
      (stroke (width 0.05) (type solid)) (fill none) (layer "B.CrtYd"))
    (fp_rect (start 0.3 -0.15) (end -0.301 0.149)
      (stroke (width 0.15) (type solid)) (fill none) (layer "B.Fab"))
    (pad "" smd roundrect (at -0.349 0.002 270) (size 0.318 0.36) (layers "B.Paste") (roundrect_rratio 0.25))
    (pad "" smd roundrect (at 0.341 0.002 270) (size 0.318 0.36) (layers "B.Paste") (roundrect_rratio 0.25))
    (pad "1" smd roundrect (at -0.321 0.002 270) (size 0.46 0.4) (layers "B.Cu" "B.Mask") (roundrect_rratio 0.25)
      (net 143 "3V3_SYS") (pintype "passive"))
    (pad "2" smd roundrect (at 0.32 0.002 270) (size 0.46 0.4) (layers "B.Cu" "B.Mask") (roundrect_rratio 0.25)
      (net 9 "GND") (pintype "passive"))
  )

  (footprint "data-center-rdimm-ddr4-tester-footprints:C_0402_1005Metric" (layer "B.Cu")
    (at 226.3 126.3 90)
    (descr "Capacitor SMD 0402")
    (tags "capacitor SMD 0402")
    (property "Author" "Antmicro")
    (property "Dielectric" "")
    (property "License" "Apache-2.0")
    (property "MPN" "C0402C105M4PACTU")
    (property "Manufacturer" "KEMET")
    (property "Sheetfile" "supply.kicad_sch")
    (property "Sheetname" "Supply")
    (property "Val" "1u/16V")
    (property "Voltage" "")
    (property "ki_description" " ")
    (attr smd)
    (fp_text reference "C280" (at 1.45 -0.59 270) (layer "B.SilkS")
        (effects (font (size 0.7 0.7) (thickness 0.15)) (justify left bottom mirror))
    )
    (fp_text value "C_1u_16V_0402" (at 0 -1.4 270) (layer "B.Fab") hide
        (effects (font (size 0.7 0.7) (thickness 0.15)) (justify left bottom mirror))
    )
    (fp_text user "${REFERENCE}" (at -0.932 -3.168 270) (layer "B.Fab") hide
        (effects (font (size 0.7 0.7) (thickness 0.15)) (justify left bottom mirror))
    )
    (fp_text user "License: Apache-2.0" (at -0.932 -5.17 270) (layer "B.Fab") hide
        (effects (font (size 0.7 0.7) (thickness 0.15)) (justify left bottom mirror))
    )
    (fp_text user "Author: Antmicro" (at -0.932 -4.17 270) (layer "B.Fab") hide
        (effects (font (size 0.7 0.7) (thickness 0.15)) (justify left bottom mirror))
    )
    (fp_rect (start -0.94 0.47) (end 0.94 -0.47)
      (stroke (width 0.05) (type solid)) (fill none) (layer "B.CrtYd"))
    (fp_rect (start -0.499 0.249) (end 0.499 -0.249)
      (stroke (width 0.15) (type solid)) (fill none) (layer "B.Fab"))
    (pad "1" smd roundrect (at -0.484 0 90) (size 0.59 0.64) (layers "B.Cu" "B.Paste" "B.Mask") (roundrect_rratio 0.25)
      (net 103 "VIN") (pintype "passive"))
    (pad "2" smd roundrect (at 0.484 0 90) (size 0.59 0.64) (layers "B.Cu" "B.Paste" "B.Mask") (roundrect_rratio 0.25)
      (net 9 "GND") (pintype "passive"))
  )

  (footprint "data-center-rdimm-ddr4-tester-footprints:R_0402_1005Metric" (layer "B.Cu")
    (at 123 97.95)
    (descr "Resistor SMD 0402")
    (tags "resistor SMD 0402")
    (property "Author" "Antmicro")
    (property "License" "Apache-2.0")
    (property "MPN" "CR0402-FX-1002GLF")
    (property "Manufacturer" "Bourns")
    (property "Sheetfile" "supply.kicad_sch")
    (property "Sheetname" "Supply")
    (property "Tolerance" "1%")
    (property "Val" "10k")
    (property "ki_description" "10k resistor in 0402 package with 1% tolerance")
    (attr smd)
    (fp_text reference "R216" (at 1.81 1.32 180) (layer "B.SilkS")
        (effects (font (size 0.7 0.7) (thickness 0.15)) (justify left bottom mirror))
    )
    (fp_text value "R_10k_0402" (at 0 -1.4 180) (layer "B.Fab") hide
        (effects (font (size 0.7 0.7) (thickness 0.15)) (justify left bottom mirror))
    )
    (fp_text user "License: Apache-2.0" (at -0.95 -5.169 180) (layer "B.Fab") hide
        (effects (font (size 0.7 0.7) (thickness 0.15)) (justify left bottom mirror))
    )
    (fp_text user "${REFERENCE}" (at -0.95 -3.168 180) (layer "B.Fab") hide
        (effects (font (size 0.7 0.7) (thickness 0.15)) (justify left bottom mirror))
    )
    (fp_text user "Author: Antmicro" (at -0.95 -4.169 180) (layer "B.Fab") hide
        (effects (font (size 0.7 0.7) (thickness 0.15)) (justify left bottom mirror))
    )
    (fp_rect (start -0.93 0.47) (end 0.93 -0.47)
      (stroke (width 0.05) (type solid)) (fill none) (layer "B.CrtYd"))
    (fp_rect (start -0.5 0.25) (end 0.5 -0.25)
      (stroke (width 0.15) (type solid)) (fill none) (layer "B.Fab"))
    (pad "1" smd roundrect (at -0.485 0) (size 0.59 0.64) (layers "B.Cu" "B.Paste" "B.Mask") (roundrect_rratio 0.25)
      (net 794 "/Supply/SLP_S4") (pintype "passive"))
    (pad "2" smd roundrect (at 0.485 0) (size 0.59 0.64) (layers "B.Cu" "B.Paste" "B.Mask") (roundrect_rratio 0.25)
      (net 9 "GND") (pintype "passive"))
  )

  (footprint "data-center-rdimm-ddr4-tester-footprints:SOT-23-5" (layer "B.Cu")
    (at 229.1 125.8)
    (property "Author" "Antmicro")
    (property "License" "Apache-2.0")
    (property "MPN" "NCP718ASN500T1G")
    (property "Manufacturer" "ON Semiconductor")
    (property "Sheetfile" "supply.kicad_sch")
    (property "Sheetname" "Supply")
    (property "ki_description" "LDO Voltage Regulators 300 MA LOW IQ WIDE INPUT 5.0V")
    (attr smd)
    (fp_text reference "U25" (at -2.5 2.6) (layer "B.SilkS")
        (effects (font (size 0.7 0.7) (thickness 0.15)) (justify right bottom mirror))
    )
    (fp_text value "NCP718ASN500_SOT" (at 0.002 -2.799) (layer "B.Fab") hide
        (effects (font (size 0.7 0.7) (thickness 0.15)) (justify right bottom mirror))
    )
    (fp_text user "${REFERENCE}" (at -1.898 -4.299) (layer "B.Fab") hide
        (effects (font (size 0.7 0.7) (thickness 0.15)) (justify right bottom mirror))
    )
    (fp_text user "Author: Antmicro" (at -1.898 -5.499) (layer "B.Fab") hide
        (effects (font (size 0.7 0.7) (thickness 0.15)) (justify right bottom mirror))
    )
    (fp_text user "License: Apache-2.0" (at -1.898 -6.7) (layer "B.Fab") hide
        (effects (font (size 0.7 0.7) (thickness 0.15)) (justify right bottom mirror))
    )
    (fp_line (start -0.898 -1.699) (end -0.898 -1.4)
      (stroke (width 0.15) (type solid)) (layer "B.SilkS"))
    (fp_line (start -0.898 1.7) (end -0.898 1.4)
      (stroke (width 0.15) (type solid)) (layer "B.SilkS"))
    (fp_line (start -0.898 1.7) (end -0.598 1.7)
      (stroke (width 0.15) (type solid)) (layer "B.SilkS"))
    (fp_line (start -0.598 -1.699) (end -0.898 -1.699)
      (stroke (width 0.15) (type solid)) (layer "B.SilkS"))
    (fp_line (start 0.902 -1.699) (end 0.651 -1.699)
      (stroke (width 0.15) (type solid)) (layer "B.SilkS"))
    (fp_line (start 0.902 -1.4) (end 0.902 -1.699)
      (stroke (width 0.15) (type solid)) (layer "B.SilkS"))
    (fp_line (start 0.902 -0.55) (end 0.902 0.55)
      (stroke (width 0.15) (type solid)) (layer "B.SilkS"))
    (fp_line (start 0.902 1.4) (end 0.902 1.7)
      (stroke (width 0.15) (type solid)) (layer "B.SilkS"))
    (fp_line (start 0.902 1.7) (end 0.602 1.7)
      (stroke (width 0.15) (type solid)) (layer "B.SilkS"))
    (fp_circle (center -1.25 1.5) (end -1.2 1.5)
      (stroke (width 0.15) (type solid)) (fill solid) (layer "B.SilkS"))
    (fp_rect (start 1.9 1.81) (end -1.9 -1.8)
      (stroke (width 0.05) (type solid)) (fill none) (layer "B.CrtYd"))
    (fp_line (start -0.398 1.526) (end -0.874 1.05)
      (stroke (width 0.15) (type solid)) (layer "B.Fab"))
    (fp_rect (start 0.874 -1.523) (end -0.873 1.525)
      (stroke (width 0.15) (type solid)) (fill none) (layer "B.Fab"))
    (pad "1" smd rect (at -1.351 0.951 90) (size 0.55 1) (layers "B.Cu" "B.Paste" "B.Mask")
      (net 103 "VIN") (pinfunction "V_{IN}") (pintype "power_in"))
    (pad "2" smd rect (at -1.351 0 90) (size 0.55 1) (layers "B.Cu" "B.Paste" "B.Mask")
      (net 9 "GND") (pinfunction "GND") (pintype "power_in"))
    (pad "3" smd rect (at -1.351 -0.949 90) (size 0.55 1) (layers "B.Cu" "B.Paste" "B.Mask")
      (net 103 "VIN") (pinfunction "EN") (pintype "input"))
    (pad "4" smd rect (at 1.35 -0.949 90) (size 0.55 1) (layers "B.Cu" "B.Paste" "B.Mask")
      (net 919 "unconnected-(U25-NC-Pad4)") (pinfunction "NC") (pintype "no_connect"))
    (pad "5" smd rect (at 1.35 0.951 90) (size 0.55 1) (layers "B.Cu" "B.Paste" "B.Mask")
      (net 846 "5V_ON_OFF") (pinfunction "V_{OUT}") (pintype "power_out"))
  )

  (footprint "data-center-rdimm-ddr4-tester-footprints:FMC_SAMTEC_ASP-134486-01" (layer "B.Cu")
    (at 251 100 90)
    (descr "VITA 57.1 FMC – SEARAY™ HPC")
    (property "Author" "Antmicro")
    (property "License" "Apache-2.0")
    (property "MPN" "ASP-134486-01")
    (property "Manufacturer" "Samtec")
    (property "Sheetfile" "fmc_hpc.kicad_sch")
    (property "Sheetname" "FMC HPC")
    (property "ki_description" "400-pole 10-row 1.27mm Female FMC HPC Connector with gold-plated copper alloy contacts. ")
    (attr smd)
    (fp_text reference "J5" (at -28.4 4.01 270) (layer "B.SilkS")
        (effects (font (size 0.7 0.7) (thickness 0.15)) (justify left bottom mirror))
    )
    (fp_text value "ASP-134486-01" (at 0 -7.9 270) (layer "B.Fab") hide
        (effects (font (size 0.7 0.7) (thickness 0.15)) (justify left bottom mirror))
    )
    (fp_text user "License: Apache-2.0" (at -35 -10.257 270) (layer "B.Fab") hide
        (effects (font (size 0.7 0.7) (thickness 0.15)) (justify left bottom mirror))
    )
    (fp_text user "${REFERENCE}" (at -35 -9.057 270) (layer "B.Fab") hide
        (effects (font (size 0.7 0.7) (thickness 0.15)) (justify left bottom mirror))
    )
    (fp_text user "Author: Antmicro" (at -35 -11.457 270) (layer "B.Fab") hide
        (effects (font (size 0.7 0.7) (thickness 0.15)) (justify left bottom mirror))
    )
    (fp_poly
      (pts
        (xy -24.766 -5.717)
        (xy -25.211 -5.717)
        (xy -25.209 -5.738)
        (xy -25.208 -5.762)
        (xy -25.205 -5.785)
        (xy -25.2 -5.809)
        (xy -25.195 -5.831)
        (xy -25.188 -5.852)
        (xy -25.182 -5.874)
        (xy -25.173 -5.897)
        (xy -25.162 -5.918)
        (xy -25.151 -5.937)
        (xy -25.139 -5.958)
        (xy -25.125 -5.977)
        (xy -25.112 -5.996)
        (xy -25.096 -6.012)
        (xy -25.08 -6.03)
        (xy -25.063 -6.046)
        (xy -25.046 -6.06)
        (xy -25.028 -6.075)
        (xy -25.008 -6.087)
        (xy -24.988 -6.1)
        (xy -24.968 -6.111)
        (xy -24.947 -6.121)
        (xy -24.926 -6.131)
        (xy -24.903 -6.137)
        (xy -24.881 -6.144)
        (xy -24.86 -6.15)
        (xy -24.836 -6.155)
        (xy -24.813 -6.158)
        (xy -24.79 -6.158)
        (xy -24.766 -6.16)
        (xy -24.743 -6.158)
        (xy -24.718 -6.158)
        (xy -24.695 -6.155)
        (xy -24.673 -6.15)
        (xy -24.65 -6.144)
        (xy -24.627 -6.137)
        (xy -24.607 -6.129)
        (xy -24.584 -6.121)
        (xy -24.563 -6.11)
        (xy -24.543 -6.099)
        (xy -24.523 -6.087)
        (xy -24.503 -6.075)
        (xy -24.485 -6.06)
        (xy -24.467 -6.046)
        (xy -24.45 -6.03)
        (xy -24.435 -6.012)
        (xy -24.419 -5.994)
        (xy -24.406 -5.977)
        (xy -24.392 -5.956)
        (xy -24.38 -5.937)
        (xy -24.369 -5.916)
        (xy -24.359 -5.895)
        (xy -24.351 -5.873)
        (xy -24.342 -5.852)
        (xy -24.336 -5.829)
        (xy -24.33 -5.807)
        (xy -24.325 -5.785)
        (xy -24.322 -5.761)
        (xy -24.322 -5.738)
        (xy -24.32 -5.714)
        (xy -24.322 -5.692)
        (xy -24.322 -5.668)
        (xy -24.325 -5.644)
        (xy -24.33 -5.621)
        (xy -24.336 -5.599)
        (xy -24.342 -5.576)
        (xy -24.351 -5.555)
        (xy -24.359 -5.533)
        (xy -24.369 -5.512)
        (xy -24.38 -5.491)
        (xy -24.392 -5.472)
        (xy -24.406 -5.453)
        (xy -24.419 -5.434)
        (xy -24.435 -5.416)
        (xy -24.45 -5.4)
        (xy -24.467 -5.384)
        (xy -24.485 -5.368)
        (xy -24.503 -5.355)
        (xy -24.523 -5.341)
        (xy -24.543 -5.329)
        (xy -24.563 -5.318)
        (xy -24.584 -5.307)
        (xy -24.607 -5.299)
        (xy -24.627 -5.291)
        (xy -24.65 -5.285)
        (xy -24.673 -5.28)
        (xy -24.695 -5.275)
        (xy -24.718 -5.272)
        (xy -24.743 -5.27)
        (xy -24.766 -5.269)
        (xy -24.79 -5.27)
        (xy -24.813 -5.272)
        (xy -24.836 -5.275)
        (xy -24.86 -5.28)
        (xy -24.881 -5.285)
        (xy -24.903 -5.291)
        (xy -24.926 -5.299)
        (xy -24.947 -5.307)
        (xy -24.968 -5.317)
        (xy -24.988 -5.328)
        (xy -25.008 -5.341)
        (xy -25.028 -5.355)
        (xy -25.046 -5.368)
        (xy -25.063 -5.384)
        (xy -25.08 -5.4)
        (xy -25.096 -5.416)
        (xy -25.112 -5.434)
        (xy -25.125 -5.453)
        (xy -25.139 -5.472)
        (xy -25.151 -5.491)
        (xy -25.162 -5.511)
        (xy -25.173 -5.533)
        (xy -25.182 -5.554)
        (xy -25.188 -5.576)
        (xy -25.195 -5.599)
        (xy -25.2 -5.621)
        (xy -25.205 -5.644)
        (xy -25.208 -5.666)
        (xy -25.209 -5.69)
        (xy -25.211 -5.712)
        (xy -24.766 -5.712)
        (xy -24.766 -5.717)
      )

      (stroke (width 0.001) (type solid)) (fill solid) (layer "B.Paste"))
    (fp_poly
      (pts
        (xy -24.766 -3.177)
        (xy -25.211 -3.177)
        (xy -25.209 -3.198)
        (xy -25.208 -3.222)
        (xy -25.205 -3.245)
        (xy -25.2 -3.269)
        (xy -25.195 -3.29)
        (xy -25.188 -3.313)
        (xy -25.182 -3.334)
        (xy -25.173 -3.357)
        (xy -25.162 -3.378)
        (xy -25.151 -3.398)
        (xy -25.139 -3.418)
        (xy -25.125 -3.436)
        (xy -25.112 -3.455)
        (xy -25.096 -3.472)
        (xy -25.08 -3.49)
        (xy -25.063 -3.505)
        (xy -25.046 -3.52)
        (xy -25.028 -3.535)
        (xy -25.008 -3.547)
        (xy -24.988 -3.56)
        (xy -24.968 -3.571)
        (xy -24.947 -3.581)
        (xy -24.926 -3.591)
        (xy -24.903 -3.597)
        (xy -24.881 -3.604)
        (xy -24.86 -3.609)
        (xy -24.836 -3.615)
        (xy -24.813 -3.617)
        (xy -24.79 -3.619)
        (xy -24.766 -3.62)
        (xy -24.743 -3.619)
        (xy -24.718 -3.617)
        (xy -24.695 -3.615)
        (xy -24.673 -3.609)
        (xy -24.65 -3.604)
        (xy -24.627 -3.597)
        (xy -24.607 -3.589)
        (xy -24.584 -3.581)
        (xy -24.563 -3.571)
        (xy -24.543 -3.559)
        (xy -24.523 -3.547)
        (xy -24.503 -3.535)
        (xy -24.485 -3.52)
        (xy -24.467 -3.505)
        (xy -24.45 -3.49)
        (xy -24.435 -3.472)
        (xy -24.419 -3.454)
        (xy -24.406 -3.436)
        (xy -24.392 -3.416)
        (xy -24.38 -3.396)
        (xy -24.369 -3.376)
        (xy -24.359 -3.355)
        (xy -24.351 -3.334)
        (xy -24.342 -3.313)
        (xy -24.336 -3.289)
        (xy -24.33 -3.267)
        (xy -24.325 -3.245)
        (xy -24.322 -3.221)
        (xy -24.322 -3.197)
        (xy -24.32 -3.174)
        (xy -24.322 -3.152)
        (xy -24.322 -3.128)
        (xy -24.325 -3.104)
        (xy -24.33 -3.081)
        (xy -24.336 -3.059)
        (xy -24.342 -3.036)
        (xy -24.351 -3.015)
        (xy -24.359 -2.994)
        (xy -24.369 -2.972)
        (xy -24.38 -2.951)
        (xy -24.392 -2.932)
        (xy -24.406 -2.912)
        (xy -24.419 -2.894)
        (xy -24.435 -2.876)
        (xy -24.45 -2.859)
        (xy -24.467 -2.843)
        (xy -24.485 -2.829)
        (xy -24.503 -2.814)
        (xy -24.523 -2.801)
        (xy -24.543 -2.789)
        (xy -24.563 -2.778)
        (xy -24.584 -2.767)
        (xy -24.607 -2.759)
        (xy -24.627 -2.751)
        (xy -24.65 -2.745)
        (xy -24.673 -2.74)
        (xy -24.695 -2.734)
        (xy -24.718 -2.732)
        (xy -24.743 -2.73)
        (xy -24.766 -2.729)
        (xy -24.79 -2.73)
        (xy -24.813 -2.732)
        (xy -24.836 -2.734)
        (xy -24.86 -2.74)
        (xy -24.881 -2.745)
        (xy -24.903 -2.751)
        (xy -24.926 -2.758)
        (xy -24.947 -2.767)
        (xy -24.968 -2.777)
        (xy -24.988 -2.789)
        (xy -25.008 -2.801)
        (xy -25.028 -2.814)
        (xy -25.046 -2.829)
        (xy -25.063 -2.843)
        (xy -25.08 -2.859)
        (xy -25.096 -2.876)
        (xy -25.112 -2.894)
        (xy -25.125 -2.912)
        (xy -25.139 -2.931)
        (xy -25.151 -2.951)
        (xy -25.162 -2.971)
        (xy -25.173 -2.992)
        (xy -25.182 -3.015)
        (xy -25.188 -3.036)
        (xy -25.195 -3.059)
        (xy -25.2 -3.08)
        (xy -25.205 -3.104)
        (xy -25.208 -3.126)
        (xy -25.209 -3.15)
        (xy -25.211 -3.172)
        (xy -24.766 -3.172)
        (xy -24.766 -3.177)
      )

      (stroke (width 0.001) (type solid)) (fill solid) (layer "B.Paste"))
    (fp_poly
      (pts
        (xy -24.766 1.903)
        (xy -25.211 1.903)
        (xy -25.209 1.881)
        (xy -25.208 1.857)
        (xy -25.205 1.835)
        (xy -25.2 1.811)
        (xy -25.195 1.789)
        (xy -25.188 1.767)
        (xy -25.182 1.746)
        (xy -25.173 1.724)
        (xy -25.162 1.702)
        (xy -25.151 1.682)
        (xy -25.139 1.662)
        (xy -25.125 1.643)
        (xy -25.112 1.625)
        (xy -25.096 1.607)
        (xy -25.08 1.591)
        (xy -25.063 1.575)
        (xy -25.046 1.559)
        (xy -25.028 1.545)
        (xy -25.008 1.532)
        (xy -24.988 1.519)
        (xy -24.968 1.508)
        (xy -24.947 1.498)
        (xy -24.926 1.49)
        (xy -24.903 1.482)
        (xy -24.881 1.476)
        (xy -24.86 1.47)
        (xy -24.836 1.466)
        (xy -24.813 1.462)
        (xy -24.79 1.462)
        (xy -24.766 1.46)
        (xy -24.743 1.462)
        (xy -24.718 1.462)
        (xy -24.695 1.466)
        (xy -24.673 1.47)
        (xy -24.65 1.476)
        (xy -24.627 1.482)
        (xy -24.607 1.49)
        (xy -24.584 1.498)
        (xy -24.563 1.509)
        (xy -24.543 1.52)
        (xy -24.523 1.532)
        (xy -24.503 1.545)
        (xy -24.485 1.559)
        (xy -24.467 1.575)
        (xy -24.45 1.591)
        (xy -24.435 1.607)
        (xy -24.419 1.625)
        (xy -24.406 1.643)
        (xy -24.392 1.663)
        (xy -24.38 1.684)
        (xy -24.369 1.704)
        (xy -24.359 1.724)
        (xy -24.351 1.746)
        (xy -24.342 1.767)
        (xy -24.336 1.79)
        (xy -24.33 1.813)
        (xy -24.325 1.835)
        (xy -24.322 1.859)
        (xy -24.322 1.882)
        (xy -24.32 1.905)
        (xy -24.322 1.928)
        (xy -24.322 1.952)
        (xy -24.325 1.976)
        (xy -24.33 1.998)
        (xy -24.336 2.02)
        (xy -24.342 2.044)
        (xy -24.351 2.065)
        (xy -24.359 2.086)
        (xy -24.369 2.108)
        (xy -24.38 2.127)
        (xy -24.392 2.147)
        (xy -24.406 2.167)
        (xy -24.419 2.186)
        (xy -24.435 2.203)
        (xy -24.45 2.221)
        (xy -24.467 2.237)
        (xy -24.485 2.251)
        (xy -24.503 2.266)
        (xy -24.523 2.278)
        (xy -24.543 2.29)
        (xy -24.563 2.302)
        (xy -24.584 2.312)
        (xy -24.607 2.32)
        (xy -24.627 2.328)
        (xy -24.65 2.335)
        (xy -24.673 2.34)
        (xy -24.695 2.346)
        (xy -24.718 2.348)
        (xy -24.743 2.35)
        (xy -24.766 2.351)
        (xy -24.79 2.35)
        (xy -24.813 2.348)
        (xy -24.836 2.346)
        (xy -24.86 2.34)
        (xy -24.881 2.335)
        (xy -24.903 2.328)
        (xy -24.926 2.322)
        (xy -24.947 2.312)
        (xy -24.968 2.302)
        (xy -24.988 2.291)
        (xy -25.008 2.278)
        (xy -25.028 2.266)
        (xy -25.046 2.251)
        (xy -25.063 2.237)
        (xy -25.08 2.221)
        (xy -25.096 2.203)
        (xy -25.112 2.186)
        (xy -25.125 2.167)
        (xy -25.139 2.149)
        (xy -25.151 2.129)
        (xy -25.162 2.109)
        (xy -25.173 2.088)
        (xy -25.182 2.065)
        (xy -25.188 2.044)
        (xy -25.195 2.021)
        (xy -25.2 2)
        (xy -25.205 1.976)
        (xy -25.208 1.954)
        (xy -25.209 1.93)
        (xy -25.211 1.907)
        (xy -24.766 1.907)
        (xy -24.766 1.903)
      )

      (stroke (width 0.001) (type solid)) (fill solid) (layer "B.Paste"))
    (fp_poly
      (pts
        (xy -24.766 3.173)
        (xy -25.211 3.173)
        (xy -25.209 3.151)
        (xy -25.208 3.127)
        (xy -25.205 3.105)
        (xy -25.2 3.081)
        (xy -25.195 3.06)
        (xy -25.188 3.037)
        (xy -25.182 3.016)
        (xy -25.173 2.993)
        (xy -25.162 2.972)
        (xy -25.151 2.952)
        (xy -25.139 2.932)
        (xy -25.125 2.913)
        (xy -25.112 2.895)
        (xy -25.096 2.877)
        (xy -25.08 2.86)
        (xy -25.063 2.844)
        (xy -25.046 2.83)
        (xy -25.028 2.815)
        (xy -25.008 2.802)
        (xy -24.988 2.79)
        (xy -24.968 2.778)
        (xy -24.947 2.768)
        (xy -24.926 2.759)
        (xy -24.903 2.752)
        (xy -24.881 2.746)
        (xy -24.86 2.741)
        (xy -24.836 2.735)
        (xy -24.813 2.733)
        (xy -24.79 2.731)
        (xy -24.766 2.73)
        (xy -24.743 2.731)
        (xy -24.718 2.733)
        (xy -24.695 2.735)
        (xy -24.673 2.741)
        (xy -24.65 2.746)
        (xy -24.627 2.752)
        (xy -24.607 2.76)
        (xy -24.584 2.768)
        (xy -24.563 2.779)
        (xy -24.543 2.79)
        (xy -24.523 2.802)
        (xy -24.503 2.815)
        (xy -24.485 2.83)
        (xy -24.467 2.844)
        (xy -24.45 2.86)
        (xy -24.435 2.877)
        (xy -24.419 2.895)
        (xy -24.406 2.913)
        (xy -24.392 2.933)
        (xy -24.38 2.952)
        (xy -24.369 2.973)
        (xy -24.359 2.995)
        (xy -24.351 3.016)
        (xy -24.342 3.037)
        (xy -24.336 3.06)
        (xy -24.33 3.082)
        (xy -24.325 3.105)
        (xy -24.322 3.129)
        (xy -24.322 3.153)
        (xy -24.32 3.175)
        (xy -24.322 3.198)
        (xy -24.322 3.222)
        (xy -24.325 3.246)
        (xy -24.33 3.268)
        (xy -24.336 3.29)
        (xy -24.342 3.314)
        (xy -24.351 3.335)
        (xy -24.359 3.356)
        (xy -24.369 3.377)
        (xy -24.38 3.397)
        (xy -24.392 3.417)
        (xy -24.406 3.437)
        (xy -24.419 3.455)
        (xy -24.435 3.473)
        (xy -24.45 3.491)
        (xy -24.467 3.506)
        (xy -24.485 3.521)
        (xy -24.503 3.536)
        (xy -24.523 3.548)
        (xy -24.543 3.56)
        (xy -24.563 3.572)
        (xy -24.584 3.582)
        (xy -24.607 3.59)
        (xy -24.627 3.598)
        (xy -24.65 3.605)
        (xy -24.673 3.61)
        (xy -24.695 3.616)
        (xy -24.718 3.618)
        (xy -24.743 3.62)
        (xy -24.766 3.621)
        (xy -24.79 3.62)
        (xy -24.813 3.618)
        (xy -24.836 3.616)
        (xy -24.86 3.61)
        (xy -24.881 3.605)
        (xy -24.903 3.598)
        (xy -24.926 3.592)
        (xy -24.947 3.582)
        (xy -24.968 3.572)
        (xy -24.988 3.561)
        (xy -25.008 3.548)
        (xy -25.028 3.536)
        (xy -25.046 3.521)
        (xy -25.063 3.506)
        (xy -25.08 3.491)
        (xy -25.096 3.473)
        (xy -25.112 3.456)
        (xy -25.125 3.437)
        (xy -25.139 3.419)
        (xy -25.151 3.399)
        (xy -25.162 3.379)
        (xy -25.173 3.358)
        (xy -25.182 3.335)
        (xy -25.188 3.314)
        (xy -25.195 3.291)
        (xy -25.2 3.27)
        (xy -25.205 3.246)
        (xy -25.208 3.223)
        (xy -25.209 3.199)
        (xy -25.211 3.178)
        (xy -24.766 3.178)
        (xy -24.766 3.173)
      )

      (stroke (width 0.001) (type solid)) (fill solid) (layer "B.Paste"))
    (fp_poly
      (pts
        (xy -24.766 4.443)
        (xy -25.211 4.443)
        (xy -25.209 4.422)
        (xy -25.208 4.398)
        (xy -25.205 4.374)
        (xy -25.2 4.351)
        (xy -25.195 4.329)
        (xy -25.188 4.308)
        (xy -25.182 4.286)
        (xy -25.173 4.263)
        (xy -25.162 4.242)
        (xy -25.151 4.223)
        (xy -25.139 4.202)
        (xy -25.125 4.183)
        (xy -25.112 4.164)
        (xy -25.096 4.148)
        (xy -25.08 4.13)
        (xy -25.063 4.114)
        (xy -25.046 4.1)
        (xy -25.028 4.085)
        (xy -25.008 4.072)
        (xy -24.988 4.06)
        (xy -24.968 4.048)
        (xy -24.947 4.039)
        (xy -24.926 4.029)
        (xy -24.903 4.023)
        (xy -24.881 4.015)
        (xy -24.86 4.01)
        (xy -24.836 4.005)
        (xy -24.813 4.002)
        (xy -24.79 4.002)
        (xy -24.766 4)
        (xy -24.743 4.002)
        (xy -24.718 4.002)
        (xy -24.695 4.005)
        (xy -24.673 4.01)
        (xy -24.65 4.015)
        (xy -24.627 4.023)
        (xy -24.607 4.031)
        (xy -24.584 4.039)
        (xy -24.563 4.05)
        (xy -24.543 4.06)
        (xy -24.523 4.072)
        (xy -24.503 4.085)
        (xy -24.485 4.1)
        (xy -24.467 4.114)
        (xy -24.45 4.13)
        (xy -24.435 4.148)
        (xy -24.419 4.165)
        (xy -24.406 4.183)
        (xy -24.392 4.204)
        (xy -24.38 4.223)
        (xy -24.369 4.244)
        (xy -24.359 4.265)
        (xy -24.351 4.286)
        (xy -24.342 4.308)
        (xy -24.336 4.33)
        (xy -24.33 4.353)
        (xy -24.325 4.375)
        (xy -24.322 4.398)
        (xy -24.322 4.422)
        (xy -24.32 4.446)
        (xy -24.322 4.468)
        (xy -24.322 4.492)
        (xy -24.325 4.515)
        (xy -24.33 4.539)
        (xy -24.336 4.56)
        (xy -24.342 4.584)
        (xy -24.351 4.604)
        (xy -24.359 4.627)
        (xy -24.369 4.648)
        (xy -24.38 4.669)
        (xy -24.392 4.688)
        (xy -24.406 4.707)
        (xy -24.419 4.725)
        (xy -24.435 4.744)
        (xy -24.45 4.76)
        (xy -24.467 4.776)
        (xy -24.485 4.792)
        (xy -24.503 4.805)
        (xy -24.523 4.818)
        (xy -24.543 4.83)
        (xy -24.563 4.842)
        (xy -24.584 4.853)
        (xy -24.607 4.861)
        (xy -24.627 4.869)
        (xy -24.65 4.875)
        (xy -24.673 4.88)
        (xy -24.695 4.885)
        (xy -24.718 4.888)
        (xy -24.743 4.89)
        (xy -24.766 4.89)
        (xy -24.79 4.89)
        (xy -24.813 4.888)
        (xy -24.836 4.885)
        (xy -24.86 4.88)
        (xy -24.881 4.875)
        (xy -24.903 4.869)
        (xy -24.926 4.861)
        (xy -24.947 4.853)
        (xy -24.968 4.842)
        (xy -24.988 4.832)
        (xy -25.008 4.818)
        (xy -25.028 4.805)
        (xy -25.046 4.792)
        (xy -25.063 4.776)
        (xy -25.08 4.76)
        (xy -25.096 4.744)
        (xy -25.112 4.726)
        (xy -25.125 4.707)
        (xy -25.139 4.688)
        (xy -25.151 4.669)
        (xy -25.162 4.648)
        (xy -25.173 4.627)
        (xy -25.182 4.606)
        (xy -25.188 4.584)
        (xy -25.195 4.561)
        (xy -25.2 4.539)
        (xy -25.205 4.516)
        (xy -25.208 4.494)
        (xy -25.209 4.47)
        (xy -25.211 4.447)
        (xy -24.766 4.447)
        (xy -24.766 4.443)
      )

      (stroke (width 0.001) (type solid)) (fill solid) (layer "B.Paste"))
    (fp_poly
      (pts
        (xy -24.766 5.713)
        (xy -25.211 5.713)
        (xy -25.209 5.691)
        (xy -25.208 5.667)
        (xy -25.205 5.645)
        (xy -25.2 5.622)
        (xy -25.195 5.6)
        (xy -25.188 5.577)
        (xy -25.182 5.555)
        (xy -25.173 5.534)
        (xy -25.162 5.512)
        (xy -25.151 5.492)
        (xy -25.139 5.473)
        (xy -25.125 5.454)
        (xy -25.112 5.435)
        (xy -25.096 5.417)
        (xy -25.08 5.401)
        (xy -25.063 5.385)
        (xy -25.046 5.369)
        (xy -25.028 5.356)
        (xy -25.008 5.342)
        (xy -24.988 5.329)
        (xy -24.968 5.318)
        (xy -24.947 5.308)
        (xy -24.926 5.3)
        (xy -24.903 5.292)
        (xy -24.881 5.286)
        (xy -24.86 5.281)
        (xy -24.836 5.276)
        (xy -24.813 5.273)
        (xy -24.79 5.271)
        (xy -24.766 5.27)
        (xy -24.743 5.271)
        (xy -24.718 5.273)
        (xy -24.695 5.276)
        (xy -24.673 5.281)
        (xy -24.65 5.286)
        (xy -24.627 5.292)
        (xy -24.607 5.3)
        (xy -24.584 5.308)
        (xy -24.563 5.319)
        (xy -24.543 5.33)
        (xy -24.523 5.342)
        (xy -24.503 5.356)
        (xy -24.485 5.369)
        (xy -24.467 5.385)
        (xy -24.45 5.401)
        (xy -24.435 5.417)
        (xy -24.419 5.435)
        (xy -24.406 5.454)
        (xy -24.392 5.473)
        (xy -24.38 5.492)
        (xy -24.369 5.513)
        (xy -24.359 5.534)
        (xy -24.351 5.556)
        (xy -24.342 5.577)
        (xy -24.336 5.6)
        (xy -24.33 5.622)
        (xy -24.325 5.645)
        (xy -24.322 5.669)
        (xy -24.322 5.693)
        (xy -24.32 5.715)
        (xy -24.322 5.739)
        (xy -24.322 5.762)
        (xy -24.325 5.786)
        (xy -24.33 5.808)
        (xy -24.336 5.83)
        (xy -24.342 5.853)
        (xy -24.351 5.874)
        (xy -24.359 5.896)
        (xy -24.369 5.917)
        (xy -24.38 5.938)
        (xy -24.392 5.957)
        (xy -24.406 5.978)
        (xy -24.419 5.995)
        (xy -24.435 6.013)
        (xy -24.45 6.031)
        (xy -24.467 6.047)
        (xy -24.485 6.061)
        (xy -24.503 6.076)
        (xy -24.523 6.088)
        (xy -24.543 6.1)
        (xy -24.563 6.111)
        (xy -24.584 6.122)
        (xy -24.607 6.13)
        (xy -24.627 6.138)
        (xy -24.65 6.145)
        (xy -24.673 6.151)
        (xy -24.695 6.156)
        (xy -24.718 6.159)
        (xy -24.743 6.159)
        (xy -24.766 6.161)
        (xy -24.79 6.159)
        (xy -24.813 6.159)
        (xy -24.836 6.156)
        (xy -24.86 6.151)
        (xy -24.881 6.145)
        (xy -24.903 6.138)
        (xy -24.926 6.132)
        (xy -24.947 6.122)
        (xy -24.968 6.112)
        (xy -24.988 6.101)
        (xy -25.008 6.088)
        (xy -25.028 6.076)
        (xy -25.046 6.061)
        (xy -25.063 6.047)
        (xy -25.08 6.031)
        (xy -25.096 6.013)
        (xy -25.112 5.997)
        (xy -25.125 5.978)
        (xy -25.139 5.959)
        (xy -25.151 5.938)
        (xy -25.162 5.919)
        (xy -25.173 5.898)
        (xy -25.182 5.875)
        (xy -25.188 5.853)
        (xy -25.195 5.832)
        (xy -25.2 5.81)
        (xy -25.205 5.786)
        (xy -25.208 5.763)
        (xy -25.209 5.739)
        (xy -25.211 5.718)
        (xy -24.766 5.718)
        (xy -24.766 5.713)
      )

      (stroke (width 0.001) (type solid)) (fill solid) (layer "B.Paste"))
    (fp_poly
      (pts
        (xy -23.496 -5.717)
        (xy -23.941 -5.717)
        (xy -23.939 -5.738)
        (xy -23.938 -5.762)
        (xy -23.935 -5.785)
        (xy -23.93 -5.809)
        (xy -23.926 -5.831)
        (xy -23.918 -5.852)
        (xy -23.912 -5.874)
        (xy -23.903 -5.897)
        (xy -23.892 -5.918)
        (xy -23.881 -5.937)
        (xy -23.868 -5.958)
        (xy -23.855 -5.977)
        (xy -23.842 -5.996)
        (xy -23.827 -6.012)
        (xy -23.81 -6.03)
        (xy -23.793 -6.046)
        (xy -23.776 -6.06)
        (xy -23.758 -6.075)
        (xy -23.738 -6.087)
        (xy -23.718 -6.1)
        (xy -23.698 -6.111)
        (xy -23.677 -6.121)
        (xy -23.656 -6.131)
        (xy -23.633 -6.137)
        (xy -23.612 -6.144)
        (xy -23.589 -6.15)
        (xy -23.566 -6.155)
        (xy -23.543 -6.158)
        (xy -23.519 -6.158)
        (xy -23.496 -6.16)
        (xy -23.473 -6.158)
        (xy -23.448 -6.158)
        (xy -23.426 -6.155)
        (xy -23.403 -6.15)
        (xy -23.38 -6.144)
        (xy -23.357 -6.137)
        (xy -23.336 -6.129)
        (xy -23.314 -6.121)
        (xy -23.293 -6.11)
        (xy -23.273 -6.099)
        (xy -23.253 -6.087)
        (xy -23.234 -6.075)
        (xy -23.215 -6.06)
        (xy -23.197 -6.046)
        (xy -23.18 -6.03)
        (xy -23.165 -6.012)
        (xy -23.15 -5.994)
        (xy -23.136 -5.977)
        (xy -23.122 -5.956)
        (xy -23.11 -5.937)
        (xy -23.099 -5.916)
        (xy -23.089 -5.895)
        (xy -23.08 -5.873)
        (xy -23.072 -5.852)
        (xy -23.066 -5.829)
        (xy -23.06 -5.807)
        (xy -23.055 -5.785)
        (xy -23.052 -5.761)
        (xy -23.051 -5.738)
        (xy -23.051 -5.714)
        (xy -23.051 -5.692)
        (xy -23.052 -5.668)
        (xy -23.055 -5.644)
        (xy -23.06 -5.621)
        (xy -23.066 -5.599)
        (xy -23.072 -5.576)
        (xy -23.08 -5.555)
        (xy -23.089 -5.533)
        (xy -23.099 -5.512)
        (xy -23.11 -5.491)
        (xy -23.122 -5.472)
        (xy -23.136 -5.453)
        (xy -23.15 -5.434)
        (xy -23.165 -5.416)
        (xy -23.18 -5.4)
        (xy -23.197 -5.384)
        (xy -23.215 -5.368)
        (xy -23.234 -5.355)
        (xy -23.253 -5.341)
        (xy -23.273 -5.329)
        (xy -23.293 -5.318)
        (xy -23.314 -5.307)
        (xy -23.336 -5.299)
        (xy -23.357 -5.291)
        (xy -23.38 -5.285)
        (xy -23.403 -5.28)
        (xy -23.426 -5.275)
        (xy -23.448 -5.272)
        (xy -23.473 -5.27)
        (xy -23.496 -5.269)
        (xy -23.519 -5.27)
        (xy -23.543 -5.272)
        (xy -23.566 -5.275)
        (xy -23.589 -5.28)
        (xy -23.612 -5.285)
        (xy -23.633 -5.291)
        (xy -23.656 -5.299)
        (xy -23.677 -5.307)
        (xy -23.698 -5.317)
        (xy -23.718 -5.328)
        (xy -23.738 -5.341)
        (xy -23.758 -5.355)
        (xy -23.776 -5.368)
        (xy -23.793 -5.384)
        (xy -23.81 -5.4)
        (xy -23.827 -5.416)
        (xy -23.842 -5.434)
        (xy -23.855 -5.453)
        (xy -23.868 -5.472)
        (xy -23.881 -5.491)
        (xy -23.892 -5.511)
        (xy -23.903 -5.533)
        (xy -23.912 -5.554)
        (xy -23.918 -5.576)
        (xy -23.926 -5.599)
        (xy -23.93 -5.621)
        (xy -23.935 -5.644)
        (xy -23.938 -5.666)
        (xy -23.939 -5.69)
        (xy -23.941 -5.712)
        (xy -23.496 -5.712)
        (xy -23.496 -5.717)
      )

      (stroke (width 0.001) (type solid)) (fill solid) (layer "B.Paste"))
    (fp_poly
      (pts
        (xy -23.496 -3.177)
        (xy -23.941 -3.177)
        (xy -23.939 -3.198)
        (xy -23.938 -3.222)
        (xy -23.935 -3.245)
        (xy -23.93 -3.269)
        (xy -23.926 -3.29)
        (xy -23.918 -3.313)
        (xy -23.912 -3.334)
        (xy -23.903 -3.357)
        (xy -23.892 -3.378)
        (xy -23.881 -3.398)
        (xy -23.868 -3.418)
        (xy -23.855 -3.436)
        (xy -23.842 -3.455)
        (xy -23.827 -3.472)
        (xy -23.81 -3.49)
        (xy -23.793 -3.505)
        (xy -23.776 -3.52)
        (xy -23.758 -3.535)
        (xy -23.738 -3.547)
        (xy -23.718 -3.56)
        (xy -23.698 -3.571)
        (xy -23.677 -3.581)
        (xy -23.656 -3.591)
        (xy -23.633 -3.597)
        (xy -23.612 -3.604)
        (xy -23.589 -3.609)
        (xy -23.566 -3.615)
        (xy -23.543 -3.617)
        (xy -23.519 -3.619)
        (xy -23.496 -3.62)
        (xy -23.473 -3.619)
        (xy -23.448 -3.617)
        (xy -23.426 -3.615)
        (xy -23.403 -3.609)
        (xy -23.38 -3.604)
        (xy -23.357 -3.597)
        (xy -23.336 -3.589)
        (xy -23.314 -3.581)
        (xy -23.293 -3.571)
        (xy -23.273 -3.559)
        (xy -23.253 -3.547)
        (xy -23.234 -3.535)
        (xy -23.215 -3.52)
        (xy -23.197 -3.505)
        (xy -23.18 -3.49)
        (xy -23.165 -3.472)
        (xy -23.15 -3.454)
        (xy -23.136 -3.436)
        (xy -23.122 -3.416)
        (xy -23.11 -3.396)
        (xy -23.099 -3.376)
        (xy -23.089 -3.355)
        (xy -23.08 -3.334)
        (xy -23.072 -3.313)
        (xy -23.066 -3.289)
        (xy -23.06 -3.267)
        (xy -23.055 -3.245)
        (xy -23.052 -3.221)
        (xy -23.051 -3.197)
        (xy -23.051 -3.174)
        (xy -23.051 -3.152)
        (xy -23.052 -3.128)
        (xy -23.055 -3.104)
        (xy -23.06 -3.081)
        (xy -23.066 -3.059)
        (xy -23.072 -3.036)
        (xy -23.08 -3.015)
        (xy -23.089 -2.994)
        (xy -23.099 -2.972)
        (xy -23.11 -2.951)
        (xy -23.122 -2.932)
        (xy -23.136 -2.912)
        (xy -23.15 -2.894)
        (xy -23.165 -2.876)
        (xy -23.18 -2.859)
        (xy -23.197 -2.843)
        (xy -23.215 -2.829)
        (xy -23.234 -2.814)
        (xy -23.253 -2.801)
        (xy -23.273 -2.789)
        (xy -23.293 -2.778)
        (xy -23.314 -2.767)
        (xy -23.336 -2.759)
        (xy -23.357 -2.751)
        (xy -23.38 -2.745)
        (xy -23.403 -2.74)
        (xy -23.426 -2.734)
        (xy -23.448 -2.732)
        (xy -23.473 -2.73)
        (xy -23.496 -2.729)
        (xy -23.519 -2.73)
        (xy -23.543 -2.732)
        (xy -23.566 -2.734)
        (xy -23.589 -2.74)
        (xy -23.612 -2.745)
        (xy -23.633 -2.751)
        (xy -23.656 -2.758)
        (xy -23.677 -2.767)
        (xy -23.698 -2.777)
        (xy -23.718 -2.789)
        (xy -23.738 -2.801)
        (xy -23.758 -2.814)
        (xy -23.776 -2.829)
        (xy -23.793 -2.843)
        (xy -23.81 -2.859)
        (xy -23.827 -2.876)
        (xy -23.842 -2.894)
        (xy -23.855 -2.912)
        (xy -23.868 -2.931)
        (xy -23.881 -2.951)
        (xy -23.892 -2.971)
        (xy -23.903 -2.992)
        (xy -23.912 -3.015)
        (xy -23.918 -3.036)
        (xy -23.926 -3.059)
        (xy -23.93 -3.08)
        (xy -23.935 -3.104)
        (xy -23.938 -3.126)
        (xy -23.939 -3.15)
        (xy -23.941 -3.172)
        (xy -23.496 -3.172)
        (xy -23.496 -3.177)
      )

      (stroke (width 0.001) (type solid)) (fill solid) (layer "B.Paste"))
    (fp_poly
      (pts
        (xy -23.496 1.903)
        (xy -23.941 1.903)
        (xy -23.939 1.881)
        (xy -23.938 1.857)
        (xy -23.935 1.835)
        (xy -23.93 1.811)
        (xy -23.926 1.789)
        (xy -23.918 1.767)
        (xy -23.912 1.746)
        (xy -23.903 1.724)
        (xy -23.892 1.702)
        (xy -23.881 1.682)
        (xy -23.868 1.662)
        (xy -23.855 1.643)
        (xy -23.842 1.625)
        (xy -23.827 1.607)
        (xy -23.81 1.591)
        (xy -23.793 1.575)
        (xy -23.776 1.559)
        (xy -23.758 1.545)
        (xy -23.738 1.532)
        (xy -23.718 1.519)
        (xy -23.698 1.508)
        (xy -23.677 1.498)
        (xy -23.656 1.49)
        (xy -23.633 1.482)
        (xy -23.612 1.476)
        (xy -23.589 1.47)
        (xy -23.566 1.466)
        (xy -23.543 1.462)
        (xy -23.519 1.462)
        (xy -23.496 1.46)
        (xy -23.473 1.462)
        (xy -23.448 1.462)
        (xy -23.426 1.466)
        (xy -23.403 1.47)
        (xy -23.38 1.476)
        (xy -23.357 1.482)
        (xy -23.336 1.49)
        (xy -23.314 1.498)
        (xy -23.293 1.509)
        (xy -23.273 1.52)
        (xy -23.253 1.532)
        (xy -23.234 1.545)
        (xy -23.215 1.559)
        (xy -23.197 1.575)
        (xy -23.18 1.591)
        (xy -23.165 1.607)
        (xy -23.15 1.625)
        (xy -23.136 1.643)
        (xy -23.122 1.663)
        (xy -23.11 1.684)
        (xy -23.099 1.704)
        (xy -23.089 1.724)
        (xy -23.08 1.746)
        (xy -23.072 1.767)
        (xy -23.066 1.79)
        (xy -23.06 1.813)
        (xy -23.055 1.835)
        (xy -23.052 1.859)
        (xy -23.051 1.882)
        (xy -23.051 1.905)
        (xy -23.051 1.928)
        (xy -23.052 1.952)
        (xy -23.055 1.976)
        (xy -23.06 1.998)
        (xy -23.066 2.02)
        (xy -23.072 2.044)
        (xy -23.08 2.065)
        (xy -23.089 2.086)
        (xy -23.099 2.108)
        (xy -23.11 2.127)
        (xy -23.122 2.147)
        (xy -23.136 2.167)
        (xy -23.15 2.186)
        (xy -23.165 2.203)
        (xy -23.18 2.221)
        (xy -23.197 2.237)
        (xy -23.215 2.251)
        (xy -23.234 2.266)
        (xy -23.253 2.278)
        (xy -23.273 2.29)
        (xy -23.293 2.302)
        (xy -23.314 2.312)
        (xy -23.336 2.32)
        (xy -23.357 2.328)
        (xy -23.38 2.335)
        (xy -23.403 2.34)
        (xy -23.426 2.346)
        (xy -23.448 2.348)
        (xy -23.473 2.35)
        (xy -23.496 2.351)
        (xy -23.519 2.35)
        (xy -23.543 2.348)
        (xy -23.566 2.346)
        (xy -23.589 2.34)
        (xy -23.612 2.335)
        (xy -23.633 2.328)
        (xy -23.656 2.322)
        (xy -23.677 2.312)
        (xy -23.698 2.302)
        (xy -23.718 2.291)
        (xy -23.738 2.278)
        (xy -23.758 2.266)
        (xy -23.776 2.251)
        (xy -23.793 2.237)
        (xy -23.81 2.221)
        (xy -23.827 2.203)
        (xy -23.842 2.186)
        (xy -23.855 2.167)
        (xy -23.868 2.149)
        (xy -23.881 2.129)
        (xy -23.892 2.109)
        (xy -23.903 2.088)
        (xy -23.912 2.065)
        (xy -23.918 2.044)
        (xy -23.926 2.021)
        (xy -23.93 2)
        (xy -23.935 1.976)
        (xy -23.938 1.954)
        (xy -23.939 1.93)
        (xy -23.941 1.907)
        (xy -23.496 1.907)
        (xy -23.496 1.903)
      )

      (stroke (width 0.001) (type solid)) (fill solid) (layer "B.Paste"))
    (fp_poly
      (pts
        (xy -23.496 3.173)
        (xy -23.941 3.173)
        (xy -23.939 3.151)
        (xy -23.938 3.127)
        (xy -23.935 3.105)
        (xy -23.93 3.081)
        (xy -23.926 3.06)
        (xy -23.918 3.037)
        (xy -23.912 3.016)
        (xy -23.903 2.993)
        (xy -23.892 2.972)
        (xy -23.881 2.952)
        (xy -23.868 2.932)
        (xy -23.855 2.913)
        (xy -23.842 2.895)
        (xy -23.827 2.877)
        (xy -23.81 2.86)
        (xy -23.793 2.844)
        (xy -23.776 2.83)
        (xy -23.758 2.815)
        (xy -23.738 2.802)
        (xy -23.718 2.79)
        (xy -23.698 2.778)
        (xy -23.677 2.768)
        (xy -23.656 2.759)
        (xy -23.633 2.752)
        (xy -23.612 2.746)
        (xy -23.589 2.741)
        (xy -23.566 2.735)
        (xy -23.543 2.733)
        (xy -23.519 2.731)
        (xy -23.496 2.73)
        (xy -23.473 2.731)
        (xy -23.448 2.733)
        (xy -23.426 2.735)
        (xy -23.403 2.741)
        (xy -23.38 2.746)
        (xy -23.357 2.752)
        (xy -23.336 2.76)
        (xy -23.314 2.768)
        (xy -23.293 2.779)
        (xy -23.273 2.79)
        (xy -23.253 2.802)
        (xy -23.234 2.815)
        (xy -23.215 2.83)
        (xy -23.197 2.844)
        (xy -23.18 2.86)
        (xy -23.165 2.877)
        (xy -23.15 2.895)
        (xy -23.136 2.913)
        (xy -23.122 2.933)
        (xy -23.11 2.952)
        (xy -23.099 2.973)
        (xy -23.089 2.995)
        (xy -23.08 3.016)
        (xy -23.072 3.037)
        (xy -23.066 3.06)
        (xy -23.06 3.082)
        (xy -23.055 3.105)
        (xy -23.052 3.129)
        (xy -23.051 3.153)
        (xy -23.051 3.175)
        (xy -23.051 3.198)
        (xy -23.052 3.222)
        (xy -23.055 3.246)
        (xy -23.06 3.268)
        (xy -23.066 3.29)
        (xy -23.072 3.314)
        (xy -23.08 3.335)
        (xy -23.089 3.356)
        (xy -23.099 3.377)
        (xy -23.11 3.397)
        (xy -23.122 3.417)
        (xy -23.136 3.437)
        (xy -23.15 3.455)
        (xy -23.165 3.473)
        (xy -23.18 3.491)
        (xy -23.197 3.506)
        (xy -23.215 3.521)
        (xy -23.234 3.536)
        (xy -23.253 3.548)
        (xy -23.273 3.56)
        (xy -23.293 3.572)
        (xy -23.314 3.582)
        (xy -23.336 3.59)
        (xy -23.357 3.598)
        (xy -23.38 3.605)
        (xy -23.403 3.61)
        (xy -23.426 3.616)
        (xy -23.448 3.618)
        (xy -23.473 3.62)
        (xy -23.496 3.621)
        (xy -23.519 3.62)
        (xy -23.543 3.618)
        (xy -23.566 3.616)
        (xy -23.589 3.61)
        (xy -23.612 3.605)
        (xy -23.633 3.598)
        (xy -23.656 3.592)
        (xy -23.677 3.582)
        (xy -23.698 3.572)
        (xy -23.718 3.561)
        (xy -23.738 3.548)
        (xy -23.758 3.536)
        (xy -23.776 3.521)
        (xy -23.793 3.506)
        (xy -23.81 3.491)
        (xy -23.827 3.473)
        (xy -23.842 3.456)
        (xy -23.855 3.437)
        (xy -23.868 3.419)
        (xy -23.881 3.399)
        (xy -23.892 3.379)
        (xy -23.903 3.358)
        (xy -23.912 3.335)
        (xy -23.918 3.314)
        (xy -23.926 3.291)
        (xy -23.93 3.27)
        (xy -23.935 3.246)
        (xy -23.938 3.223)
        (xy -23.939 3.199)
        (xy -23.941 3.178)
        (xy -23.496 3.178)
        (xy -23.496 3.173)
      )

      (stroke (width 0.001) (type solid)) (fill solid) (layer "B.Paste"))
    (fp_poly
      (pts
        (xy -23.496 4.443)
        (xy -23.941 4.443)
        (xy -23.939 4.422)
        (xy -23.938 4.398)
        (xy -23.935 4.374)
        (xy -23.93 4.351)
        (xy -23.926 4.329)
        (xy -23.918 4.308)
        (xy -23.912 4.286)
        (xy -23.903 4.263)
        (xy -23.892 4.242)
        (xy -23.881 4.223)
        (xy -23.868 4.202)
        (xy -23.855 4.183)
        (xy -23.842 4.164)
        (xy -23.827 4.148)
        (xy -23.81 4.13)
        (xy -23.793 4.114)
        (xy -23.776 4.1)
        (xy -23.758 4.085)
        (xy -23.738 4.072)
        (xy -23.718 4.06)
        (xy -23.698 4.048)
        (xy -23.677 4.039)
        (xy -23.656 4.029)
        (xy -23.633 4.023)
        (xy -23.612 4.015)
        (xy -23.589 4.01)
        (xy -23.566 4.005)
        (xy -23.543 4.002)
        (xy -23.519 4.002)
        (xy -23.496 4)
        (xy -23.473 4.002)
        (xy -23.448 4.002)
        (xy -23.426 4.005)
        (xy -23.403 4.01)
        (xy -23.38 4.015)
        (xy -23.357 4.023)
        (xy -23.336 4.031)
        (xy -23.314 4.039)
        (xy -23.293 4.05)
        (xy -23.273 4.06)
        (xy -23.253 4.072)
        (xy -23.234 4.085)
        (xy -23.215 4.1)
        (xy -23.197 4.114)
        (xy -23.18 4.13)
        (xy -23.165 4.148)
        (xy -23.15 4.165)
        (xy -23.136 4.183)
        (xy -23.122 4.204)
        (xy -23.11 4.223)
        (xy -23.099 4.244)
        (xy -23.089 4.265)
        (xy -23.08 4.286)
        (xy -23.072 4.308)
        (xy -23.066 4.33)
        (xy -23.06 4.353)
        (xy -23.055 4.375)
        (xy -23.052 4.398)
        (xy -23.051 4.422)
        (xy -23.051 4.446)
        (xy -23.051 4.468)
        (xy -23.052 4.492)
        (xy -23.055 4.515)
        (xy -23.06 4.539)
        (xy -23.066 4.56)
        (xy -23.072 4.584)
        (xy -23.08 4.604)
        (xy -23.089 4.627)
        (xy -23.099 4.648)
        (xy -23.11 4.669)
        (xy -23.122 4.688)
        (xy -23.136 4.707)
        (xy -23.15 4.725)
        (xy -23.165 4.744)
        (xy -23.18 4.76)
        (xy -23.197 4.776)
        (xy -23.215 4.792)
        (xy -23.234 4.805)
        (xy -23.253 4.818)
        (xy -23.273 4.83)
        (xy -23.293 4.842)
        (xy -23.314 4.853)
        (xy -23.336 4.861)
        (xy -23.357 4.869)
        (xy -23.38 4.875)
        (xy -23.403 4.88)
        (xy -23.426 4.885)
        (xy -23.448 4.888)
        (xy -23.473 4.89)
        (xy -23.496 4.89)
        (xy -23.519 4.89)
        (xy -23.543 4.888)
        (xy -23.566 4.885)
        (xy -23.589 4.88)
        (xy -23.612 4.875)
        (xy -23.633 4.869)
        (xy -23.656 4.861)
        (xy -23.677 4.853)
        (xy -23.698 4.842)
        (xy -23.718 4.832)
        (xy -23.738 4.818)
        (xy -23.758 4.805)
        (xy -23.776 4.792)
        (xy -23.793 4.776)
        (xy -23.81 4.76)
        (xy -23.827 4.744)
        (xy -23.842 4.726)
        (xy -23.855 4.707)
        (xy -23.868 4.688)
        (xy -23.881 4.669)
        (xy -23.892 4.648)
        (xy -23.903 4.627)
        (xy -23.912 4.606)
        (xy -23.918 4.584)
        (xy -23.926 4.561)
        (xy -23.93 4.539)
        (xy -23.935 4.516)
        (xy -23.938 4.494)
        (xy -23.939 4.47)
        (xy -23.941 4.447)
        (xy -23.496 4.447)
        (xy -23.496 4.443)
      )

      (stroke (width 0.001) (type solid)) (fill solid) (layer "B.Paste"))
    (fp_poly
      (pts
        (xy -23.496 5.713)
        (xy -23.941 5.713)
        (xy -23.939 5.691)
        (xy -23.938 5.667)
        (xy -23.935 5.645)
        (xy -23.93 5.622)
        (xy -23.926 5.6)
        (xy -23.918 5.577)
        (xy -23.912 5.555)
        (xy -23.903 5.534)
        (xy -23.892 5.512)
        (xy -23.881 5.492)
        (xy -23.868 5.473)
        (xy -23.855 5.454)
        (xy -23.842 5.435)
        (xy -23.827 5.417)
        (xy -23.81 5.401)
        (xy -23.793 5.385)
        (xy -23.776 5.369)
        (xy -23.758 5.356)
        (xy -23.738 5.342)
        (xy -23.718 5.329)
        (xy -23.698 5.318)
        (xy -23.677 5.308)
        (xy -23.656 5.3)
        (xy -23.633 5.292)
        (xy -23.612 5.286)
        (xy -23.589 5.281)
        (xy -23.566 5.276)
        (xy -23.543 5.273)
        (xy -23.519 5.271)
        (xy -23.496 5.27)
        (xy -23.473 5.271)
        (xy -23.448 5.273)
        (xy -23.426 5.276)
        (xy -23.403 5.281)
        (xy -23.38 5.286)
        (xy -23.357 5.292)
        (xy -23.336 5.3)
        (xy -23.314 5.308)
        (xy -23.293 5.319)
        (xy -23.273 5.33)
        (xy -23.253 5.342)
        (xy -23.234 5.356)
        (xy -23.215 5.369)
        (xy -23.197 5.385)
        (xy -23.18 5.401)
        (xy -23.165 5.417)
        (xy -23.15 5.435)
        (xy -23.136 5.454)
        (xy -23.122 5.473)
        (xy -23.11 5.492)
        (xy -23.099 5.513)
        (xy -23.089 5.534)
        (xy -23.08 5.556)
        (xy -23.072 5.577)
        (xy -23.066 5.6)
        (xy -23.06 5.622)
        (xy -23.055 5.645)
        (xy -23.052 5.669)
        (xy -23.051 5.693)
        (xy -23.051 5.715)
        (xy -23.051 5.739)
        (xy -23.052 5.762)
        (xy -23.055 5.786)
        (xy -23.06 5.808)
        (xy -23.066 5.83)
        (xy -23.072 5.853)
        (xy -23.08 5.874)
        (xy -23.089 5.896)
        (xy -23.099 5.917)
        (xy -23.11 5.938)
        (xy -23.122 5.957)
        (xy -23.136 5.978)
        (xy -23.15 5.995)
        (xy -23.165 6.013)
        (xy -23.18 6.031)
        (xy -23.197 6.047)
        (xy -23.215 6.061)
        (xy -23.234 6.076)
        (xy -23.253 6.088)
        (xy -23.273 6.1)
        (xy -23.293 6.111)
        (xy -23.314 6.122)
        (xy -23.336 6.13)
        (xy -23.357 6.138)
        (xy -23.38 6.145)
        (xy -23.403 6.151)
        (xy -23.426 6.156)
        (xy -23.448 6.159)
        (xy -23.473 6.159)
        (xy -23.496 6.161)
        (xy -23.519 6.159)
        (xy -23.543 6.159)
        (xy -23.566 6.156)
        (xy -23.589 6.151)
        (xy -23.612 6.145)
        (xy -23.633 6.138)
        (xy -23.656 6.132)
        (xy -23.677 6.122)
        (xy -23.698 6.112)
        (xy -23.718 6.101)
        (xy -23.738 6.088)
        (xy -23.758 6.076)
        (xy -23.776 6.061)
        (xy -23.793 6.047)
        (xy -23.81 6.031)
        (xy -23.827 6.013)
        (xy -23.842 5.997)
        (xy -23.855 5.978)
        (xy -23.868 5.959)
        (xy -23.881 5.938)
        (xy -23.892 5.919)
        (xy -23.903 5.898)
        (xy -23.912 5.875)
        (xy -23.918 5.853)
        (xy -23.926 5.832)
        (xy -23.93 5.81)
        (xy -23.935 5.786)
        (xy -23.938 5.763)
        (xy -23.939 5.739)
        (xy -23.941 5.718)
        (xy -23.496 5.718)
        (xy -23.496 5.713)
      )

      (stroke (width 0.001) (type solid)) (fill solid) (layer "B.Paste"))
    (fp_poly
      (pts
        (xy -22.226 -5.717)
        (xy -22.671 -5.717)
        (xy -22.67 -5.738)
        (xy -22.668 -5.762)
        (xy -22.665 -5.785)
        (xy -22.66 -5.809)
        (xy -22.656 -5.831)
        (xy -22.648 -5.852)
        (xy -22.641 -5.874)
        (xy -22.633 -5.897)
        (xy -22.622 -5.918)
        (xy -22.612 -5.937)
        (xy -22.598 -5.958)
        (xy -22.586 -5.977)
        (xy -22.572 -5.996)
        (xy -22.557 -6.012)
        (xy -22.54 -6.03)
        (xy -22.523 -6.046)
        (xy -22.506 -6.06)
        (xy -22.487 -6.075)
        (xy -22.468 -6.087)
        (xy -22.448 -6.1)
        (xy -22.429 -6.111)
        (xy -22.407 -6.121)
        (xy -22.386 -6.131)
        (xy -22.363 -6.137)
        (xy -22.342 -6.144)
        (xy -22.319 -6.15)
        (xy -22.296 -6.155)
        (xy -22.273 -6.158)
        (xy -22.249 -6.158)
        (xy -22.226 -6.16)
        (xy -22.203 -6.158)
        (xy -22.179 -6.158)
        (xy -22.156 -6.155)
        (xy -22.133 -6.15)
        (xy -22.11 -6.144)
        (xy -22.087 -6.137)
        (xy -22.066 -6.129)
        (xy -22.045 -6.121)
        (xy -22.023 -6.11)
        (xy -22.003 -6.099)
        (xy -21.984 -6.087)
        (xy -21.964 -6.075)
        (xy -21.945 -6.06)
        (xy -21.927 -6.046)
        (xy -21.91 -6.03)
        (xy -21.894 -6.012)
        (xy -21.88 -5.994)
        (xy -21.865 -5.977)
        (xy -21.852 -5.956)
        (xy -21.84 -5.937)
        (xy -21.83 -5.916)
        (xy -21.819 -5.895)
        (xy -21.81 -5.873)
        (xy -21.802 -5.852)
        (xy -21.796 -5.829)
        (xy -21.79 -5.807)
        (xy -21.785 -5.785)
        (xy -21.782 -5.761)
        (xy -21.781 -5.738)
        (xy -21.781 -5.714)
        (xy -21.781 -5.692)
        (xy -21.782 -5.668)
        (xy -21.785 -5.644)
        (xy -21.79 -5.621)
        (xy -21.796 -5.599)
        (xy -21.802 -5.576)
        (xy -21.81 -5.555)
        (xy -21.819 -5.533)
        (xy -21.83 -5.512)
        (xy -21.84 -5.491)
        (xy -21.852 -5.472)
        (xy -21.865 -5.453)
        (xy -21.88 -5.434)
        (xy -21.894 -5.416)
        (xy -21.91 -5.4)
        (xy -21.927 -5.384)
        (xy -21.945 -5.368)
        (xy -21.964 -5.355)
        (xy -21.984 -5.341)
        (xy -22.003 -5.329)
        (xy -22.023 -5.318)
        (xy -22.045 -5.307)
        (xy -22.066 -5.299)
        (xy -22.087 -5.291)
        (xy -22.11 -5.285)
        (xy -22.133 -5.28)
        (xy -22.156 -5.275)
        (xy -22.179 -5.272)
        (xy -22.203 -5.27)
        (xy -22.226 -5.269)
        (xy -22.249 -5.27)
        (xy -22.273 -5.272)
        (xy -22.296 -5.275)
        (xy -22.319 -5.28)
        (xy -22.342 -5.285)
        (xy -22.363 -5.291)
        (xy -22.386 -5.299)
        (xy -22.407 -5.307)
        (xy -22.429 -5.317)
        (xy -22.448 -5.328)
        (xy -22.468 -5.341)
        (xy -22.487 -5.355)
        (xy -22.506 -5.368)
        (xy -22.523 -5.384)
        (xy -22.54 -5.4)
        (xy -22.557 -5.416)
        (xy -22.572 -5.434)
        (xy -22.586 -5.453)
        (xy -22.598 -5.472)
        (xy -22.612 -5.491)
        (xy -22.622 -5.511)
        (xy -22.633 -5.533)
        (xy -22.641 -5.554)
        (xy -22.648 -5.576)
        (xy -22.656 -5.599)
        (xy -22.66 -5.621)
        (xy -22.665 -5.644)
        (xy -22.668 -5.666)
        (xy -22.67 -5.69)
        (xy -22.671 -5.712)
        (xy -22.226 -5.712)
        (xy -22.226 -5.717)
      )

      (stroke (width 0.001) (type solid)) (fill solid) (layer "B.Paste"))
    (fp_poly
      (pts
        (xy -22.226 -3.177)
        (xy -22.671 -3.177)
        (xy -22.67 -3.198)
        (xy -22.668 -3.222)
        (xy -22.665 -3.245)
        (xy -22.66 -3.269)
        (xy -22.656 -3.29)
        (xy -22.648 -3.313)
        (xy -22.641 -3.334)
        (xy -22.633 -3.357)
        (xy -22.622 -3.378)
        (xy -22.612 -3.398)
        (xy -22.598 -3.418)
        (xy -22.586 -3.436)
        (xy -22.572 -3.455)
        (xy -22.557 -3.472)
        (xy -22.54 -3.49)
        (xy -22.523 -3.505)
        (xy -22.506 -3.52)
        (xy -22.487 -3.535)
        (xy -22.468 -3.547)
        (xy -22.448 -3.56)
        (xy -22.429 -3.571)
        (xy -22.407 -3.581)
        (xy -22.386 -3.591)
        (xy -22.363 -3.597)
        (xy -22.342 -3.604)
        (xy -22.319 -3.609)
        (xy -22.296 -3.615)
        (xy -22.273 -3.617)
        (xy -22.249 -3.619)
        (xy -22.226 -3.62)
        (xy -22.203 -3.619)
        (xy -22.179 -3.617)
        (xy -22.156 -3.615)
        (xy -22.133 -3.609)
        (xy -22.11 -3.604)
        (xy -22.087 -3.597)
        (xy -22.066 -3.589)
        (xy -22.045 -3.581)
        (xy -22.023 -3.571)
        (xy -22.003 -3.559)
        (xy -21.984 -3.547)
        (xy -21.964 -3.535)
        (xy -21.945 -3.52)
        (xy -21.927 -3.505)
        (xy -21.91 -3.49)
        (xy -21.894 -3.472)
        (xy -21.88 -3.454)
        (xy -21.865 -3.436)
        (xy -21.852 -3.416)
        (xy -21.84 -3.396)
        (xy -21.83 -3.376)
        (xy -21.819 -3.355)
        (xy -21.81 -3.334)
        (xy -21.802 -3.313)
        (xy -21.796 -3.289)
        (xy -21.79 -3.267)
        (xy -21.785 -3.245)
        (xy -21.782 -3.221)
        (xy -21.781 -3.197)
        (xy -21.781 -3.174)
        (xy -21.781 -3.152)
        (xy -21.782 -3.128)
        (xy -21.785 -3.104)
        (xy -21.79 -3.081)
        (xy -21.796 -3.059)
        (xy -21.802 -3.036)
        (xy -21.81 -3.015)
        (xy -21.819 -2.994)
        (xy -21.83 -2.972)
        (xy -21.84 -2.951)
        (xy -21.852 -2.932)
        (xy -21.865 -2.912)
        (xy -21.88 -2.894)
        (xy -21.894 -2.876)
        (xy -21.91 -2.859)
        (xy -21.927 -2.843)
        (xy -21.945 -2.829)
        (xy -21.964 -2.814)
        (xy -21.984 -2.801)
        (xy -22.003 -2.789)
        (xy -22.023 -2.778)
        (xy -22.045 -2.767)
        (xy -22.066 -2.759)
        (xy -22.087 -2.751)
        (xy -22.11 -2.745)
        (xy -22.133 -2.74)
        (xy -22.156 -2.734)
        (xy -22.179 -2.732)
        (xy -22.203 -2.73)
        (xy -22.226 -2.729)
        (xy -22.249 -2.73)
        (xy -22.273 -2.732)
        (xy -22.296 -2.734)
        (xy -22.319 -2.74)
        (xy -22.342 -2.745)
        (xy -22.363 -2.751)
        (xy -22.386 -2.758)
        (xy -22.407 -2.767)
        (xy -22.429 -2.777)
        (xy -22.448 -2.789)
        (xy -22.468 -2.801)
        (xy -22.487 -2.814)
        (xy -22.506 -2.829)
        (xy -22.523 -2.843)
        (xy -22.54 -2.859)
        (xy -22.557 -2.876)
        (xy -22.572 -2.894)
        (xy -22.586 -2.912)
        (xy -22.598 -2.931)
        (xy -22.612 -2.951)
        (xy -22.622 -2.971)
        (xy -22.633 -2.992)
        (xy -22.641 -3.015)
        (xy -22.648 -3.036)
        (xy -22.656 -3.059)
        (xy -22.66 -3.08)
        (xy -22.665 -3.104)
        (xy -22.668 -3.126)
        (xy -22.67 -3.15)
        (xy -22.671 -3.172)
        (xy -22.226 -3.172)
        (xy -22.226 -3.177)
      )

      (stroke (width 0.001) (type solid)) (fill solid) (layer "B.Paste"))
    (fp_poly
      (pts
        (xy -22.226 1.903)
        (xy -22.671 1.903)
        (xy -22.67 1.881)
        (xy -22.668 1.857)
        (xy -22.665 1.835)
        (xy -22.66 1.811)
        (xy -22.656 1.789)
        (xy -22.648 1.767)
        (xy -22.641 1.746)
        (xy -22.633 1.724)
        (xy -22.622 1.702)
        (xy -22.612 1.682)
        (xy -22.598 1.662)
        (xy -22.586 1.643)
        (xy -22.572 1.625)
        (xy -22.557 1.607)
        (xy -22.54 1.591)
        (xy -22.523 1.575)
        (xy -22.506 1.559)
        (xy -22.487 1.545)
        (xy -22.468 1.532)
        (xy -22.448 1.519)
        (xy -22.429 1.508)
        (xy -22.407 1.498)
        (xy -22.386 1.49)
        (xy -22.363 1.482)
        (xy -22.342 1.476)
        (xy -22.319 1.47)
        (xy -22.296 1.466)
        (xy -22.273 1.462)
        (xy -22.249 1.462)
        (xy -22.226 1.46)
        (xy -22.203 1.462)
        (xy -22.179 1.462)
        (xy -22.156 1.466)
        (xy -22.133 1.47)
        (xy -22.11 1.476)
        (xy -22.087 1.482)
        (xy -22.066 1.49)
        (xy -22.045 1.498)
        (xy -22.023 1.509)
        (xy -22.003 1.52)
        (xy -21.984 1.532)
        (xy -21.964 1.545)
        (xy -21.945 1.559)
        (xy -21.927 1.575)
        (xy -21.91 1.591)
        (xy -21.894 1.607)
        (xy -21.88 1.625)
        (xy -21.865 1.643)
        (xy -21.852 1.663)
        (xy -21.84 1.684)
        (xy -21.83 1.704)
        (xy -21.819 1.724)
        (xy -21.81 1.746)
        (xy -21.802 1.767)
        (xy -21.796 1.79)
        (xy -21.79 1.813)
        (xy -21.785 1.835)
        (xy -21.782 1.859)
        (xy -21.781 1.882)
        (xy -21.781 1.905)
        (xy -21.781 1.928)
        (xy -21.782 1.952)
        (xy -21.785 1.976)
        (xy -21.79 1.998)
        (xy -21.796 2.02)
        (xy -21.802 2.044)
        (xy -21.81 2.065)
        (xy -21.819 2.086)
        (xy -21.83 2.108)
        (xy -21.84 2.127)
        (xy -21.852 2.147)
        (xy -21.865 2.167)
        (xy -21.88 2.186)
        (xy -21.894 2.203)
        (xy -21.91 2.221)
        (xy -21.927 2.237)
        (xy -21.945 2.251)
        (xy -21.964 2.266)
        (xy -21.984 2.278)
        (xy -22.003 2.29)
        (xy -22.023 2.302)
        (xy -22.045 2.312)
        (xy -22.066 2.32)
        (xy -22.087 2.328)
        (xy -22.11 2.335)
        (xy -22.133 2.34)
        (xy -22.156 2.346)
        (xy -22.179 2.348)
        (xy -22.203 2.35)
        (xy -22.226 2.351)
        (xy -22.249 2.35)
        (xy -22.273 2.348)
        (xy -22.296 2.346)
        (xy -22.319 2.34)
        (xy -22.342 2.335)
        (xy -22.363 2.328)
        (xy -22.386 2.322)
        (xy -22.407 2.312)
        (xy -22.429 2.302)
        (xy -22.448 2.291)
        (xy -22.468 2.278)
        (xy -22.487 2.266)
        (xy -22.506 2.251)
        (xy -22.523 2.237)
        (xy -22.54 2.221)
        (xy -22.557 2.203)
        (xy -22.572 2.186)
        (xy -22.586 2.167)
        (xy -22.598 2.149)
        (xy -22.612 2.129)
        (xy -22.622 2.109)
        (xy -22.633 2.088)
        (xy -22.641 2.065)
        (xy -22.648 2.044)
        (xy -22.656 2.021)
        (xy -22.66 2)
        (xy -22.665 1.976)
        (xy -22.668 1.954)
        (xy -22.67 1.93)
        (xy -22.671 1.907)
        (xy -22.226 1.907)
        (xy -22.226 1.903)
      )

      (stroke (width 0.001) (type solid)) (fill solid) (layer "B.Paste"))
    (fp_poly
      (pts
        (xy -22.226 3.173)
        (xy -22.671 3.173)
        (xy -22.67 3.151)
        (xy -22.668 3.127)
        (xy -22.665 3.105)
        (xy -22.66 3.081)
        (xy -22.656 3.06)
        (xy -22.648 3.037)
        (xy -22.641 3.016)
        (xy -22.633 2.993)
        (xy -22.622 2.972)
        (xy -22.612 2.952)
        (xy -22.598 2.932)
        (xy -22.586 2.913)
        (xy -22.572 2.895)
        (xy -22.557 2.877)
        (xy -22.54 2.86)
        (xy -22.523 2.844)
        (xy -22.506 2.83)
        (xy -22.487 2.815)
        (xy -22.468 2.802)
        (xy -22.448 2.79)
        (xy -22.429 2.778)
        (xy -22.407 2.768)
        (xy -22.386 2.759)
        (xy -22.363 2.752)
        (xy -22.342 2.746)
        (xy -22.319 2.741)
        (xy -22.296 2.735)
        (xy -22.273 2.733)
        (xy -22.249 2.731)
        (xy -22.226 2.73)
        (xy -22.203 2.731)
        (xy -22.179 2.733)
        (xy -22.156 2.735)
        (xy -22.133 2.741)
        (xy -22.11 2.746)
        (xy -22.087 2.752)
        (xy -22.066 2.76)
        (xy -22.045 2.768)
        (xy -22.023 2.779)
        (xy -22.003 2.79)
        (xy -21.984 2.802)
        (xy -21.964 2.815)
        (xy -21.945 2.83)
        (xy -21.927 2.844)
        (xy -21.91 2.86)
        (xy -21.894 2.877)
        (xy -21.88 2.895)
        (xy -21.865 2.913)
        (xy -21.852 2.933)
        (xy -21.84 2.952)
        (xy -21.83 2.973)
        (xy -21.819 2.995)
        (xy -21.81 3.016)
        (xy -21.802 3.037)
        (xy -21.796 3.06)
        (xy -21.79 3.082)
        (xy -21.785 3.105)
        (xy -21.782 3.129)
        (xy -21.781 3.153)
        (xy -21.781 3.175)
        (xy -21.781 3.198)
        (xy -21.782 3.222)
        (xy -21.785 3.246)
        (xy -21.79 3.268)
        (xy -21.796 3.29)
        (xy -21.802 3.314)
        (xy -21.81 3.335)
        (xy -21.819 3.356)
        (xy -21.83 3.377)
        (xy -21.84 3.397)
        (xy -21.852 3.417)
        (xy -21.865 3.437)
        (xy -21.88 3.455)
        (xy -21.894 3.473)
        (xy -21.91 3.491)
        (xy -21.927 3.506)
        (xy -21.945 3.521)
        (xy -21.964 3.536)
        (xy -21.984 3.548)
        (xy -22.003 3.56)
        (xy -22.023 3.572)
        (xy -22.045 3.582)
        (xy -22.066 3.59)
        (xy -22.087 3.598)
        (xy -22.11 3.605)
        (xy -22.133 3.61)
        (xy -22.156 3.616)
        (xy -22.179 3.618)
        (xy -22.203 3.62)
        (xy -22.226 3.621)
        (xy -22.249 3.62)
        (xy -22.273 3.618)
        (xy -22.296 3.616)
        (xy -22.319 3.61)
        (xy -22.342 3.605)
        (xy -22.363 3.598)
        (xy -22.386 3.592)
        (xy -22.407 3.582)
        (xy -22.429 3.572)
        (xy -22.448 3.561)
        (xy -22.468 3.548)
        (xy -22.487 3.536)
        (xy -22.506 3.521)
        (xy -22.523 3.506)
        (xy -22.54 3.491)
        (xy -22.557 3.473)
        (xy -22.572 3.456)
        (xy -22.586 3.437)
        (xy -22.598 3.419)
        (xy -22.612 3.399)
        (xy -22.622 3.379)
        (xy -22.633 3.358)
        (xy -22.641 3.335)
        (xy -22.648 3.314)
        (xy -22.656 3.291)
        (xy -22.66 3.27)
        (xy -22.665 3.246)
        (xy -22.668 3.223)
        (xy -22.67 3.199)
        (xy -22.671 3.178)
        (xy -22.226 3.178)
        (xy -22.226 3.173)
      )

      (stroke (width 0.001) (type solid)) (fill solid) (layer "B.Paste"))
    (fp_poly
      (pts
        (xy -22.226 4.443)
        (xy -22.671 4.443)
        (xy -22.67 4.422)
        (xy -22.668 4.398)
        (xy -22.665 4.374)
        (xy -22.66 4.351)
        (xy -22.656 4.329)
        (xy -22.648 4.308)
        (xy -22.641 4.286)
        (xy -22.633 4.263)
        (xy -22.622 4.242)
        (xy -22.612 4.223)
        (xy -22.598 4.202)
        (xy -22.586 4.183)
        (xy -22.572 4.164)
        (xy -22.557 4.148)
        (xy -22.54 4.13)
        (xy -22.523 4.114)
        (xy -22.506 4.1)
        (xy -22.487 4.085)
        (xy -22.468 4.072)
        (xy -22.448 4.06)
        (xy -22.429 4.048)
        (xy -22.407 4.039)
        (xy -22.386 4.029)
        (xy -22.363 4.023)
        (xy -22.342 4.015)
        (xy -22.319 4.01)
        (xy -22.296 4.005)
        (xy -22.273 4.002)
        (xy -22.249 4.002)
        (xy -22.226 4)
        (xy -22.203 4.002)
        (xy -22.179 4.002)
        (xy -22.156 4.005)
        (xy -22.133 4.01)
        (xy -22.11 4.015)
        (xy -22.087 4.023)
        (xy -22.066 4.031)
        (xy -22.045 4.039)
        (xy -22.023 4.05)
        (xy -22.003 4.06)
        (xy -21.984 4.072)
        (xy -21.964 4.085)
        (xy -21.945 4.1)
        (xy -21.927 4.114)
        (xy -21.91 4.13)
        (xy -21.894 4.148)
        (xy -21.88 4.165)
        (xy -21.865 4.183)
        (xy -21.852 4.204)
        (xy -21.84 4.223)
        (xy -21.83 4.244)
        (xy -21.819 4.265)
        (xy -21.81 4.286)
        (xy -21.802 4.308)
        (xy -21.796 4.33)
        (xy -21.79 4.353)
        (xy -21.785 4.375)
        (xy -21.782 4.398)
        (xy -21.781 4.422)
        (xy -21.781 4.446)
        (xy -21.781 4.468)
        (xy -21.782 4.492)
        (xy -21.785 4.515)
        (xy -21.79 4.539)
        (xy -21.796 4.56)
        (xy -21.802 4.584)
        (xy -21.81 4.604)
        (xy -21.819 4.627)
        (xy -21.83 4.648)
        (xy -21.84 4.669)
        (xy -21.852 4.688)
        (xy -21.865 4.707)
        (xy -21.88 4.725)
        (xy -21.894 4.744)
        (xy -21.91 4.76)
        (xy -21.927 4.776)
        (xy -21.945 4.792)
        (xy -21.964 4.805)
        (xy -21.984 4.818)
        (xy -22.003 4.83)
        (xy -22.023 4.842)
        (xy -22.045 4.853)
        (xy -22.066 4.861)
        (xy -22.087 4.869)
        (xy -22.11 4.875)
        (xy -22.133 4.88)
        (xy -22.156 4.885)
        (xy -22.179 4.888)
        (xy -22.203 4.89)
        (xy -22.226 4.89)
        (xy -22.249 4.89)
        (xy -22.273 4.888)
        (xy -22.296 4.885)
        (xy -22.319 4.88)
        (xy -22.342 4.875)
        (xy -22.363 4.869)
        (xy -22.386 4.861)
        (xy -22.407 4.853)
        (xy -22.429 4.842)
        (xy -22.448 4.832)
        (xy -22.468 4.818)
        (xy -22.487 4.805)
        (xy -22.506 4.792)
        (xy -22.523 4.776)
        (xy -22.54 4.76)
        (xy -22.557 4.744)
        (xy -22.572 4.726)
        (xy -22.586 4.707)
        (xy -22.598 4.688)
        (xy -22.612 4.669)
        (xy -22.622 4.648)
        (xy -22.633 4.627)
        (xy -22.641 4.606)
        (xy -22.648 4.584)
        (xy -22.656 4.561)
        (xy -22.66 4.539)
        (xy -22.665 4.516)
        (xy -22.668 4.494)
        (xy -22.67 4.47)
        (xy -22.671 4.447)
        (xy -22.226 4.447)
        (xy -22.226 4.443)
      )

      (stroke (width 0.001) (type solid)) (fill solid) (layer "B.Paste"))
    (fp_poly
      (pts
        (xy -22.226 5.713)
        (xy -22.671 5.713)
        (xy -22.67 5.691)
        (xy -22.668 5.667)
        (xy -22.665 5.645)
        (xy -22.66 5.622)
        (xy -22.656 5.6)
        (xy -22.648 5.577)
        (xy -22.641 5.555)
        (xy -22.633 5.534)
        (xy -22.622 5.512)
        (xy -22.612 5.492)
        (xy -22.598 5.473)
        (xy -22.586 5.454)
        (xy -22.572 5.435)
        (xy -22.557 5.417)
        (xy -22.54 5.401)
        (xy -22.523 5.385)
        (xy -22.506 5.369)
        (xy -22.487 5.356)
        (xy -22.468 5.342)
        (xy -22.448 5.329)
        (xy -22.429 5.318)
        (xy -22.407 5.308)
        (xy -22.386 5.3)
        (xy -22.363 5.292)
        (xy -22.342 5.286)
        (xy -22.319 5.281)
        (xy -22.296 5.276)
        (xy -22.273 5.273)
        (xy -22.249 5.271)
        (xy -22.226 5.27)
        (xy -22.203 5.271)
        (xy -22.179 5.273)
        (xy -22.156 5.276)
        (xy -22.133 5.281)
        (xy -22.11 5.286)
        (xy -22.087 5.292)
        (xy -22.066 5.3)
        (xy -22.045 5.308)
        (xy -22.023 5.319)
        (xy -22.003 5.33)
        (xy -21.984 5.342)
        (xy -21.964 5.356)
        (xy -21.945 5.369)
        (xy -21.927 5.385)
        (xy -21.91 5.401)
        (xy -21.894 5.417)
        (xy -21.88 5.435)
        (xy -21.865 5.454)
        (xy -21.852 5.473)
        (xy -21.84 5.492)
        (xy -21.83 5.513)
        (xy -21.819 5.534)
        (xy -21.81 5.556)
        (xy -21.802 5.577)
        (xy -21.796 5.6)
        (xy -21.79 5.622)
        (xy -21.785 5.645)
        (xy -21.782 5.669)
        (xy -21.781 5.693)
        (xy -21.781 5.715)
        (xy -21.781 5.739)
        (xy -21.782 5.762)
        (xy -21.785 5.786)
        (xy -21.79 5.808)
        (xy -21.796 5.83)
        (xy -21.802 5.853)
        (xy -21.81 5.874)
        (xy -21.819 5.896)
        (xy -21.83 5.917)
        (xy -21.84 5.938)
        (xy -21.852 5.957)
        (xy -21.865 5.978)
        (xy -21.88 5.995)
        (xy -21.894 6.013)
        (xy -21.91 6.031)
        (xy -21.927 6.047)
        (xy -21.945 6.061)
        (xy -21.964 6.076)
        (xy -21.984 6.088)
        (xy -22.003 6.1)
        (xy -22.023 6.111)
        (xy -22.045 6.122)
        (xy -22.066 6.13)
        (xy -22.087 6.138)
        (xy -22.11 6.145)
        (xy -22.133 6.151)
        (xy -22.156 6.156)
        (xy -22.179 6.159)
        (xy -22.203 6.159)
        (xy -22.226 6.161)
        (xy -22.249 6.159)
        (xy -22.273 6.159)
        (xy -22.296 6.156)
        (xy -22.319 6.151)
        (xy -22.342 6.145)
        (xy -22.363 6.138)
        (xy -22.386 6.132)
        (xy -22.407 6.122)
        (xy -22.429 6.112)
        (xy -22.448 6.101)
        (xy -22.468 6.088)
        (xy -22.487 6.076)
        (xy -22.506 6.061)
        (xy -22.523 6.047)
        (xy -22.54 6.031)
        (xy -22.557 6.013)
        (xy -22.572 5.997)
        (xy -22.586 5.978)
        (xy -22.598 5.959)
        (xy -22.612 5.938)
        (xy -22.622 5.919)
        (xy -22.633 5.898)
        (xy -22.641 5.875)
        (xy -22.648 5.853)
        (xy -22.656 5.832)
        (xy -22.66 5.81)
        (xy -22.665 5.786)
        (xy -22.668 5.763)
        (xy -22.67 5.739)
        (xy -22.671 5.718)
        (xy -22.226 5.718)
        (xy -22.226 5.713)
      )

      (stroke (width 0.001) (type solid)) (fill solid) (layer "B.Paste"))
    (fp_poly
      (pts
        (xy -20.955 -5.717)
        (xy -21.4 -5.717)
        (xy -21.4 -5.738)
        (xy -21.398 -5.762)
        (xy -21.395 -5.785)
        (xy -21.391 -5.809)
        (xy -21.386 -5.831)
        (xy -21.378 -5.852)
        (xy -21.371 -5.874)
        (xy -21.362 -5.897)
        (xy -21.352 -5.918)
        (xy -21.342 -5.937)
        (xy -21.328 -5.958)
        (xy -21.316 -5.977)
        (xy -21.301 -5.996)
        (xy -21.287 -6.012)
        (xy -21.27 -6.03)
        (xy -21.253 -6.046)
        (xy -21.237 -6.06)
        (xy -21.217 -6.075)
        (xy -21.198 -6.087)
        (xy -21.179 -6.1)
        (xy -21.159 -6.111)
        (xy -21.138 -6.121)
        (xy -21.115 -6.131)
        (xy -21.093 -6.137)
        (xy -21.072 -6.144)
        (xy -21.049 -6.15)
        (xy -21.026 -6.155)
        (xy -21.003 -6.158)
        (xy -20.979 -6.158)
        (xy -20.955 -6.16)
        (xy -20.932 -6.158)
        (xy -20.909 -6.158)
        (xy -20.886 -6.155)
        (xy -20.862 -6.15)
        (xy -20.84 -6.144)
        (xy -20.817 -6.137)
        (xy -20.796 -6.129)
        (xy -20.775 -6.121)
        (xy -20.753 -6.11)
        (xy -20.734 -6.099)
        (xy -20.714 -6.087)
        (xy -20.694 -6.075)
        (xy -20.676 -6.06)
        (xy -20.657 -6.046)
        (xy -20.641 -6.03)
        (xy -20.624 -6.012)
        (xy -20.61 -5.994)
        (xy -20.595 -5.977)
        (xy -20.583 -5.956)
        (xy -20.57 -5.937)
        (xy -20.56 -5.916)
        (xy -20.548 -5.895)
        (xy -20.54 -5.873)
        (xy -20.532 -5.852)
        (xy -20.525 -5.829)
        (xy -20.52 -5.807)
        (xy -20.516 -5.785)
        (xy -20.513 -5.761)
        (xy -20.511 -5.738)
        (xy -20.511 -5.714)
        (xy -20.511 -5.692)
        (xy -20.513 -5.668)
        (xy -20.516 -5.644)
        (xy -20.52 -5.621)
        (xy -20.525 -5.599)
        (xy -20.532 -5.576)
        (xy -20.54 -5.555)
        (xy -20.548 -5.533)
        (xy -20.56 -5.512)
        (xy -20.57 -5.491)
        (xy -20.583 -5.472)
        (xy -20.595 -5.453)
        (xy -20.61 -5.434)
        (xy -20.624 -5.416)
        (xy -20.641 -5.4)
        (xy -20.657 -5.384)
        (xy -20.676 -5.368)
        (xy -20.694 -5.355)
        (xy -20.714 -5.341)
        (xy -20.734 -5.329)
        (xy -20.753 -5.318)
        (xy -20.775 -5.307)
        (xy -20.796 -5.299)
        (xy -20.817 -5.291)
        (xy -20.84 -5.285)
        (xy -20.862 -5.28)
        (xy -20.886 -5.275)
        (xy -20.909 -5.272)
        (xy -20.932 -5.27)
        (xy -20.955 -5.269)
        (xy -20.979 -5.27)
        (xy -21.003 -5.272)
        (xy -21.026 -5.275)
        (xy -21.049 -5.28)
        (xy -21.072 -5.285)
        (xy -21.093 -5.291)
        (xy -21.115 -5.299)
        (xy -21.138 -5.307)
        (xy -21.159 -5.317)
        (xy -21.179 -5.328)
        (xy -21.198 -5.341)
        (xy -21.217 -5.355)
        (xy -21.237 -5.368)
        (xy -21.253 -5.384)
        (xy -21.27 -5.4)
        (xy -21.287 -5.416)
        (xy -21.301 -5.434)
        (xy -21.316 -5.453)
        (xy -21.328 -5.472)
        (xy -21.342 -5.491)
        (xy -21.352 -5.511)
        (xy -21.362 -5.533)
        (xy -21.371 -5.554)
        (xy -21.378 -5.576)
        (xy -21.386 -5.599)
        (xy -21.391 -5.621)
        (xy -21.395 -5.644)
        (xy -21.398 -5.666)
        (xy -21.4 -5.69)
        (xy -21.4 -5.712)
        (xy -20.955 -5.712)
        (xy -20.955 -5.717)
      )

      (stroke (width 0.001) (type solid)) (fill solid) (layer "B.Paste"))
    (fp_poly
      (pts
        (xy -20.955 -3.177)
        (xy -21.4 -3.177)
        (xy -21.4 -3.198)
        (xy -21.398 -3.222)
        (xy -21.395 -3.245)
        (xy -21.391 -3.269)
        (xy -21.386 -3.29)
        (xy -21.378 -3.313)
        (xy -21.371 -3.334)
        (xy -21.362 -3.357)
        (xy -21.352 -3.378)
        (xy -21.342 -3.398)
        (xy -21.328 -3.418)
        (xy -21.316 -3.436)
        (xy -21.301 -3.455)
        (xy -21.287 -3.472)
        (xy -21.27 -3.49)
        (xy -21.253 -3.505)
        (xy -21.237 -3.52)
        (xy -21.217 -3.535)
        (xy -21.198 -3.547)
        (xy -21.179 -3.56)
        (xy -21.159 -3.571)
        (xy -21.138 -3.581)
        (xy -21.115 -3.591)
        (xy -21.093 -3.597)
        (xy -21.072 -3.604)
        (xy -21.049 -3.609)
        (xy -21.026 -3.615)
        (xy -21.003 -3.617)
        (xy -20.979 -3.619)
        (xy -20.955 -3.62)
        (xy -20.932 -3.619)
        (xy -20.909 -3.617)
        (xy -20.886 -3.615)
        (xy -20.862 -3.609)
        (xy -20.84 -3.604)
        (xy -20.817 -3.597)
        (xy -20.796 -3.589)
        (xy -20.775 -3.581)
        (xy -20.753 -3.571)
        (xy -20.734 -3.559)
        (xy -20.714 -3.547)
        (xy -20.694 -3.535)
        (xy -20.676 -3.52)
        (xy -20.657 -3.505)
        (xy -20.641 -3.49)
        (xy -20.624 -3.472)
        (xy -20.61 -3.454)
        (xy -20.595 -3.436)
        (xy -20.583 -3.416)
        (xy -20.57 -3.398)
        (xy -20.56 -3.376)
        (xy -20.548 -3.355)
        (xy -20.54 -3.334)
        (xy -20.532 -3.313)
        (xy -20.525 -3.289)
        (xy -20.52 -3.267)
        (xy -20.516 -3.245)
        (xy -20.513 -3.221)
        (xy -20.511 -3.197)
        (xy -20.511 -3.174)
        (xy -20.511 -3.152)
        (xy -20.513 -3.128)
        (xy -20.516 -3.104)
        (xy -20.52 -3.081)
        (xy -20.525 -3.059)
        (xy -20.532 -3.036)
        (xy -20.54 -3.015)
        (xy -20.548 -2.994)
        (xy -20.56 -2.972)
        (xy -20.57 -2.951)
        (xy -20.583 -2.932)
        (xy -20.595 -2.912)
        (xy -20.61 -2.894)
        (xy -20.624 -2.876)
        (xy -20.641 -2.859)
        (xy -20.657 -2.843)
        (xy -20.676 -2.829)
        (xy -20.694 -2.814)
        (xy -20.714 -2.801)
        (xy -20.734 -2.789)
        (xy -20.753 -2.778)
        (xy -20.775 -2.767)
        (xy -20.796 -2.759)
        (xy -20.817 -2.751)
        (xy -20.84 -2.745)
        (xy -20.862 -2.74)
        (xy -20.886 -2.734)
        (xy -20.909 -2.732)
        (xy -20.932 -2.73)
        (xy -20.955 -2.729)
        (xy -20.979 -2.73)
        (xy -21.003 -2.732)
        (xy -21.026 -2.734)
        (xy -21.049 -2.74)
        (xy -21.072 -2.745)
        (xy -21.093 -2.751)
        (xy -21.115 -2.758)
        (xy -21.138 -2.767)
        (xy -21.159 -2.777)
        (xy -21.179 -2.789)
        (xy -21.198 -2.801)
        (xy -21.217 -2.814)
        (xy -21.237 -2.829)
        (xy -21.253 -2.843)
        (xy -21.27 -2.859)
        (xy -21.287 -2.876)
        (xy -21.301 -2.894)
        (xy -21.316 -2.912)
        (xy -21.328 -2.931)
        (xy -21.342 -2.951)
        (xy -21.352 -2.971)
        (xy -21.362 -2.992)
        (xy -21.371 -3.015)
        (xy -21.378 -3.036)
        (xy -21.386 -3.059)
        (xy -21.391 -3.08)
        (xy -21.395 -3.104)
        (xy -21.398 -3.126)
        (xy -21.4 -3.15)
        (xy -21.4 -3.172)
        (xy -20.955 -3.172)
        (xy -20.955 -3.177)
      )

      (stroke (width 0.001) (type solid)) (fill solid) (layer "B.Paste"))
    (fp_poly
      (pts
        (xy -20.955 1.903)
        (xy -21.4 1.903)
        (xy -21.4 1.881)
        (xy -21.398 1.857)
        (xy -21.395 1.835)
        (xy -21.391 1.811)
        (xy -21.386 1.789)
        (xy -21.378 1.767)
        (xy -21.371 1.746)
        (xy -21.362 1.724)
        (xy -21.352 1.702)
        (xy -21.342 1.682)
        (xy -21.328 1.662)
        (xy -21.316 1.643)
        (xy -21.301 1.625)
        (xy -21.287 1.607)
        (xy -21.27 1.591)
        (xy -21.253 1.575)
        (xy -21.237 1.559)
        (xy -21.217 1.545)
        (xy -21.198 1.532)
        (xy -21.179 1.519)
        (xy -21.159 1.508)
        (xy -21.138 1.498)
        (xy -21.115 1.49)
        (xy -21.093 1.482)
        (xy -21.072 1.476)
        (xy -21.049 1.47)
        (xy -21.026 1.466)
        (xy -21.003 1.462)
        (xy -20.979 1.462)
        (xy -20.955 1.46)
        (xy -20.932 1.462)
        (xy -20.909 1.462)
        (xy -20.886 1.466)
        (xy -20.862 1.47)
        (xy -20.84 1.476)
        (xy -20.817 1.482)
        (xy -20.796 1.49)
        (xy -20.775 1.498)
        (xy -20.753 1.509)
        (xy -20.734 1.52)
        (xy -20.714 1.532)
        (xy -20.694 1.545)
        (xy -20.676 1.559)
        (xy -20.657 1.575)
        (xy -20.641 1.591)
        (xy -20.624 1.607)
        (xy -20.61 1.625)
        (xy -20.595 1.643)
        (xy -20.583 1.663)
        (xy -20.57 1.682)
        (xy -20.56 1.704)
        (xy -20.548 1.724)
        (xy -20.54 1.746)
        (xy -20.532 1.767)
        (xy -20.525 1.79)
        (xy -20.52 1.813)
        (xy -20.516 1.835)
        (xy -20.513 1.859)
        (xy -20.511 1.882)
        (xy -20.511 1.905)
        (xy -20.511 1.928)
        (xy -20.513 1.952)
        (xy -20.516 1.976)
        (xy -20.52 1.998)
        (xy -20.525 2.02)
        (xy -20.532 2.044)
        (xy -20.54 2.065)
        (xy -20.548 2.086)
        (xy -20.56 2.108)
        (xy -20.57 2.129)
        (xy -20.583 2.147)
        (xy -20.595 2.167)
        (xy -20.61 2.186)
        (xy -20.624 2.203)
        (xy -20.641 2.221)
        (xy -20.657 2.237)
        (xy -20.676 2.251)
        (xy -20.694 2.266)
        (xy -20.714 2.278)
        (xy -20.734 2.29)
        (xy -20.753 2.302)
        (xy -20.775 2.312)
        (xy -20.796 2.32)
        (xy -20.817 2.328)
        (xy -20.84 2.335)
        (xy -20.862 2.34)
        (xy -20.886 2.346)
        (xy -20.909 2.348)
        (xy -20.932 2.35)
        (xy -20.955 2.351)
        (xy -20.979 2.35)
        (xy -21.003 2.348)
        (xy -21.026 2.346)
        (xy -21.049 2.34)
        (xy -21.072 2.335)
        (xy -21.093 2.328)
        (xy -21.115 2.322)
        (xy -21.138 2.312)
        (xy -21.159 2.302)
        (xy -21.179 2.291)
        (xy -21.198 2.278)
        (xy -21.217 2.266)
        (xy -21.237 2.251)
        (xy -21.253 2.237)
        (xy -21.27 2.221)
        (xy -21.287 2.203)
        (xy -21.301 2.186)
        (xy -21.316 2.167)
        (xy -21.328 2.149)
        (xy -21.342 2.129)
        (xy -21.352 2.109)
        (xy -21.362 2.088)
        (xy -21.371 2.065)
        (xy -21.378 2.044)
        (xy -21.386 2.021)
        (xy -21.391 2)
        (xy -21.395 1.976)
        (xy -21.398 1.954)
        (xy -21.4 1.93)
        (xy -21.4 1.907)
        (xy -20.955 1.907)
        (xy -20.955 1.903)
      )

      (stroke (width 0.001) (type solid)) (fill solid) (layer "B.Paste"))
    (fp_poly
      (pts
        (xy -20.955 3.173)
        (xy -21.4 3.173)
        (xy -21.4 3.151)
        (xy -21.398 3.127)
        (xy -21.395 3.105)
        (xy -21.391 3.081)
        (xy -21.386 3.06)
        (xy -21.378 3.037)
        (xy -21.371 3.016)
        (xy -21.362 2.993)
        (xy -21.352 2.972)
        (xy -21.342 2.952)
        (xy -21.328 2.932)
        (xy -21.316 2.913)
        (xy -21.301 2.895)
        (xy -21.287 2.877)
        (xy -21.27 2.86)
        (xy -21.253 2.844)
        (xy -21.237 2.83)
        (xy -21.217 2.815)
        (xy -21.198 2.802)
        (xy -21.179 2.79)
        (xy -21.159 2.778)
        (xy -21.138 2.768)
        (xy -21.115 2.759)
        (xy -21.093 2.752)
        (xy -21.072 2.746)
        (xy -21.049 2.741)
        (xy -21.026 2.735)
        (xy -21.003 2.733)
        (xy -20.979 2.731)
        (xy -20.955 2.73)
        (xy -20.932 2.731)
        (xy -20.909 2.733)
        (xy -20.886 2.735)
        (xy -20.862 2.741)
        (xy -20.84 2.746)
        (xy -20.817 2.752)
        (xy -20.796 2.76)
        (xy -20.775 2.768)
        (xy -20.753 2.779)
        (xy -20.734 2.79)
        (xy -20.714 2.802)
        (xy -20.694 2.815)
        (xy -20.676 2.83)
        (xy -20.657 2.844)
        (xy -20.641 2.86)
        (xy -20.624 2.877)
        (xy -20.61 2.895)
        (xy -20.595 2.913)
        (xy -20.583 2.933)
        (xy -20.57 2.952)
        (xy -20.56 2.973)
        (xy -20.548 2.995)
        (xy -20.54 3.016)
        (xy -20.532 3.037)
        (xy -20.525 3.06)
        (xy -20.52 3.082)
        (xy -20.516 3.105)
        (xy -20.513 3.129)
        (xy -20.511 3.153)
        (xy -20.511 3.175)
        (xy -20.511 3.198)
        (xy -20.513 3.222)
        (xy -20.516 3.246)
        (xy -20.52 3.268)
        (xy -20.525 3.29)
        (xy -20.532 3.314)
        (xy -20.54 3.335)
        (xy -20.548 3.356)
        (xy -20.56 3.377)
        (xy -20.57 3.399)
        (xy -20.583 3.417)
        (xy -20.595 3.437)
        (xy -20.61 3.455)
        (xy -20.624 3.473)
        (xy -20.641 3.491)
        (xy -20.657 3.506)
        (xy -20.676 3.521)
        (xy -20.694 3.536)
        (xy -20.714 3.548)
        (xy -20.734 3.56)
        (xy -20.753 3.572)
        (xy -20.775 3.582)
        (xy -20.796 3.59)
        (xy -20.817 3.598)
        (xy -20.84 3.605)
        (xy -20.862 3.61)
        (xy -20.886 3.616)
        (xy -20.909 3.618)
        (xy -20.932 3.62)
        (xy -20.955 3.621)
        (xy -20.979 3.62)
        (xy -21.003 3.618)
        (xy -21.026 3.616)
        (xy -21.049 3.61)
        (xy -21.072 3.605)
        (xy -21.093 3.598)
        (xy -21.115 3.592)
        (xy -21.138 3.582)
        (xy -21.159 3.572)
        (xy -21.179 3.561)
        (xy -21.198 3.548)
        (xy -21.217 3.536)
        (xy -21.237 3.521)
        (xy -21.253 3.506)
        (xy -21.27 3.491)
        (xy -21.287 3.473)
        (xy -21.301 3.456)
        (xy -21.316 3.437)
        (xy -21.328 3.419)
        (xy -21.342 3.399)
        (xy -21.352 3.379)
        (xy -21.362 3.358)
        (xy -21.371 3.335)
        (xy -21.378 3.314)
        (xy -21.386 3.291)
        (xy -21.391 3.27)
        (xy -21.395 3.246)
        (xy -21.398 3.223)
        (xy -21.4 3.199)
        (xy -21.4 3.178)
        (xy -20.955 3.178)
        (xy -20.955 3.173)
      )

      (stroke (width 0.001) (type solid)) (fill solid) (layer "B.Paste"))
    (fp_poly
      (pts
        (xy -20.955 4.443)
        (xy -21.4 4.443)
        (xy -21.4 4.422)
        (xy -21.398 4.398)
        (xy -21.395 4.374)
        (xy -21.391 4.351)
        (xy -21.386 4.329)
        (xy -21.378 4.308)
        (xy -21.371 4.286)
        (xy -21.362 4.263)
        (xy -21.352 4.242)
        (xy -21.342 4.223)
        (xy -21.328 4.202)
        (xy -21.316 4.183)
        (xy -21.301 4.164)
        (xy -21.287 4.148)
        (xy -21.27 4.13)
        (xy -21.253 4.114)
        (xy -21.237 4.1)
        (xy -21.217 4.085)
        (xy -21.198 4.072)
        (xy -21.179 4.06)
        (xy -21.159 4.048)
        (xy -21.138 4.039)
        (xy -21.115 4.029)
        (xy -21.093 4.023)
        (xy -21.072 4.015)
        (xy -21.049 4.01)
        (xy -21.026 4.005)
        (xy -21.003 4.002)
        (xy -20.979 4.002)
        (xy -20.955 4)
        (xy -20.932 4.002)
        (xy -20.909 4.002)
        (xy -20.886 4.005)
        (xy -20.862 4.01)
        (xy -20.84 4.015)
        (xy -20.817 4.023)
        (xy -20.796 4.031)
        (xy -20.775 4.039)
        (xy -20.753 4.05)
        (xy -20.734 4.06)
        (xy -20.714 4.072)
        (xy -20.694 4.085)
        (xy -20.676 4.1)
        (xy -20.657 4.114)
        (xy -20.641 4.13)
        (xy -20.624 4.148)
        (xy -20.61 4.165)
        (xy -20.595 4.183)
        (xy -20.583 4.204)
        (xy -20.57 4.223)
        (xy -20.56 4.244)
        (xy -20.548 4.265)
        (xy -20.54 4.286)
        (xy -20.532 4.308)
        (xy -20.525 4.33)
        (xy -20.52 4.353)
        (xy -20.516 4.375)
        (xy -20.513 4.398)
        (xy -20.511 4.422)
        (xy -20.511 4.446)
        (xy -20.511 4.468)
        (xy -20.513 4.492)
        (xy -20.516 4.515)
        (xy -20.52 4.539)
        (xy -20.525 4.56)
        (xy -20.532 4.584)
        (xy -20.54 4.604)
        (xy -20.548 4.627)
        (xy -20.56 4.648)
        (xy -20.57 4.669)
        (xy -20.583 4.688)
        (xy -20.595 4.707)
        (xy -20.61 4.725)
        (xy -20.624 4.744)
        (xy -20.641 4.76)
        (xy -20.657 4.776)
        (xy -20.676 4.792)
        (xy -20.694 4.805)
        (xy -20.714 4.818)
        (xy -20.734 4.83)
        (xy -20.753 4.842)
        (xy -20.775 4.853)
        (xy -20.796 4.861)
        (xy -20.817 4.869)
        (xy -20.84 4.875)
        (xy -20.862 4.88)
        (xy -20.886 4.885)
        (xy -20.909 4.888)
        (xy -20.932 4.89)
        (xy -20.955 4.89)
        (xy -20.979 4.89)
        (xy -21.003 4.888)
        (xy -21.026 4.885)
        (xy -21.049 4.88)
        (xy -21.072 4.875)
        (xy -21.093 4.869)
        (xy -21.115 4.861)
        (xy -21.138 4.853)
        (xy -21.159 4.842)
        (xy -21.179 4.832)
        (xy -21.198 4.818)
        (xy -21.217 4.805)
        (xy -21.237 4.792)
        (xy -21.253 4.776)
        (xy -21.27 4.76)
        (xy -21.287 4.744)
        (xy -21.301 4.726)
        (xy -21.316 4.707)
        (xy -21.328 4.688)
        (xy -21.342 4.669)
        (xy -21.352 4.648)
        (xy -21.362 4.627)
        (xy -21.371 4.606)
        (xy -21.378 4.584)
        (xy -21.386 4.561)
        (xy -21.391 4.539)
        (xy -21.395 4.516)
        (xy -21.398 4.494)
        (xy -21.4 4.47)
        (xy -21.4 4.447)
        (xy -20.955 4.447)
        (xy -20.955 4.443)
      )

      (stroke (width 0.001) (type solid)) (fill solid) (layer "B.Paste"))
    (fp_poly
      (pts
        (xy -20.955 5.713)
        (xy -21.4 5.713)
        (xy -21.4 5.691)
        (xy -21.398 5.667)
        (xy -21.395 5.645)
        (xy -21.391 5.622)
        (xy -21.386 5.6)
        (xy -21.378 5.577)
        (xy -21.371 5.555)
        (xy -21.362 5.534)
        (xy -21.352 5.512)
        (xy -21.342 5.492)
        (xy -21.328 5.473)
        (xy -21.316 5.454)
        (xy -21.301 5.435)
        (xy -21.287 5.417)
        (xy -21.27 5.401)
        (xy -21.253 5.385)
        (xy -21.237 5.369)
        (xy -21.217 5.356)
        (xy -21.198 5.342)
        (xy -21.179 5.329)
        (xy -21.159 5.318)
        (xy -21.138 5.308)
        (xy -21.115 5.3)
        (xy -21.093 5.292)
        (xy -21.072 5.286)
        (xy -21.049 5.281)
        (xy -21.026 5.276)
        (xy -21.003 5.273)
        (xy -20.979 5.271)
        (xy -20.955 5.27)
        (xy -20.932 5.271)
        (xy -20.909 5.273)
        (xy -20.886 5.276)
        (xy -20.862 5.281)
        (xy -20.84 5.286)
        (xy -20.817 5.292)
        (xy -20.796 5.3)
        (xy -20.775 5.308)
        (xy -20.753 5.319)
        (xy -20.734 5.33)
        (xy -20.714 5.342)
        (xy -20.694 5.356)
        (xy -20.676 5.369)
        (xy -20.657 5.385)
        (xy -20.641 5.401)
        (xy -20.624 5.417)
        (xy -20.61 5.435)
        (xy -20.595 5.454)
        (xy -20.583 5.473)
        (xy -20.57 5.492)
        (xy -20.56 5.513)
        (xy -20.548 5.534)
        (xy -20.54 5.556)
        (xy -20.532 5.577)
        (xy -20.525 5.6)
        (xy -20.52 5.622)
        (xy -20.516 5.645)
        (xy -20.513 5.669)
        (xy -20.511 5.693)
        (xy -20.511 5.715)
        (xy -20.511 5.739)
        (xy -20.513 5.762)
        (xy -20.516 5.786)
        (xy -20.52 5.808)
        (xy -20.525 5.83)
        (xy -20.532 5.853)
        (xy -20.54 5.874)
        (xy -20.548 5.896)
        (xy -20.56 5.917)
        (xy -20.57 5.938)
        (xy -20.583 5.957)
        (xy -20.595 5.978)
        (xy -20.61 5.995)
        (xy -20.624 6.013)
        (xy -20.641 6.031)
        (xy -20.657 6.047)
        (xy -20.676 6.061)
        (xy -20.694 6.076)
        (xy -20.714 6.088)
        (xy -20.734 6.1)
        (xy -20.753 6.111)
        (xy -20.775 6.122)
        (xy -20.796 6.13)
        (xy -20.817 6.138)
        (xy -20.84 6.145)
        (xy -20.862 6.151)
        (xy -20.886 6.156)
        (xy -20.909 6.159)
        (xy -20.932 6.159)
        (xy -20.955 6.161)
        (xy -20.979 6.159)
        (xy -21.003 6.159)
        (xy -21.026 6.156)
        (xy -21.049 6.151)
        (xy -21.072 6.145)
        (xy -21.093 6.138)
        (xy -21.115 6.132)
        (xy -21.138 6.122)
        (xy -21.159 6.112)
        (xy -21.179 6.101)
        (xy -21.198 6.088)
        (xy -21.217 6.076)
        (xy -21.237 6.061)
        (xy -21.253 6.047)
        (xy -21.27 6.031)
        (xy -21.287 6.013)
        (xy -21.301 5.997)
        (xy -21.316 5.978)
        (xy -21.328 5.959)
        (xy -21.342 5.938)
        (xy -21.352 5.919)
        (xy -21.362 5.898)
        (xy -21.371 5.875)
        (xy -21.378 5.853)
        (xy -21.386 5.832)
        (xy -21.391 5.81)
        (xy -21.395 5.786)
        (xy -21.398 5.763)
        (xy -21.4 5.739)
        (xy -21.4 5.718)
        (xy -20.955 5.718)
        (xy -20.955 5.713)
      )

      (stroke (width 0.001) (type solid)) (fill solid) (layer "B.Paste"))
    (fp_poly
      (pts
        (xy -19.685 -5.717)
        (xy -20.13 -5.717)
        (xy -20.13 -5.738)
        (xy -20.128 -5.762)
        (xy -20.125 -5.785)
        (xy -20.121 -5.809)
        (xy -20.115 -5.831)
        (xy -20.109 -5.852)
        (xy -20.101 -5.874)
        (xy -20.092 -5.897)
        (xy -20.083 -5.918)
        (xy -20.072 -5.937)
        (xy -20.058 -5.958)
        (xy -20.046 -5.977)
        (xy -20.031 -5.996)
        (xy -20.016 -6.012)
        (xy -20 -6.03)
        (xy -19.984 -6.046)
        (xy -19.967 -6.06)
        (xy -19.947 -6.075)
        (xy -19.929 -6.087)
        (xy -19.909 -6.1)
        (xy -19.889 -6.111)
        (xy -19.868 -6.121)
        (xy -19.845 -6.131)
        (xy -19.823 -6.137)
        (xy -19.801 -6.144)
        (xy -19.779 -6.15)
        (xy -19.756 -6.155)
        (xy -19.734 -6.158)
        (xy -19.709 -6.158)
        (xy -19.685 -6.16)
        (xy -19.662 -6.158)
        (xy -19.639 -6.158)
        (xy -19.615 -6.155)
        (xy -19.592 -6.15)
        (xy -19.57 -6.144)
        (xy -19.548 -6.137)
        (xy -19.526 -6.129)
        (xy -19.505 -6.121)
        (xy -19.484 -6.11)
        (xy -19.462 -6.099)
        (xy -19.444 -6.087)
        (xy -19.423 -6.075)
        (xy -19.406 -6.06)
        (xy -19.388 -6.046)
        (xy -19.371 -6.03)
        (xy -19.354 -6.012)
        (xy -19.339 -5.994)
        (xy -19.325 -5.977)
        (xy -19.313 -5.956)
        (xy -19.301 -5.937)
        (xy -19.29 -5.916)
        (xy -19.278 -5.895)
        (xy -19.27 -5.873)
        (xy -19.263 -5.852)
        (xy -19.255 -5.829)
        (xy -19.25 -5.807)
        (xy -19.246 -5.785)
        (xy -19.243 -5.761)
        (xy -19.241 -5.738)
        (xy -19.24 -5.714)
        (xy -19.241 -5.692)
        (xy -19.243 -5.668)
        (xy -19.246 -5.644)
        (xy -19.25 -5.621)
        (xy -19.255 -5.599)
        (xy -19.263 -5.576)
        (xy -19.27 -5.555)
        (xy -19.278 -5.533)
        (xy -19.29 -5.512)
        (xy -19.301 -5.491)
        (xy -19.313 -5.472)
        (xy -19.325 -5.453)
        (xy -19.339 -5.434)
        (xy -19.354 -5.416)
        (xy -19.371 -5.4)
        (xy -19.388 -5.384)
        (xy -19.406 -5.368)
        (xy -19.423 -5.355)
        (xy -19.444 -5.341)
        (xy -19.462 -5.329)
        (xy -19.484 -5.318)
        (xy -19.505 -5.307)
        (xy -19.526 -5.299)
        (xy -19.548 -5.291)
        (xy -19.57 -5.285)
        (xy -19.592 -5.28)
        (xy -19.615 -5.275)
        (xy -19.639 -5.272)
        (xy -19.662 -5.27)
        (xy -19.685 -5.269)
        (xy -19.709 -5.27)
        (xy -19.734 -5.272)
        (xy -19.756 -5.275)
        (xy -19.779 -5.28)
        (xy -19.801 -5.285)
        (xy -19.823 -5.291)
        (xy -19.845 -5.299)
        (xy -19.868 -5.307)
        (xy -19.889 -5.317)
        (xy -19.909 -5.328)
        (xy -19.929 -5.341)
        (xy -19.947 -5.355)
        (xy -19.967 -5.368)
        (xy -19.984 -5.384)
        (xy -20 -5.4)
        (xy -20.016 -5.416)
        (xy -20.031 -5.434)
        (xy -20.046 -5.453)
        (xy -20.058 -5.472)
        (xy -20.072 -5.491)
        (xy -20.083 -5.511)
        (xy -20.092 -5.533)
        (xy -20.101 -5.554)
        (xy -20.109 -5.576)
        (xy -20.115 -5.599)
        (xy -20.121 -5.621)
        (xy -20.125 -5.644)
        (xy -20.128 -5.666)
        (xy -20.13 -5.69)
        (xy -20.13 -5.712)
        (xy -19.685 -5.712)
        (xy -19.685 -5.717)
      )

      (stroke (width 0.001) (type solid)) (fill solid) (layer "B.Paste"))
    (fp_poly
      (pts
        (xy -19.685 -3.177)
        (xy -20.13 -3.177)
        (xy -20.13 -3.198)
        (xy -20.128 -3.222)
        (xy -20.125 -3.245)
        (xy -20.121 -3.269)
        (xy -20.115 -3.29)
        (xy -20.109 -3.313)
        (xy -20.101 -3.334)
        (xy -20.092 -3.357)
        (xy -20.083 -3.378)
        (xy -20.072 -3.398)
        (xy -20.058 -3.418)
        (xy -20.046 -3.436)
        (xy -20.031 -3.455)
        (xy -20.016 -3.472)
        (xy -20 -3.49)
        (xy -19.984 -3.505)
        (xy -19.967 -3.52)
        (xy -19.947 -3.535)
        (xy -19.929 -3.547)
        (xy -19.909 -3.56)
        (xy -19.889 -3.571)
        (xy -19.868 -3.581)
        (xy -19.845 -3.591)
        (xy -19.823 -3.597)
        (xy -19.801 -3.604)
        (xy -19.779 -3.609)
        (xy -19.756 -3.615)
        (xy -19.734 -3.617)
        (xy -19.709 -3.619)
        (xy -19.685 -3.62)
        (xy -19.662 -3.619)
        (xy -19.639 -3.617)
        (xy -19.615 -3.615)
        (xy -19.592 -3.609)
        (xy -19.57 -3.604)
        (xy -19.548 -3.597)
        (xy -19.526 -3.589)
        (xy -19.505 -3.581)
        (xy -19.484 -3.571)
        (xy -19.462 -3.559)
        (xy -19.444 -3.547)
        (xy -19.423 -3.535)
        (xy -19.406 -3.52)
        (xy -19.388 -3.505)
        (xy -19.371 -3.49)
        (xy -19.354 -3.472)
        (xy -19.339 -3.454)
        (xy -19.325 -3.436)
        (xy -19.313 -3.416)
        (xy -19.301 -3.396)
        (xy -19.29 -3.376)
        (xy -19.278 -3.355)
        (xy -19.27 -3.334)
        (xy -19.263 -3.313)
        (xy -19.255 -3.289)
        (xy -19.25 -3.267)
        (xy -19.246 -3.245)
        (xy -19.243 -3.221)
        (xy -19.241 -3.197)
        (xy -19.24 -3.174)
        (xy -19.241 -3.152)
        (xy -19.243 -3.128)
        (xy -19.246 -3.104)
        (xy -19.25 -3.081)
        (xy -19.255 -3.059)
        (xy -19.263 -3.036)
        (xy -19.27 -3.015)
        (xy -19.278 -2.994)
        (xy -19.29 -2.972)
        (xy -19.301 -2.951)
        (xy -19.313 -2.932)
        (xy -19.325 -2.912)
        (xy -19.339 -2.894)
        (xy -19.354 -2.876)
        (xy -19.371 -2.859)
        (xy -19.388 -2.843)
        (xy -19.406 -2.829)
        (xy -19.423 -2.814)
        (xy -19.444 -2.801)
        (xy -19.462 -2.789)
        (xy -19.484 -2.778)
        (xy -19.505 -2.767)
        (xy -19.526 -2.759)
        (xy -19.548 -2.751)
        (xy -19.57 -2.745)
        (xy -19.592 -2.74)
        (xy -19.615 -2.734)
        (xy -19.639 -2.732)
        (xy -19.662 -2.73)
        (xy -19.685 -2.729)
        (xy -19.709 -2.73)
        (xy -19.734 -2.732)
        (xy -19.756 -2.734)
        (xy -19.779 -2.74)
        (xy -19.801 -2.745)
        (xy -19.823 -2.751)
        (xy -19.845 -2.758)
        (xy -19.868 -2.767)
        (xy -19.889 -2.777)
        (xy -19.909 -2.789)
        (xy -19.929 -2.801)
        (xy -19.947 -2.814)
        (xy -19.967 -2.829)
        (xy -19.984 -2.843)
        (xy -20 -2.859)
        (xy -20.016 -2.876)
        (xy -20.031 -2.894)
        (xy -20.046 -2.912)
        (xy -20.058 -2.931)
        (xy -20.072 -2.951)
        (xy -20.083 -2.971)
        (xy -20.092 -2.992)
        (xy -20.101 -3.015)
        (xy -20.109 -3.036)
        (xy -20.115 -3.059)
        (xy -20.121 -3.08)
        (xy -20.125 -3.104)
        (xy -20.128 -3.126)
        (xy -20.13 -3.15)
        (xy -20.13 -3.172)
        (xy -19.685 -3.172)
        (xy -19.685 -3.177)
      )

      (stroke (width 0.001) (type solid)) (fill solid) (layer "B.Paste"))
    (fp_poly
      (pts
        (xy -19.685 1.903)
        (xy -20.13 1.903)
        (xy -20.13 1.881)
        (xy -20.128 1.857)
        (xy -20.125 1.835)
        (xy -20.121 1.811)
        (xy -20.115 1.789)
        (xy -20.109 1.767)
        (xy -20.101 1.746)
        (xy -20.092 1.724)
        (xy -20.083 1.702)
        (xy -20.072 1.682)
        (xy -20.058 1.662)
        (xy -20.046 1.643)
        (xy -20.031 1.625)
        (xy -20.016 1.607)
        (xy -20 1.591)
        (xy -19.984 1.575)
        (xy -19.967 1.559)
        (xy -19.947 1.545)
        (xy -19.929 1.532)
        (xy -19.909 1.519)
        (xy -19.889 1.508)
        (xy -19.868 1.498)
        (xy -19.845 1.49)
        (xy -19.823 1.482)
        (xy -19.801 1.476)
        (xy -19.779 1.47)
        (xy -19.756 1.466)
        (xy -19.734 1.462)
        (xy -19.709 1.462)
        (xy -19.685 1.46)
        (xy -19.662 1.462)
        (xy -19.639 1.462)
        (xy -19.615 1.466)
        (xy -19.592 1.47)
        (xy -19.57 1.476)
        (xy -19.548 1.482)
        (xy -19.526 1.49)
        (xy -19.505 1.498)
        (xy -19.484 1.509)
        (xy -19.462 1.52)
        (xy -19.444 1.532)
        (xy -19.423 1.545)
        (xy -19.406 1.559)
        (xy -19.388 1.575)
        (xy -19.371 1.591)
        (xy -19.354 1.607)
        (xy -19.339 1.625)
        (xy -19.325 1.643)
        (xy -19.313 1.663)
        (xy -19.301 1.684)
        (xy -19.29 1.704)
        (xy -19.278 1.724)
        (xy -19.27 1.746)
        (xy -19.263 1.767)
        (xy -19.255 1.79)
        (xy -19.25 1.813)
        (xy -19.246 1.835)
        (xy -19.243 1.859)
        (xy -19.241 1.882)
        (xy -19.24 1.905)
        (xy -19.241 1.928)
        (xy -19.243 1.952)
        (xy -19.246 1.976)
        (xy -19.25 1.998)
        (xy -19.255 2.02)
        (xy -19.263 2.044)
        (xy -19.27 2.065)
        (xy -19.278 2.086)
        (xy -19.29 2.108)
        (xy -19.301 2.127)
        (xy -19.313 2.147)
        (xy -19.325 2.167)
        (xy -19.339 2.186)
        (xy -19.354 2.203)
        (xy -19.371 2.221)
        (xy -19.388 2.237)
        (xy -19.406 2.251)
        (xy -19.423 2.266)
        (xy -19.444 2.278)
        (xy -19.462 2.29)
        (xy -19.484 2.302)
        (xy -19.505 2.312)
        (xy -19.526 2.32)
        (xy -19.548 2.328)
        (xy -19.57 2.335)
        (xy -19.592 2.34)
        (xy -19.615 2.346)
        (xy -19.639 2.348)
        (xy -19.662 2.35)
        (xy -19.685 2.351)
        (xy -19.709 2.35)
        (xy -19.734 2.348)
        (xy -19.756 2.346)
        (xy -19.779 2.34)
        (xy -19.801 2.335)
        (xy -19.823 2.328)
        (xy -19.845 2.322)
        (xy -19.868 2.312)
        (xy -19.889 2.302)
        (xy -19.909 2.291)
        (xy -19.929 2.278)
        (xy -19.947 2.266)
        (xy -19.967 2.251)
        (xy -19.984 2.237)
        (xy -20 2.221)
        (xy -20.016 2.203)
        (xy -20.031 2.186)
        (xy -20.046 2.167)
        (xy -20.058 2.149)
        (xy -20.072 2.129)
        (xy -20.083 2.109)
        (xy -20.092 2.088)
        (xy -20.101 2.065)
        (xy -20.109 2.044)
        (xy -20.115 2.021)
        (xy -20.121 2)
        (xy -20.125 1.976)
        (xy -20.128 1.954)
        (xy -20.13 1.93)
        (xy -20.13 1.907)
        (xy -19.685 1.907)
        (xy -19.685 1.903)
      )

      (stroke (width 0.001) (type solid)) (fill solid) (layer "B.Paste"))
    (fp_poly
      (pts
        (xy -19.685 3.173)
        (xy -20.13 3.173)
        (xy -20.13 3.151)
        (xy -20.128 3.127)
        (xy -20.125 3.105)
        (xy -20.121 3.081)
        (xy -20.115 3.06)
        (xy -20.109 3.037)
        (xy -20.101 3.016)
        (xy -20.092 2.993)
        (xy -20.083 2.972)
        (xy -20.072 2.952)
        (xy -20.058 2.932)
        (xy -20.046 2.913)
        (xy -20.031 2.895)
        (xy -20.016 2.877)
        (xy -20 2.86)
        (xy -19.984 2.844)
        (xy -19.967 2.83)
        (xy -19.947 2.815)
        (xy -19.929 2.802)
        (xy -19.909 2.79)
        (xy -19.889 2.778)
        (xy -19.868 2.768)
        (xy -19.845 2.759)
        (xy -19.823 2.752)
        (xy -19.801 2.746)
        (xy -19.779 2.741)
        (xy -19.756 2.735)
        (xy -19.734 2.733)
        (xy -19.709 2.731)
        (xy -19.685 2.73)
        (xy -19.662 2.731)
        (xy -19.639 2.733)
        (xy -19.615 2.735)
        (xy -19.592 2.741)
        (xy -19.57 2.746)
        (xy -19.548 2.752)
        (xy -19.526 2.76)
        (xy -19.505 2.768)
        (xy -19.484 2.779)
        (xy -19.462 2.79)
        (xy -19.444 2.802)
        (xy -19.423 2.815)
        (xy -19.406 2.83)
        (xy -19.388 2.844)
        (xy -19.371 2.86)
        (xy -19.354 2.877)
        (xy -19.339 2.895)
        (xy -19.325 2.913)
        (xy -19.313 2.933)
        (xy -19.301 2.952)
        (xy -19.29 2.973)
        (xy -19.278 2.995)
        (xy -19.27 3.016)
        (xy -19.263 3.037)
        (xy -19.255 3.06)
        (xy -19.25 3.082)
        (xy -19.246 3.105)
        (xy -19.243 3.129)
        (xy -19.241 3.153)
        (xy -19.24 3.175)
        (xy -19.241 3.198)
        (xy -19.243 3.222)
        (xy -19.246 3.246)
        (xy -19.25 3.268)
        (xy -19.255 3.29)
        (xy -19.263 3.314)
        (xy -19.27 3.335)
        (xy -19.278 3.356)
        (xy -19.29 3.377)
        (xy -19.301 3.397)
        (xy -19.313 3.417)
        (xy -19.325 3.437)
        (xy -19.339 3.455)
        (xy -19.354 3.473)
        (xy -19.371 3.491)
        (xy -19.388 3.506)
        (xy -19.406 3.521)
        (xy -19.423 3.536)
        (xy -19.444 3.548)
        (xy -19.462 3.56)
        (xy -19.484 3.572)
        (xy -19.505 3.582)
        (xy -19.526 3.59)
        (xy -19.548 3.598)
        (xy -19.57 3.605)
        (xy -19.592 3.61)
        (xy -19.615 3.616)
        (xy -19.639 3.618)
        (xy -19.662 3.62)
        (xy -19.685 3.621)
        (xy -19.709 3.62)
        (xy -19.734 3.618)
        (xy -19.756 3.616)
        (xy -19.779 3.61)
        (xy -19.801 3.605)
        (xy -19.823 3.598)
        (xy -19.845 3.592)
        (xy -19.868 3.582)
        (xy -19.889 3.572)
        (xy -19.909 3.561)
        (xy -19.929 3.548)
        (xy -19.947 3.536)
        (xy -19.967 3.521)
        (xy -19.984 3.506)
        (xy -20 3.491)
        (xy -20.016 3.473)
        (xy -20.031 3.456)
        (xy -20.046 3.437)
        (xy -20.058 3.419)
        (xy -20.072 3.399)
        (xy -20.083 3.379)
        (xy -20.092 3.358)
        (xy -20.101 3.335)
        (xy -20.109 3.314)
        (xy -20.115 3.291)
        (xy -20.121 3.27)
        (xy -20.125 3.246)
        (xy -20.128 3.223)
        (xy -20.13 3.199)
        (xy -20.13 3.178)
        (xy -19.685 3.178)
        (xy -19.685 3.173)
      )

      (stroke (width 0.001) (type solid)) (fill solid) (layer "B.Paste"))
    (fp_poly
      (pts
        (xy -19.685 4.443)
        (xy -20.13 4.443)
        (xy -20.13 4.422)
        (xy -20.128 4.398)
        (xy -20.125 4.374)
        (xy -20.121 4.351)
        (xy -20.115 4.329)
        (xy -20.109 4.308)
        (xy -20.101 4.286)
        (xy -20.092 4.263)
        (xy -20.083 4.242)
        (xy -20.072 4.223)
        (xy -20.058 4.202)
        (xy -20.046 4.183)
        (xy -20.031 4.164)
        (xy -20.016 4.148)
        (xy -20 4.13)
        (xy -19.984 4.114)
        (xy -19.967 4.1)
        (xy -19.947 4.085)
        (xy -19.929 4.072)
        (xy -19.909 4.06)
        (xy -19.889 4.048)
        (xy -19.868 4.039)
        (xy -19.845 4.029)
        (xy -19.823 4.023)
        (xy -19.801 4.015)
        (xy -19.779 4.01)
        (xy -19.756 4.005)
        (xy -19.734 4.002)
        (xy -19.709 4.002)
        (xy -19.685 4)
        (xy -19.662 4.002)
        (xy -19.639 4.002)
        (xy -19.615 4.005)
        (xy -19.592 4.01)
        (xy -19.57 4.015)
        (xy -19.548 4.023)
        (xy -19.526 4.031)
        (xy -19.505 4.039)
        (xy -19.484 4.05)
        (xy -19.462 4.06)
        (xy -19.444 4.072)
        (xy -19.423 4.085)
        (xy -19.406 4.1)
        (xy -19.388 4.114)
        (xy -19.371 4.13)
        (xy -19.354 4.148)
        (xy -19.339 4.165)
        (xy -19.325 4.183)
        (xy -19.313 4.204)
        (xy -19.301 4.223)
        (xy -19.29 4.244)
        (xy -19.278 4.265)
        (xy -19.27 4.286)
        (xy -19.263 4.308)
        (xy -19.255 4.33)
        (xy -19.25 4.353)
        (xy -19.246 4.375)
        (xy -19.243 4.398)
        (xy -19.241 4.422)
        (xy -19.24 4.446)
        (xy -19.241 4.468)
        (xy -19.243 4.492)
        (xy -19.246 4.515)
        (xy -19.25 4.539)
        (xy -19.255 4.56)
        (xy -19.263 4.584)
        (xy -19.27 4.604)
        (xy -19.278 4.627)
        (xy -19.29 4.648)
        (xy -19.301 4.669)
        (xy -19.313 4.688)
        (xy -19.325 4.707)
        (xy -19.339 4.725)
        (xy -19.354 4.744)
        (xy -19.371 4.76)
        (xy -19.388 4.776)
        (xy -19.406 4.792)
        (xy -19.423 4.805)
        (xy -19.444 4.818)
        (xy -19.462 4.83)
        (xy -19.484 4.842)
        (xy -19.505 4.853)
        (xy -19.526 4.861)
        (xy -19.548 4.869)
        (xy -19.57 4.875)
        (xy -19.592 4.88)
        (xy -19.615 4.885)
        (xy -19.639 4.888)
        (xy -19.662 4.89)
        (xy -19.685 4.89)
        (xy -19.709 4.89)
        (xy -19.734 4.888)
        (xy -19.756 4.885)
        (xy -19.779 4.88)
        (xy -19.801 4.875)
        (xy -19.823 4.869)
        (xy -19.845 4.861)
        (xy -19.868 4.853)
        (xy -19.889 4.842)
        (xy -19.909 4.832)
        (xy -19.929 4.818)
        (xy -19.947 4.805)
        (xy -19.967 4.792)
        (xy -19.984 4.776)
        (xy -20 4.76)
        (xy -20.016 4.744)
        (xy -20.031 4.726)
        (xy -20.046 4.707)
        (xy -20.058 4.688)
        (xy -20.072 4.669)
        (xy -20.083 4.648)
        (xy -20.092 4.627)
        (xy -20.101 4.606)
        (xy -20.109 4.584)
        (xy -20.115 4.561)
        (xy -20.121 4.539)
        (xy -20.125 4.516)
        (xy -20.128 4.494)
        (xy -20.13 4.47)
        (xy -20.13 4.447)
        (xy -19.685 4.447)
        (xy -19.685 4.443)
      )

      (stroke (width 0.001) (type solid)) (fill solid) (layer "B.Paste"))
    (fp_poly
      (pts
        (xy -19.685 5.713)
        (xy -20.13 5.713)
        (xy -20.13 5.691)
        (xy -20.128 5.667)
        (xy -20.125 5.645)
        (xy -20.121 5.622)
        (xy -20.115 5.6)
        (xy -20.109 5.577)
        (xy -20.101 5.555)
        (xy -20.092 5.534)
        (xy -20.083 5.512)
        (xy -20.072 5.492)
        (xy -20.058 5.473)
        (xy -20.046 5.454)
        (xy -20.031 5.435)
        (xy -20.016 5.417)
        (xy -20 5.401)
        (xy -19.984 5.385)
        (xy -19.967 5.369)
        (xy -19.947 5.356)
        (xy -19.929 5.342)
        (xy -19.909 5.329)
        (xy -19.889 5.318)
        (xy -19.868 5.308)
        (xy -19.845 5.3)
        (xy -19.823 5.292)
        (xy -19.801 5.286)
        (xy -19.779 5.281)
        (xy -19.756 5.276)
        (xy -19.734 5.273)
        (xy -19.709 5.271)
        (xy -19.685 5.27)
        (xy -19.662 5.271)
        (xy -19.639 5.273)
        (xy -19.615 5.276)
        (xy -19.592 5.281)
        (xy -19.57 5.286)
        (xy -19.548 5.292)
        (xy -19.526 5.3)
        (xy -19.505 5.308)
        (xy -19.484 5.319)
        (xy -19.462 5.33)
        (xy -19.444 5.342)
        (xy -19.423 5.356)
        (xy -19.406 5.369)
        (xy -19.388 5.385)
        (xy -19.371 5.401)
        (xy -19.354 5.417)
        (xy -19.339 5.435)
        (xy -19.325 5.454)
        (xy -19.313 5.473)
        (xy -19.301 5.492)
        (xy -19.29 5.513)
        (xy -19.278 5.534)
        (xy -19.27 5.556)
        (xy -19.263 5.577)
        (xy -19.255 5.6)
        (xy -19.25 5.622)
        (xy -19.246 5.645)
        (xy -19.243 5.669)
        (xy -19.241 5.693)
        (xy -19.24 5.715)
        (xy -19.241 5.739)
        (xy -19.243 5.762)
        (xy -19.246 5.786)
        (xy -19.25 5.808)
        (xy -19.255 5.83)
        (xy -19.263 5.853)
        (xy -19.27 5.874)
        (xy -19.278 5.896)
        (xy -19.29 5.917)
        (xy -19.301 5.938)
        (xy -19.313 5.957)
        (xy -19.325 5.978)
        (xy -19.339 5.995)
        (xy -19.354 6.013)
        (xy -19.371 6.031)
        (xy -19.388 6.047)
        (xy -19.406 6.061)
        (xy -19.423 6.076)
        (xy -19.444 6.088)
        (xy -19.462 6.1)
        (xy -19.484 6.111)
        (xy -19.505 6.122)
        (xy -19.526 6.13)
        (xy -19.548 6.138)
        (xy -19.57 6.145)
        (xy -19.592 6.151)
        (xy -19.615 6.156)
        (xy -19.639 6.159)
        (xy -19.662 6.159)
        (xy -19.685 6.161)
        (xy -19.709 6.159)
        (xy -19.734 6.159)
        (xy -19.756 6.156)
        (xy -19.779 6.151)
        (xy -19.801 6.145)
        (xy -19.823 6.138)
        (xy -19.845 6.132)
        (xy -19.868 6.122)
        (xy -19.889 6.112)
        (xy -19.909 6.101)
        (xy -19.929 6.088)
        (xy -19.947 6.076)
        (xy -19.967 6.061)
        (xy -19.984 6.047)
        (xy -20 6.031)
        (xy -20.016 6.013)
        (xy -20.031 5.997)
        (xy -20.046 5.978)
        (xy -20.058 5.959)
        (xy -20.072 5.938)
        (xy -20.083 5.919)
        (xy -20.092 5.898)
        (xy -20.101 5.875)
        (xy -20.109 5.853)
        (xy -20.115 5.832)
        (xy -20.121 5.81)
        (xy -20.125 5.786)
        (xy -20.128 5.763)
        (xy -20.13 5.739)
        (xy -20.13 5.718)
        (xy -19.685 5.718)
        (xy -19.685 5.713)
      )

      (stroke (width 0.001) (type solid)) (fill solid) (layer "B.Paste"))
    (fp_poly
      (pts
        (xy -18.415 -5.717)
        (xy -18.86 -5.717)
        (xy -18.86 -5.738)
        (xy -18.859 -5.762)
        (xy -18.856 -5.785)
        (xy -18.851 -5.809)
        (xy -18.845 -5.831)
        (xy -18.839 -5.852)
        (xy -18.831 -5.874)
        (xy -18.822 -5.897)
        (xy -18.813 -5.918)
        (xy -18.801 -5.937)
        (xy -18.788 -5.958)
        (xy -18.775 -5.977)
        (xy -18.761 -5.996)
        (xy -18.746 -6.012)
        (xy -18.731 -6.03)
        (xy -18.714 -6.046)
        (xy -18.697 -6.06)
        (xy -18.677 -6.075)
        (xy -18.659 -6.087)
        (xy -18.639 -6.1)
        (xy -18.618 -6.111)
        (xy -18.598 -6.121)
        (xy -18.575 -6.131)
        (xy -18.554 -6.137)
        (xy -18.531 -6.144)
        (xy -18.509 -6.15)
        (xy -18.487 -6.155)
        (xy -18.464 -6.158)
        (xy -18.439 -6.158)
        (xy -18.415 -6.16)
        (xy -18.392 -6.158)
        (xy -18.368 -6.158)
        (xy -18.345 -6.155)
        (xy -18.322 -6.15)
        (xy -18.301 -6.144)
        (xy -18.278 -6.137)
        (xy -18.256 -6.129)
        (xy -18.235 -6.121)
        (xy -18.214 -6.11)
        (xy -18.192 -6.099)
        (xy -18.173 -6.087)
        (xy -18.153 -6.075)
        (xy -18.136 -6.06)
        (xy -18.118 -6.046)
        (xy -18.101 -6.03)
        (xy -18.084 -6.012)
        (xy -18.069 -5.994)
        (xy -18.055 -5.977)
        (xy -18.043 -5.956)
        (xy -18.031 -5.937)
        (xy -18.019 -5.916)
        (xy -18.008 -5.895)
        (xy -18 -5.873)
        (xy -17.993 -5.852)
        (xy -17.985 -5.829)
        (xy -17.981 -5.807)
        (xy -17.976 -5.785)
        (xy -17.973 -5.761)
        (xy -17.971 -5.738)
        (xy -17.97 -5.714)
        (xy -17.971 -5.692)
        (xy -17.973 -5.668)
        (xy -17.976 -5.644)
        (xy -17.981 -5.621)
        (xy -17.985 -5.599)
        (xy -17.993 -5.576)
        (xy -18 -5.555)
        (xy -18.008 -5.533)
        (xy -18.019 -5.512)
        (xy -18.031 -5.491)
        (xy -18.043 -5.472)
        (xy -18.055 -5.453)
        (xy -18.069 -5.434)
        (xy -18.084 -5.416)
        (xy -18.101 -5.4)
        (xy -18.118 -5.384)
        (xy -18.136 -5.368)
        (xy -18.153 -5.355)
        (xy -18.173 -5.341)
        (xy -18.192 -5.329)
        (xy -18.214 -5.318)
        (xy -18.235 -5.307)
        (xy -18.256 -5.299)
        (xy -18.278 -5.291)
        (xy -18.301 -5.285)
        (xy -18.322 -5.28)
        (xy -18.345 -5.275)
        (xy -18.368 -5.272)
        (xy -18.392 -5.27)
        (xy -18.415 -5.269)
        (xy -18.439 -5.27)
        (xy -18.464 -5.272)
        (xy -18.487 -5.275)
        (xy -18.509 -5.28)
        (xy -18.531 -5.285)
        (xy -18.554 -5.291)
        (xy -18.575 -5.299)
        (xy -18.598 -5.307)
        (xy -18.618 -5.317)
        (xy -18.639 -5.328)
        (xy -18.659 -5.341)
        (xy -18.677 -5.355)
        (xy -18.697 -5.368)
        (xy -18.714 -5.384)
        (xy -18.731 -5.4)
        (xy -18.746 -5.416)
        (xy -18.761 -5.434)
        (xy -18.775 -5.453)
        (xy -18.788 -5.472)
        (xy -18.801 -5.491)
        (xy -18.813 -5.511)
        (xy -18.822 -5.533)
        (xy -18.831 -5.554)
        (xy -18.839 -5.576)
        (xy -18.845 -5.599)
        (xy -18.851 -5.621)
        (xy -18.856 -5.644)
        (xy -18.859 -5.666)
        (xy -18.86 -5.69)
        (xy -18.86 -5.712)
        (xy -18.415 -5.712)
        (xy -18.415 -5.717)
      )

      (stroke (width 0.001) (type solid)) (fill solid) (layer "B.Paste"))
    (fp_poly
      (pts
        (xy -18.415 -3.177)
        (xy -18.86 -3.177)
        (xy -18.86 -3.198)
        (xy -18.859 -3.222)
        (xy -18.856 -3.245)
        (xy -18.851 -3.269)
        (xy -18.845 -3.29)
        (xy -18.839 -3.313)
        (xy -18.831 -3.334)
        (xy -18.822 -3.357)
        (xy -18.813 -3.378)
        (xy -18.801 -3.398)
        (xy -18.788 -3.418)
        (xy -18.775 -3.436)
        (xy -18.761 -3.455)
        (xy -18.746 -3.472)
        (xy -18.731 -3.49)
        (xy -18.714 -3.505)
        (xy -18.697 -3.52)
        (xy -18.677 -3.535)
        (xy -18.659 -3.547)
        (xy -18.639 -3.56)
        (xy -18.618 -3.571)
        (xy -18.598 -3.581)
        (xy -18.575 -3.591)
        (xy -18.554 -3.597)
        (xy -18.531 -3.604)
        (xy -18.509 -3.609)
        (xy -18.487 -3.615)
        (xy -18.464 -3.617)
        (xy -18.439 -3.619)
        (xy -18.415 -3.62)
        (xy -18.392 -3.619)
        (xy -18.368 -3.617)
        (xy -18.345 -3.615)
        (xy -18.322 -3.609)
        (xy -18.301 -3.604)
        (xy -18.278 -3.597)
        (xy -18.256 -3.589)
        (xy -18.235 -3.581)
        (xy -18.214 -3.571)
        (xy -18.192 -3.559)
        (xy -18.173 -3.547)
        (xy -18.153 -3.535)
        (xy -18.136 -3.52)
        (xy -18.118 -3.505)
        (xy -18.101 -3.49)
        (xy -18.084 -3.472)
        (xy -18.069 -3.454)
        (xy -18.055 -3.436)
        (xy -18.043 -3.416)
        (xy -18.031 -3.396)
        (xy -18.019 -3.376)
        (xy -18.008 -3.355)
        (xy -18 -3.334)
        (xy -17.993 -3.313)
        (xy -17.985 -3.289)
        (xy -17.981 -3.267)
        (xy -17.976 -3.245)
        (xy -17.973 -3.221)
        (xy -17.971 -3.197)
        (xy -17.97 -3.174)
        (xy -17.971 -3.152)
        (xy -17.973 -3.128)
        (xy -17.976 -3.104)
        (xy -17.981 -3.081)
        (xy -17.985 -3.059)
        (xy -17.993 -3.036)
        (xy -18 -3.015)
        (xy -18.008 -2.994)
        (xy -18.019 -2.972)
        (xy -18.031 -2.951)
        (xy -18.043 -2.932)
        (xy -18.055 -2.912)
        (xy -18.069 -2.894)
        (xy -18.084 -2.876)
        (xy -18.101 -2.859)
        (xy -18.118 -2.843)
        (xy -18.136 -2.829)
        (xy -18.153 -2.814)
        (xy -18.173 -2.801)
        (xy -18.192 -2.789)
        (xy -18.214 -2.778)
        (xy -18.235 -2.767)
        (xy -18.256 -2.759)
        (xy -18.278 -2.751)
        (xy -18.301 -2.745)
        (xy -18.322 -2.74)
        (xy -18.345 -2.734)
        (xy -18.368 -2.732)
        (xy -18.392 -2.73)
        (xy -18.415 -2.729)
        (xy -18.439 -2.73)
        (xy -18.464 -2.732)
        (xy -18.487 -2.734)
        (xy -18.509 -2.74)
        (xy -18.531 -2.745)
        (xy -18.554 -2.751)
        (xy -18.575 -2.758)
        (xy -18.598 -2.767)
        (xy -18.618 -2.777)
        (xy -18.639 -2.789)
        (xy -18.659 -2.801)
        (xy -18.677 -2.814)
        (xy -18.697 -2.829)
        (xy -18.714 -2.843)
        (xy -18.731 -2.859)
        (xy -18.746 -2.876)
        (xy -18.761 -2.894)
        (xy -18.775 -2.912)
        (xy -18.788 -2.931)
        (xy -18.801 -2.951)
        (xy -18.813 -2.971)
        (xy -18.822 -2.992)
        (xy -18.831 -3.015)
        (xy -18.839 -3.036)
        (xy -18.845 -3.059)
        (xy -18.851 -3.08)
        (xy -18.856 -3.104)
        (xy -18.859 -3.126)
        (xy -18.86 -3.15)
        (xy -18.86 -3.172)
        (xy -18.415 -3.172)
        (xy -18.415 -3.177)
      )

      (stroke (width 0.001) (type solid)) (fill solid) (layer "B.Paste"))
    (fp_poly
      (pts
        (xy -18.415 1.903)
        (xy -18.86 1.903)
        (xy -18.86 1.881)
        (xy -18.859 1.857)
        (xy -18.856 1.835)
        (xy -18.851 1.811)
        (xy -18.845 1.789)
        (xy -18.839 1.767)
        (xy -18.831 1.746)
        (xy -18.822 1.724)
        (xy -18.813 1.702)
        (xy -18.801 1.682)
        (xy -18.788 1.662)
        (xy -18.775 1.643)
        (xy -18.761 1.625)
        (xy -18.746 1.607)
        (xy -18.731 1.591)
        (xy -18.714 1.575)
        (xy -18.697 1.559)
        (xy -18.677 1.545)
        (xy -18.659 1.532)
        (xy -18.639 1.519)
        (xy -18.618 1.508)
        (xy -18.598 1.498)
        (xy -18.575 1.49)
        (xy -18.554 1.482)
        (xy -18.531 1.476)
        (xy -18.509 1.47)
        (xy -18.487 1.466)
        (xy -18.464 1.462)
        (xy -18.439 1.462)
        (xy -18.415 1.46)
        (xy -18.392 1.462)
        (xy -18.368 1.462)
        (xy -18.345 1.466)
        (xy -18.322 1.47)
        (xy -18.301 1.476)
        (xy -18.278 1.482)
        (xy -18.256 1.49)
        (xy -18.235 1.498)
        (xy -18.214 1.509)
        (xy -18.192 1.52)
        (xy -18.173 1.532)
        (xy -18.153 1.545)
        (xy -18.136 1.559)
        (xy -18.118 1.575)
        (xy -18.101 1.591)
        (xy -18.084 1.607)
        (xy -18.069 1.625)
        (xy -18.055 1.643)
        (xy -18.043 1.663)
        (xy -18.031 1.684)
        (xy -18.019 1.704)
        (xy -18.008 1.724)
        (xy -18 1.746)
        (xy -17.993 1.767)
        (xy -17.985 1.79)
        (xy -17.981 1.813)
        (xy -17.976 1.835)
        (xy -17.973 1.859)
        (xy -17.971 1.882)
        (xy -17.97 1.905)
        (xy -17.971 1.928)
        (xy -17.973 1.952)
        (xy -17.976 1.976)
        (xy -17.981 1.998)
        (xy -17.985 2.02)
        (xy -17.993 2.044)
        (xy -18 2.065)
        (xy -18.008 2.086)
        (xy -18.019 2.108)
        (xy -18.031 2.127)
        (xy -18.043 2.147)
        (xy -18.055 2.167)
        (xy -18.069 2.186)
        (xy -18.084 2.203)
        (xy -18.101 2.221)
        (xy -18.118 2.237)
        (xy -18.136 2.251)
        (xy -18.153 2.266)
        (xy -18.173 2.278)
        (xy -18.192 2.29)
        (xy -18.214 2.302)
        (xy -18.235 2.312)
        (xy -18.256 2.32)
        (xy -18.278 2.328)
        (xy -18.301 2.335)
        (xy -18.322 2.34)
        (xy -18.345 2.346)
        (xy -18.368 2.348)
        (xy -18.392 2.35)
        (xy -18.415 2.351)
        (xy -18.439 2.35)
        (xy -18.464 2.348)
        (xy -18.487 2.346)
        (xy -18.509 2.34)
        (xy -18.531 2.335)
        (xy -18.554 2.328)
        (xy -18.575 2.322)
        (xy -18.598 2.312)
        (xy -18.618 2.302)
        (xy -18.639 2.291)
        (xy -18.659 2.278)
        (xy -18.677 2.266)
        (xy -18.697 2.251)
        (xy -18.714 2.237)
        (xy -18.731 2.221)
        (xy -18.746 2.203)
        (xy -18.761 2.186)
        (xy -18.775 2.167)
        (xy -18.788 2.149)
        (xy -18.801 2.129)
        (xy -18.813 2.109)
        (xy -18.822 2.088)
        (xy -18.831 2.065)
        (xy -18.839 2.044)
        (xy -18.845 2.021)
        (xy -18.851 2)
        (xy -18.856 1.976)
        (xy -18.859 1.954)
        (xy -18.86 1.93)
        (xy -18.86 1.907)
        (xy -18.415 1.907)
        (xy -18.415 1.903)
      )

      (stroke (width 0.001) (type solid)) (fill solid) (layer "B.Paste"))
    (fp_poly
      (pts
        (xy -18.415 3.173)
        (xy -18.86 3.173)
        (xy -18.86 3.151)
        (xy -18.859 3.127)
        (xy -18.856 3.105)
        (xy -18.851 3.081)
        (xy -18.845 3.06)
        (xy -18.839 3.037)
        (xy -18.831 3.016)
        (xy -18.822 2.993)
        (xy -18.813 2.972)
        (xy -18.801 2.952)
        (xy -18.788 2.932)
        (xy -18.775 2.913)
        (xy -18.761 2.895)
        (xy -18.746 2.877)
        (xy -18.731 2.86)
        (xy -18.714 2.844)
        (xy -18.697 2.83)
        (xy -18.677 2.815)
        (xy -18.659 2.802)
        (xy -18.639 2.79)
        (xy -18.618 2.778)
        (xy -18.598 2.768)
        (xy -18.575 2.759)
        (xy -18.554 2.752)
        (xy -18.531 2.746)
        (xy -18.509 2.741)
        (xy -18.487 2.735)
        (xy -18.464 2.733)
        (xy -18.439 2.731)
        (xy -18.415 2.73)
        (xy -18.392 2.731)
        (xy -18.368 2.733)
        (xy -18.345 2.735)
        (xy -18.322 2.741)
        (xy -18.301 2.746)
        (xy -18.278 2.752)
        (xy -18.256 2.76)
        (xy -18.235 2.768)
        (xy -18.214 2.779)
        (xy -18.192 2.79)
        (xy -18.173 2.802)
        (xy -18.153 2.815)
        (xy -18.136 2.83)
        (xy -18.118 2.844)
        (xy -18.101 2.86)
        (xy -18.084 2.877)
        (xy -18.069 2.895)
        (xy -18.055 2.913)
        (xy -18.043 2.933)
        (xy -18.031 2.952)
        (xy -18.019 2.973)
        (xy -18.008 2.995)
        (xy -18 3.016)
        (xy -17.993 3.037)
        (xy -17.985 3.06)
        (xy -17.981 3.082)
        (xy -17.976 3.105)
        (xy -17.973 3.129)
        (xy -17.971 3.153)
        (xy -17.97 3.175)
        (xy -17.971 3.198)
        (xy -17.973 3.222)
        (xy -17.976 3.246)
        (xy -17.981 3.268)
        (xy -17.985 3.29)
        (xy -17.993 3.314)
        (xy -18 3.335)
        (xy -18.008 3.356)
        (xy -18.019 3.377)
        (xy -18.031 3.397)
        (xy -18.043 3.417)
        (xy -18.055 3.437)
        (xy -18.069 3.455)
        (xy -18.084 3.473)
        (xy -18.101 3.491)
        (xy -18.118 3.506)
        (xy -18.136 3.521)
        (xy -18.153 3.536)
        (xy -18.173 3.548)
        (xy -18.192 3.56)
        (xy -18.214 3.572)
        (xy -18.235 3.582)
        (xy -18.256 3.59)
        (xy -18.278 3.598)
        (xy -18.301 3.605)
        (xy -18.322 3.61)
        (xy -18.345 3.616)
        (xy -18.368 3.618)
        (xy -18.392 3.62)
        (xy -18.415 3.621)
        (xy -18.439 3.62)
        (xy -18.464 3.618)
        (xy -18.487 3.616)
        (xy -18.509 3.61)
        (xy -18.531 3.605)
        (xy -18.554 3.598)
        (xy -18.575 3.592)
        (xy -18.598 3.582)
        (xy -18.618 3.572)
        (xy -18.639 3.561)
        (xy -18.659 3.548)
        (xy -18.677 3.536)
        (xy -18.697 3.521)
        (xy -18.714 3.506)
        (xy -18.731 3.491)
        (xy -18.746 3.473)
        (xy -18.761 3.456)
        (xy -18.775 3.437)
        (xy -18.788 3.419)
        (xy -18.801 3.399)
        (xy -18.813 3.379)
        (xy -18.822 3.358)
        (xy -18.831 3.335)
        (xy -18.839 3.314)
        (xy -18.845 3.291)
        (xy -18.851 3.27)
        (xy -18.856 3.246)
        (xy -18.859 3.223)
        (xy -18.86 3.199)
        (xy -18.86 3.178)
        (xy -18.415 3.178)
        (xy -18.415 3.173)
      )

      (stroke (width 0.001) (type solid)) (fill solid) (layer "B.Paste"))
    (fp_poly
      (pts
        (xy -18.415 4.443)
        (xy -18.86 4.443)
        (xy -18.86 4.422)
        (xy -18.859 4.398)
        (xy -18.856 4.374)
        (xy -18.851 4.351)
        (xy -18.845 4.329)
        (xy -18.839 4.308)
        (xy -18.831 4.286)
        (xy -18.822 4.263)
        (xy -18.813 4.242)
        (xy -18.801 4.223)
        (xy -18.788 4.202)
        (xy -18.775 4.183)
        (xy -18.761 4.164)
        (xy -18.746 4.148)
        (xy -18.731 4.13)
        (xy -18.714 4.114)
        (xy -18.697 4.1)
        (xy -18.677 4.085)
        (xy -18.659 4.072)
        (xy -18.639 4.06)
        (xy -18.618 4.048)
        (xy -18.598 4.039)
        (xy -18.575 4.029)
        (xy -18.554 4.023)
        (xy -18.531 4.015)
        (xy -18.509 4.01)
        (xy -18.487 4.005)
        (xy -18.464 4.002)
        (xy -18.439 4.002)
        (xy -18.415 4)
        (xy -18.392 4.002)
        (xy -18.368 4.002)
        (xy -18.345 4.005)
        (xy -18.322 4.01)
        (xy -18.301 4.015)
        (xy -18.278 4.023)
        (xy -18.256 4.031)
        (xy -18.235 4.039)
        (xy -18.214 4.05)
        (xy -18.192 4.06)
        (xy -18.173 4.072)
        (xy -18.153 4.085)
        (xy -18.136 4.1)
        (xy -18.118 4.114)
        (xy -18.101 4.13)
        (xy -18.084 4.148)
        (xy -18.069 4.165)
        (xy -18.055 4.183)
        (xy -18.043 4.204)
        (xy -18.031 4.223)
        (xy -18.019 4.244)
        (xy -18.008 4.265)
        (xy -18 4.286)
        (xy -17.993 4.308)
        (xy -17.985 4.33)
        (xy -17.981 4.353)
        (xy -17.976 4.375)
        (xy -17.973 4.398)
        (xy -17.971 4.422)
        (xy -17.97 4.446)
        (xy -17.971 4.468)
        (xy -17.973 4.492)
        (xy -17.976 4.515)
        (xy -17.981 4.539)
        (xy -17.985 4.56)
        (xy -17.993 4.584)
        (xy -18 4.604)
        (xy -18.008 4.627)
        (xy -18.019 4.648)
        (xy -18.031 4.669)
        (xy -18.043 4.688)
        (xy -18.055 4.707)
        (xy -18.069 4.725)
        (xy -18.084 4.744)
        (xy -18.101 4.76)
        (xy -18.118 4.776)
        (xy -18.136 4.792)
        (xy -18.153 4.805)
        (xy -18.173 4.818)
        (xy -18.192 4.83)
        (xy -18.214 4.842)
        (xy -18.235 4.853)
        (xy -18.256 4.861)
        (xy -18.278 4.869)
        (xy -18.301 4.875)
        (xy -18.322 4.88)
        (xy -18.345 4.885)
        (xy -18.368 4.888)
        (xy -18.392 4.89)
        (xy -18.415 4.89)
        (xy -18.439 4.89)
        (xy -18.464 4.888)
        (xy -18.487 4.885)
        (xy -18.509 4.88)
        (xy -18.531 4.875)
        (xy -18.554 4.869)
        (xy -18.575 4.861)
        (xy -18.598 4.853)
        (xy -18.618 4.842)
        (xy -18.639 4.832)
        (xy -18.659 4.818)
        (xy -18.677 4.805)
        (xy -18.697 4.792)
        (xy -18.714 4.776)
        (xy -18.731 4.76)
        (xy -18.746 4.744)
        (xy -18.761 4.726)
        (xy -18.775 4.707)
        (xy -18.788 4.688)
        (xy -18.801 4.669)
        (xy -18.813 4.648)
        (xy -18.822 4.627)
        (xy -18.831 4.606)
        (xy -18.839 4.584)
        (xy -18.845 4.561)
        (xy -18.851 4.539)
        (xy -18.856 4.516)
        (xy -18.859 4.494)
        (xy -18.86 4.47)
        (xy -18.86 4.447)
        (xy -18.415 4.447)
        (xy -18.415 4.443)
      )

      (stroke (width 0.001) (type solid)) (fill solid) (layer "B.Paste"))
    (fp_poly
      (pts
        (xy -18.415 5.713)
        (xy -18.86 5.713)
        (xy -18.86 5.691)
        (xy -18.859 5.667)
        (xy -18.856 5.645)
        (xy -18.851 5.622)
        (xy -18.845 5.6)
        (xy -18.839 5.577)
        (xy -18.831 5.555)
        (xy -18.822 5.534)
        (xy -18.813 5.512)
        (xy -18.801 5.492)
        (xy -18.788 5.473)
        (xy -18.775 5.454)
        (xy -18.761 5.435)
        (xy -18.746 5.417)
        (xy -18.731 5.401)
        (xy -18.714 5.385)
        (xy -18.697 5.369)
        (xy -18.677 5.356)
        (xy -18.659 5.342)
        (xy -18.639 5.329)
        (xy -18.618 5.318)
        (xy -18.598 5.308)
        (xy -18.575 5.3)
        (xy -18.554 5.292)
        (xy -18.531 5.286)
        (xy -18.509 5.281)
        (xy -18.487 5.276)
        (xy -18.464 5.273)
        (xy -18.439 5.271)
        (xy -18.415 5.27)
        (xy -18.392 5.271)
        (xy -18.368 5.273)
        (xy -18.345 5.276)
        (xy -18.322 5.281)
        (xy -18.301 5.286)
        (xy -18.278 5.292)
        (xy -18.256 5.3)
        (xy -18.235 5.308)
        (xy -18.214 5.319)
        (xy -18.192 5.33)
        (xy -18.173 5.342)
        (xy -18.153 5.356)
        (xy -18.136 5.369)
        (xy -18.118 5.385)
        (xy -18.101 5.401)
        (xy -18.084 5.417)
        (xy -18.069 5.435)
        (xy -18.055 5.454)
        (xy -18.043 5.473)
        (xy -18.031 5.492)
        (xy -18.019 5.513)
        (xy -18.008 5.534)
        (xy -18 5.556)
        (xy -17.993 5.577)
        (xy -17.985 5.6)
        (xy -17.981 5.622)
        (xy -17.976 5.645)
        (xy -17.973 5.669)
        (xy -17.971 5.693)
        (xy -17.97 5.715)
        (xy -17.971 5.739)
        (xy -17.973 5.762)
        (xy -17.976 5.786)
        (xy -17.981 5.808)
        (xy -17.985 5.83)
        (xy -17.993 5.853)
        (xy -18 5.874)
        (xy -18.008 5.896)
        (xy -18.019 5.917)
        (xy -18.031 5.938)
        (xy -18.043 5.957)
        (xy -18.055 5.978)
        (xy -18.069 5.995)
        (xy -18.084 6.013)
        (xy -18.101 6.031)
        (xy -18.118 6.047)
        (xy -18.136 6.061)
        (xy -18.153 6.076)
        (xy -18.173 6.088)
        (xy -18.192 6.1)
        (xy -18.214 6.111)
        (xy -18.235 6.122)
        (xy -18.256 6.13)
        (xy -18.278 6.138)
        (xy -18.301 6.145)
        (xy -18.322 6.151)
        (xy -18.345 6.156)
        (xy -18.368 6.159)
        (xy -18.392 6.159)
        (xy -18.415 6.161)
        (xy -18.439 6.159)
        (xy -18.464 6.159)
        (xy -18.487 6.156)
        (xy -18.509 6.151)
        (xy -18.531 6.145)
        (xy -18.554 6.138)
        (xy -18.575 6.132)
        (xy -18.598 6.122)
        (xy -18.618 6.112)
        (xy -18.639 6.101)
        (xy -18.659 6.088)
        (xy -18.677 6.076)
        (xy -18.697 6.061)
        (xy -18.714 6.047)
        (xy -18.731 6.031)
        (xy -18.746 6.013)
        (xy -18.761 5.997)
        (xy -18.775 5.978)
        (xy -18.788 5.959)
        (xy -18.801 5.938)
        (xy -18.813 5.919)
        (xy -18.822 5.898)
        (xy -18.831 5.875)
        (xy -18.839 5.853)
        (xy -18.845 5.832)
        (xy -18.851 5.81)
        (xy -18.856 5.786)
        (xy -18.859 5.763)
        (xy -18.86 5.739)
        (xy -18.86 5.718)
        (xy -18.415 5.718)
        (xy -18.415 5.713)
      )

      (stroke (width 0.001) (type solid)) (fill solid) (layer "B.Paste"))
    (fp_poly
      (pts
        (xy -17.145 -5.717)
        (xy -17.59 -5.717)
        (xy -17.589 -5.738)
        (xy -17.589 -5.762)
        (xy -17.586 -5.785)
        (xy -17.58 -5.809)
        (xy -17.575 -5.831)
        (xy -17.569 -5.852)
        (xy -17.561 -5.874)
        (xy -17.552 -5.897)
        (xy -17.543 -5.918)
        (xy -17.531 -5.937)
        (xy -17.519 -5.958)
        (xy -17.505 -5.977)
        (xy -17.491 -5.996)
        (xy -17.476 -6.012)
        (xy -17.461 -6.03)
        (xy -17.444 -6.046)
        (xy -17.426 -6.06)
        (xy -17.407 -6.075)
        (xy -17.389 -6.087)
        (xy -17.368 -6.1)
        (xy -17.348 -6.111)
        (xy -17.328 -6.121)
        (xy -17.305 -6.131)
        (xy -17.284 -6.137)
        (xy -17.261 -6.144)
        (xy -17.24 -6.15)
        (xy -17.217 -6.155)
        (xy -17.194 -6.158)
        (xy -17.17 -6.158)
        (xy -17.145 -6.16)
        (xy -17.122 -6.158)
        (xy -17.098 -6.158)
        (xy -17.075 -6.155)
        (xy -17.052 -6.15)
        (xy -17.031 -6.144)
        (xy -17.008 -6.137)
        (xy -16.987 -6.129)
        (xy -16.964 -6.121)
        (xy -16.944 -6.11)
        (xy -16.923 -6.099)
        (xy -16.903 -6.087)
        (xy -16.883 -6.075)
        (xy -16.865 -6.06)
        (xy -16.848 -6.046)
        (xy -16.83 -6.03)
        (xy -16.814 -6.012)
        (xy -16.799 -5.994)
        (xy -16.785 -5.977)
        (xy -16.772 -5.956)
        (xy -16.761 -5.937)
        (xy -16.749 -5.916)
        (xy -16.738 -5.895)
        (xy -16.731 -5.873)
        (xy -16.723 -5.852)
        (xy -16.715 -5.829)
        (xy -16.711 -5.807)
        (xy -16.705 -5.785)
        (xy -16.703 -5.761)
        (xy -16.702 -5.738)
        (xy -16.7 -5.714)
        (xy -16.702 -5.692)
        (xy -16.703 -5.668)
        (xy -16.705 -5.644)
        (xy -16.711 -5.621)
        (xy -16.715 -5.599)
        (xy -16.723 -5.576)
        (xy -16.731 -5.555)
        (xy -16.738 -5.533)
        (xy -16.749 -5.512)
        (xy -16.761 -5.491)
        (xy -16.772 -5.472)
        (xy -16.785 -5.453)
        (xy -16.799 -5.434)
        (xy -16.814 -5.416)
        (xy -16.83 -5.4)
        (xy -16.848 -5.384)
        (xy -16.865 -5.368)
        (xy -16.883 -5.355)
        (xy -16.903 -5.341)
        (xy -16.923 -5.329)
        (xy -16.944 -5.318)
        (xy -16.964 -5.307)
        (xy -16.987 -5.299)
        (xy -17.008 -5.291)
        (xy -17.031 -5.285)
        (xy -17.052 -5.28)
        (xy -17.075 -5.275)
        (xy -17.098 -5.272)
        (xy -17.122 -5.27)
        (xy -17.145 -5.269)
        (xy -17.17 -5.27)
        (xy -17.194 -5.272)
        (xy -17.217 -5.275)
        (xy -17.24 -5.28)
        (xy -17.261 -5.285)
        (xy -17.284 -5.291)
        (xy -17.305 -5.299)
        (xy -17.328 -5.307)
        (xy -17.348 -5.317)
        (xy -17.368 -5.328)
        (xy -17.389 -5.341)
        (xy -17.407 -5.355)
        (xy -17.426 -5.368)
        (xy -17.444 -5.384)
        (xy -17.461 -5.4)
        (xy -17.476 -5.416)
        (xy -17.491 -5.434)
        (xy -17.505 -5.453)
        (xy -17.519 -5.472)
        (xy -17.531 -5.491)
        (xy -17.543 -5.511)
        (xy -17.552 -5.533)
        (xy -17.561 -5.554)
        (xy -17.569 -5.576)
        (xy -17.575 -5.599)
        (xy -17.58 -5.621)
        (xy -17.586 -5.644)
        (xy -17.589 -5.666)
        (xy -17.589 -5.69)
        (xy -17.59 -5.712)
        (xy -17.145 -5.712)
        (xy -17.145 -5.717)
      )

      (stroke (width 0.001) (type solid)) (fill solid) (layer "B.Paste"))
    (fp_poly
      (pts
        (xy -17.145 -3.177)
        (xy -17.59 -3.177)
        (xy -17.589 -3.198)
        (xy -17.589 -3.222)
        (xy -17.586 -3.245)
        (xy -17.58 -3.269)
        (xy -17.575 -3.29)
        (xy -17.569 -3.313)
        (xy -17.561 -3.334)
        (xy -17.552 -3.357)
        (xy -17.543 -3.378)
        (xy -17.531 -3.398)
        (xy -17.519 -3.418)
        (xy -17.505 -3.436)
        (xy -17.491 -3.455)
        (xy -17.476 -3.472)
        (xy -17.461 -3.49)
        (xy -17.444 -3.505)
        (xy -17.426 -3.52)
        (xy -17.407 -3.535)
        (xy -17.389 -3.547)
        (xy -17.368 -3.56)
        (xy -17.348 -3.571)
        (xy -17.328 -3.581)
        (xy -17.305 -3.591)
        (xy -17.284 -3.597)
        (xy -17.261 -3.604)
        (xy -17.24 -3.609)
        (xy -17.217 -3.615)
        (xy -17.194 -3.617)
        (xy -17.17 -3.619)
        (xy -17.145 -3.62)
        (xy -17.122 -3.619)
        (xy -17.098 -3.617)
        (xy -17.075 -3.615)
        (xy -17.052 -3.609)
        (xy -17.031 -3.604)
        (xy -17.008 -3.597)
        (xy -16.987 -3.589)
        (xy -16.964 -3.581)
        (xy -16.944 -3.571)
        (xy -16.923 -3.559)
        (xy -16.903 -3.547)
        (xy -16.883 -3.535)
        (xy -16.865 -3.52)
        (xy -16.848 -3.505)
        (xy -16.83 -3.49)
        (xy -16.814 -3.472)
        (xy -16.799 -3.454)
        (xy -16.785 -3.436)
        (xy -16.772 -3.416)
        (xy -16.761 -3.396)
        (xy -16.749 -3.376)
        (xy -16.738 -3.355)
        (xy -16.731 -3.334)
        (xy -16.723 -3.313)
        (xy -16.715 -3.289)
        (xy -16.711 -3.267)
        (xy -16.705 -3.245)
        (xy -16.703 -3.221)
        (xy -16.702 -3.197)
        (xy -16.7 -3.174)
        (xy -16.702 -3.152)
        (xy -16.703 -3.128)
        (xy -16.705 -3.104)
        (xy -16.711 -3.081)
        (xy -16.715 -3.059)
        (xy -16.723 -3.036)
        (xy -16.731 -3.015)
        (xy -16.738 -2.994)
        (xy -16.749 -2.972)
        (xy -16.761 -2.951)
        (xy -16.772 -2.932)
        (xy -16.785 -2.912)
        (xy -16.799 -2.894)
        (xy -16.814 -2.876)
        (xy -16.83 -2.859)
        (xy -16.848 -2.843)
        (xy -16.865 -2.829)
        (xy -16.883 -2.814)
        (xy -16.903 -2.801)
        (xy -16.923 -2.789)
        (xy -16.944 -2.778)
        (xy -16.964 -2.767)
        (xy -16.987 -2.759)
        (xy -17.008 -2.751)
        (xy -17.031 -2.745)
        (xy -17.052 -2.74)
        (xy -17.075 -2.734)
        (xy -17.098 -2.732)
        (xy -17.122 -2.73)
        (xy -17.145 -2.729)
        (xy -17.17 -2.73)
        (xy -17.194 -2.732)
        (xy -17.217 -2.734)
        (xy -17.24 -2.74)
        (xy -17.261 -2.745)
        (xy -17.284 -2.751)
        (xy -17.305 -2.758)
        (xy -17.328 -2.767)
        (xy -17.348 -2.777)
        (xy -17.368 -2.789)
        (xy -17.389 -2.801)
        (xy -17.407 -2.814)
        (xy -17.426 -2.829)
        (xy -17.444 -2.843)
        (xy -17.461 -2.859)
        (xy -17.476 -2.876)
        (xy -17.491 -2.894)
        (xy -17.505 -2.912)
        (xy -17.519 -2.931)
        (xy -17.531 -2.951)
        (xy -17.543 -2.971)
        (xy -17.552 -2.992)
        (xy -17.561 -3.015)
        (xy -17.569 -3.036)
        (xy -17.575 -3.059)
        (xy -17.58 -3.08)
        (xy -17.586 -3.104)
        (xy -17.589 -3.126)
        (xy -17.589 -3.15)
        (xy -17.59 -3.172)
        (xy -17.145 -3.172)
        (xy -17.145 -3.177)
      )

      (stroke (width 0.001) (type solid)) (fill solid) (layer "B.Paste"))
    (fp_poly
      (pts
        (xy -17.145 1.903)
        (xy -17.59 1.903)
        (xy -17.589 1.881)
        (xy -17.589 1.857)
        (xy -17.586 1.835)
        (xy -17.58 1.811)
        (xy -17.575 1.789)
        (xy -17.569 1.767)
        (xy -17.561 1.746)
        (xy -17.552 1.724)
        (xy -17.543 1.702)
        (xy -17.531 1.682)
        (xy -17.519 1.662)
        (xy -17.505 1.643)
        (xy -17.491 1.625)
        (xy -17.476 1.607)
        (xy -17.461 1.591)
        (xy -17.444 1.575)
        (xy -17.426 1.559)
        (xy -17.407 1.545)
        (xy -17.389 1.532)
        (xy -17.368 1.519)
        (xy -17.348 1.508)
        (xy -17.328 1.498)
        (xy -17.305 1.49)
        (xy -17.284 1.482)
        (xy -17.261 1.476)
        (xy -17.24 1.47)
        (xy -17.217 1.466)
        (xy -17.194 1.462)
        (xy -17.17 1.462)
        (xy -17.145 1.46)
        (xy -17.122 1.462)
        (xy -17.098 1.462)
        (xy -17.075 1.466)
        (xy -17.052 1.47)
        (xy -17.031 1.476)
        (xy -17.008 1.482)
        (xy -16.987 1.49)
        (xy -16.964 1.498)
        (xy -16.944 1.509)
        (xy -16.923 1.52)
        (xy -16.903 1.532)
        (xy -16.883 1.545)
        (xy -16.865 1.559)
        (xy -16.848 1.575)
        (xy -16.83 1.591)
        (xy -16.814 1.607)
        (xy -16.799 1.625)
        (xy -16.785 1.643)
        (xy -16.772 1.663)
        (xy -16.761 1.684)
        (xy -16.749 1.704)
        (xy -16.738 1.724)
        (xy -16.731 1.746)
        (xy -16.723 1.767)
        (xy -16.715 1.79)
        (xy -16.711 1.813)
        (xy -16.705 1.835)
        (xy -16.703 1.859)
        (xy -16.702 1.882)
        (xy -16.7 1.905)
        (xy -16.702 1.928)
        (xy -16.703 1.952)
        (xy -16.705 1.976)
        (xy -16.711 1.998)
        (xy -16.715 2.02)
        (xy -16.723 2.044)
        (xy -16.731 2.065)
        (xy -16.738 2.086)
        (xy -16.749 2.108)
        (xy -16.761 2.127)
        (xy -16.772 2.147)
        (xy -16.785 2.167)
        (xy -16.799 2.186)
        (xy -16.814 2.203)
        (xy -16.83 2.221)
        (xy -16.848 2.237)
        (xy -16.865 2.251)
        (xy -16.883 2.266)
        (xy -16.903 2.278)
        (xy -16.923 2.29)
        (xy -16.944 2.302)
        (xy -16.964 2.312)
        (xy -16.987 2.32)
        (xy -17.008 2.328)
        (xy -17.031 2.335)
        (xy -17.052 2.34)
        (xy -17.075 2.346)
        (xy -17.098 2.348)
        (xy -17.122 2.35)
        (xy -17.145 2.351)
        (xy -17.17 2.35)
        (xy -17.194 2.348)
        (xy -17.217 2.346)
        (xy -17.24 2.34)
        (xy -17.261 2.335)
        (xy -17.284 2.328)
        (xy -17.305 2.322)
        (xy -17.328 2.312)
        (xy -17.348 2.302)
        (xy -17.368 2.291)
        (xy -17.389 2.278)
        (xy -17.407 2.266)
        (xy -17.426 2.251)
        (xy -17.444 2.237)
        (xy -17.461 2.221)
        (xy -17.476 2.203)
        (xy -17.491 2.186)
        (xy -17.505 2.167)
        (xy -17.519 2.149)
        (xy -17.531 2.129)
        (xy -17.543 2.109)
        (xy -17.552 2.088)
        (xy -17.561 2.065)
        (xy -17.569 2.044)
        (xy -17.575 2.021)
        (xy -17.58 2)
        (xy -17.586 1.976)
        (xy -17.589 1.954)
        (xy -17.589 1.93)
        (xy -17.59 1.907)
        (xy -17.145 1.907)
        (xy -17.145 1.903)
      )

      (stroke (width 0.001) (type solid)) (fill solid) (layer "B.Paste"))
    (fp_poly
      (pts
        (xy -17.145 3.173)
        (xy -17.59 3.173)
        (xy -17.589 3.151)
        (xy -17.589 3.127)
        (xy -17.586 3.105)
        (xy -17.58 3.081)
        (xy -17.575 3.06)
        (xy -17.569 3.037)
        (xy -17.561 3.016)
        (xy -17.552 2.993)
        (xy -17.543 2.972)
        (xy -17.531 2.952)
        (xy -17.519 2.932)
        (xy -17.505 2.913)
        (xy -17.491 2.895)
        (xy -17.476 2.877)
        (xy -17.461 2.86)
        (xy -17.444 2.844)
        (xy -17.426 2.83)
        (xy -17.407 2.815)
        (xy -17.389 2.802)
        (xy -17.368 2.79)
        (xy -17.348 2.778)
        (xy -17.328 2.768)
        (xy -17.305 2.759)
        (xy -17.284 2.752)
        (xy -17.261 2.746)
        (xy -17.24 2.741)
        (xy -17.217 2.735)
        (xy -17.194 2.733)
        (xy -17.17 2.731)
        (xy -17.145 2.73)
        (xy -17.122 2.731)
        (xy -17.098 2.733)
        (xy -17.075 2.735)
        (xy -17.052 2.741)
        (xy -17.031 2.746)
        (xy -17.008 2.752)
        (xy -16.987 2.76)
        (xy -16.964 2.768)
        (xy -16.944 2.779)
        (xy -16.923 2.79)
        (xy -16.903 2.802)
        (xy -16.883 2.815)
        (xy -16.865 2.83)
        (xy -16.848 2.844)
        (xy -16.83 2.86)
        (xy -16.814 2.877)
        (xy -16.799 2.895)
        (xy -16.785 2.913)
        (xy -16.772 2.933)
        (xy -16.761 2.952)
        (xy -16.749 2.973)
        (xy -16.738 2.995)
        (xy -16.731 3.016)
        (xy -16.723 3.037)
        (xy -16.715 3.06)
        (xy -16.711 3.082)
        (xy -16.705 3.105)
        (xy -16.703 3.129)
        (xy -16.702 3.153)
        (xy -16.7 3.175)
        (xy -16.702 3.198)
        (xy -16.703 3.222)
        (xy -16.705 3.246)
        (xy -16.711 3.268)
        (xy -16.715 3.29)
        (xy -16.723 3.314)
        (xy -16.731 3.335)
        (xy -16.738 3.356)
        (xy -16.749 3.377)
        (xy -16.761 3.397)
        (xy -16.772 3.417)
        (xy -16.785 3.437)
        (xy -16.799 3.455)
        (xy -16.814 3.473)
        (xy -16.83 3.491)
        (xy -16.848 3.506)
        (xy -16.865 3.521)
        (xy -16.883 3.536)
        (xy -16.903 3.548)
        (xy -16.923 3.56)
        (xy -16.944 3.572)
        (xy -16.964 3.582)
        (xy -16.987 3.59)
        (xy -17.008 3.598)
        (xy -17.031 3.605)
        (xy -17.052 3.61)
        (xy -17.075 3.616)
        (xy -17.098 3.618)
        (xy -17.122 3.62)
        (xy -17.145 3.621)
        (xy -17.17 3.62)
        (xy -17.194 3.618)
        (xy -17.217 3.616)
        (xy -17.24 3.61)
        (xy -17.261 3.605)
        (xy -17.284 3.598)
        (xy -17.305 3.592)
        (xy -17.328 3.582)
        (xy -17.348 3.572)
        (xy -17.368 3.561)
        (xy -17.389 3.548)
        (xy -17.407 3.536)
        (xy -17.426 3.521)
        (xy -17.444 3.506)
        (xy -17.461 3.491)
        (xy -17.476 3.473)
        (xy -17.491 3.456)
        (xy -17.505 3.437)
        (xy -17.519 3.419)
        (xy -17.531 3.399)
        (xy -17.543 3.379)
        (xy -17.552 3.358)
        (xy -17.561 3.335)
        (xy -17.569 3.314)
        (xy -17.575 3.291)
        (xy -17.58 3.27)
        (xy -17.586 3.246)
        (xy -17.589 3.223)
        (xy -17.589 3.199)
        (xy -17.59 3.178)
        (xy -17.145 3.178)
        (xy -17.145 3.173)
      )

      (stroke (width 0.001) (type solid)) (fill solid) (layer "B.Paste"))
    (fp_poly
      (pts
        (xy -17.145 4.443)
        (xy -17.59 4.443)
        (xy -17.589 4.422)
        (xy -17.589 4.398)
        (xy -17.586 4.374)
        (xy -17.58 4.351)
        (xy -17.575 4.329)
        (xy -17.569 4.308)
        (xy -17.561 4.286)
        (xy -17.552 4.263)
        (xy -17.543 4.242)
        (xy -17.531 4.223)
        (xy -17.519 4.202)
        (xy -17.505 4.183)
        (xy -17.491 4.164)
        (xy -17.476 4.148)
        (xy -17.461 4.13)
        (xy -17.444 4.114)
        (xy -17.426 4.1)
        (xy -17.407 4.085)
        (xy -17.389 4.072)
        (xy -17.368 4.06)
        (xy -17.348 4.048)
        (xy -17.328 4.039)
        (xy -17.305 4.029)
        (xy -17.284 4.023)
        (xy -17.261 4.015)
        (xy -17.24 4.01)
        (xy -17.217 4.005)
        (xy -17.194 4.002)
        (xy -17.17 4.002)
        (xy -17.145 4)
        (xy -17.122 4.002)
        (xy -17.098 4.002)
        (xy -17.075 4.005)
        (xy -17.052 4.01)
        (xy -17.031 4.015)
        (xy -17.008 4.023)
        (xy -16.987 4.031)
        (xy -16.964 4.039)
        (xy -16.944 4.05)
        (xy -16.923 4.06)
        (xy -16.903 4.072)
        (xy -16.883 4.085)
        (xy -16.865 4.1)
        (xy -16.848 4.114)
        (xy -16.83 4.13)
        (xy -16.814 4.148)
        (xy -16.799 4.165)
        (xy -16.785 4.183)
        (xy -16.772 4.204)
        (xy -16.761 4.223)
        (xy -16.749 4.244)
        (xy -16.738 4.265)
        (xy -16.731 4.286)
        (xy -16.723 4.308)
        (xy -16.715 4.33)
        (xy -16.711 4.353)
        (xy -16.705 4.375)
        (xy -16.703 4.398)
        (xy -16.702 4.422)
        (xy -16.7 4.446)
        (xy -16.702 4.468)
        (xy -16.703 4.492)
        (xy -16.705 4.515)
        (xy -16.711 4.539)
        (xy -16.715 4.56)
        (xy -16.723 4.584)
        (xy -16.731 4.604)
        (xy -16.738 4.627)
        (xy -16.749 4.648)
        (xy -16.761 4.669)
        (xy -16.772 4.688)
        (xy -16.785 4.707)
        (xy -16.799 4.725)
        (xy -16.814 4.744)
        (xy -16.83 4.76)
        (xy -16.848 4.776)
        (xy -16.865 4.792)
        (xy -16.883 4.805)
        (xy -16.903 4.818)
        (xy -16.923 4.83)
        (xy -16.944 4.842)
        (xy -16.964 4.853)
        (xy -16.987 4.861)
        (xy -17.008 4.869)
        (xy -17.031 4.875)
        (xy -17.052 4.88)
        (xy -17.075 4.885)
        (xy -17.098 4.888)
        (xy -17.122 4.89)
        (xy -17.145 4.89)
        (xy -17.17 4.89)
        (xy -17.194 4.888)
        (xy -17.217 4.885)
        (xy -17.24 4.88)
        (xy -17.261 4.875)
        (xy -17.284 4.869)
        (xy -17.305 4.861)
        (xy -17.328 4.853)
        (xy -17.348 4.842)
        (xy -17.368 4.832)
        (xy -17.389 4.818)
        (xy -17.407 4.805)
        (xy -17.426 4.792)
        (xy -17.444 4.776)
        (xy -17.461 4.76)
        (xy -17.476 4.744)
        (xy -17.491 4.726)
        (xy -17.505 4.707)
        (xy -17.519 4.688)
        (xy -17.531 4.669)
        (xy -17.543 4.648)
        (xy -17.552 4.627)
        (xy -17.561 4.606)
        (xy -17.569 4.584)
        (xy -17.575 4.561)
        (xy -17.58 4.539)
        (xy -17.586 4.516)
        (xy -17.589 4.494)
        (xy -17.589 4.47)
        (xy -17.59 4.447)
        (xy -17.145 4.447)
        (xy -17.145 4.443)
      )

      (stroke (width 0.001) (type solid)) (fill solid) (layer "B.Paste"))
    (fp_poly
      (pts
        (xy -17.145 5.713)
        (xy -17.59 5.713)
        (xy -17.589 5.691)
        (xy -17.589 5.667)
        (xy -17.586 5.645)
        (xy -17.58 5.622)
        (xy -17.575 5.6)
        (xy -17.569 5.577)
        (xy -17.561 5.555)
        (xy -17.552 5.534)
        (xy -17.543 5.512)
        (xy -17.531 5.492)
        (xy -17.519 5.473)
        (xy -17.505 5.454)
        (xy -17.491 5.435)
        (xy -17.476 5.417)
        (xy -17.461 5.401)
        (xy -17.444 5.385)
        (xy -17.426 5.369)
        (xy -17.407 5.356)
        (xy -17.389 5.342)
        (xy -17.368 5.329)
        (xy -17.348 5.318)
        (xy -17.328 5.308)
        (xy -17.305 5.3)
        (xy -17.284 5.292)
        (xy -17.261 5.286)
        (xy -17.24 5.281)
        (xy -17.217 5.276)
        (xy -17.194 5.273)
        (xy -17.17 5.271)
        (xy -17.145 5.27)
        (xy -17.122 5.271)
        (xy -17.098 5.273)
        (xy -17.075 5.276)
        (xy -17.052 5.281)
        (xy -17.031 5.286)
        (xy -17.008 5.292)
        (xy -16.987 5.3)
        (xy -16.964 5.308)
        (xy -16.944 5.319)
        (xy -16.923 5.33)
        (xy -16.903 5.342)
        (xy -16.883 5.356)
        (xy -16.865 5.369)
        (xy -16.848 5.385)
        (xy -16.83 5.401)
        (xy -16.814 5.417)
        (xy -16.799 5.435)
        (xy -16.785 5.454)
        (xy -16.772 5.473)
        (xy -16.761 5.492)
        (xy -16.749 5.513)
        (xy -16.738 5.534)
        (xy -16.731 5.556)
        (xy -16.723 5.577)
        (xy -16.715 5.6)
        (xy -16.711 5.622)
        (xy -16.705 5.645)
        (xy -16.703 5.669)
        (xy -16.702 5.693)
        (xy -16.7 5.715)
        (xy -16.702 5.739)
        (xy -16.703 5.762)
        (xy -16.705 5.786)
        (xy -16.711 5.808)
        (xy -16.715 5.83)
        (xy -16.723 5.853)
        (xy -16.731 5.874)
        (xy -16.738 5.896)
        (xy -16.749 5.917)
        (xy -16.761 5.938)
        (xy -16.772 5.957)
        (xy -16.785 5.978)
        (xy -16.799 5.995)
        (xy -16.814 6.013)
        (xy -16.83 6.031)
        (xy -16.848 6.047)
        (xy -16.865 6.061)
        (xy -16.883 6.076)
        (xy -16.903 6.088)
        (xy -16.923 6.1)
        (xy -16.944 6.111)
        (xy -16.964 6.122)
        (xy -16.987 6.13)
        (xy -17.008 6.138)
        (xy -17.031 6.145)
        (xy -17.052 6.151)
        (xy -17.075 6.156)
        (xy -17.098 6.159)
        (xy -17.122 6.159)
        (xy -17.145 6.161)
        (xy -17.17 6.159)
        (xy -17.194 6.159)
        (xy -17.217 6.156)
        (xy -17.24 6.151)
        (xy -17.261 6.145)
        (xy -17.284 6.138)
        (xy -17.305 6.132)
        (xy -17.328 6.122)
        (xy -17.348 6.112)
        (xy -17.368 6.101)
        (xy -17.389 6.088)
        (xy -17.407 6.076)
        (xy -17.426 6.061)
        (xy -17.444 6.047)
        (xy -17.461 6.031)
        (xy -17.476 6.013)
        (xy -17.491 5.997)
        (xy -17.505 5.978)
        (xy -17.519 5.959)
        (xy -17.531 5.938)
        (xy -17.543 5.919)
        (xy -17.552 5.898)
        (xy -17.561 5.875)
        (xy -17.569 5.853)
        (xy -17.575 5.832)
        (xy -17.58 5.81)
        (xy -17.586 5.786)
        (xy -17.589 5.763)
        (xy -17.589 5.739)
        (xy -17.59 5.718)
        (xy -17.145 5.718)
        (xy -17.145 5.713)
      )

      (stroke (width 0.001) (type solid)) (fill solid) (layer "B.Paste"))
    (fp_poly
      (pts
        (xy -15.875 -5.717)
        (xy -16.32 -5.717)
        (xy -16.319 -5.738)
        (xy -16.319 -5.762)
        (xy -16.316 -5.785)
        (xy -16.31 -5.809)
        (xy -16.305 -5.831)
        (xy -16.298 -5.852)
        (xy -16.292 -5.874)
        (xy -16.282 -5.897)
        (xy -16.272 -5.918)
        (xy -16.261 -5.937)
        (xy -16.249 -5.958)
        (xy -16.235 -5.977)
        (xy -16.221 -5.996)
        (xy -16.206 -6.012)
        (xy -16.191 -6.03)
        (xy -16.173 -6.046)
        (xy -16.156 -6.06)
        (xy -16.138 -6.075)
        (xy -16.118 -6.087)
        (xy -16.098 -6.1)
        (xy -16.078 -6.111)
        (xy -16.057 -6.121)
        (xy -16.035 -6.131)
        (xy -16.014 -6.137)
        (xy -15.991 -6.144)
        (xy -15.969 -6.15)
        (xy -15.946 -6.155)
        (xy -15.923 -6.158)
        (xy -15.899 -6.158)
        (xy -15.875 -6.16)
        (xy -15.852 -6.158)
        (xy -15.828 -6.158)
        (xy -15.805 -6.155)
        (xy -15.782 -6.15)
        (xy -15.76 -6.144)
        (xy -15.737 -6.137)
        (xy -15.716 -6.129)
        (xy -15.695 -6.121)
        (xy -15.673 -6.11)
        (xy -15.652 -6.099)
        (xy -15.633 -6.087)
        (xy -15.613 -6.075)
        (xy -15.596 -6.06)
        (xy -15.577 -6.046)
        (xy -15.561 -6.03)
        (xy -15.545 -6.012)
        (xy -15.529 -5.994)
        (xy -15.516 -5.977)
        (xy -15.503 -5.956)
        (xy -15.49 -5.937)
        (xy -15.479 -5.916)
        (xy -15.468 -5.895)
        (xy -15.461 -5.873)
        (xy -15.452 -5.852)
        (xy -15.445 -5.829)
        (xy -15.44 -5.807)
        (xy -15.436 -5.785)
        (xy -15.433 -5.761)
        (xy -15.431 -5.738)
        (xy -15.43 -5.714)
        (xy -15.431 -5.692)
        (xy -15.433 -5.668)
        (xy -15.436 -5.644)
        (xy -15.44 -5.621)
        (xy -15.445 -5.599)
        (xy -15.452 -5.576)
        (xy -15.461 -5.555)
        (xy -15.468 -5.533)
        (xy -15.479 -5.512)
        (xy -15.49 -5.491)
        (xy -15.503 -5.472)
        (xy -15.516 -5.453)
        (xy -15.529 -5.434)
        (xy -15.545 -5.416)
        (xy -15.561 -5.4)
        (xy -15.577 -5.384)
        (xy -15.596 -5.368)
        (xy -15.613 -5.355)
        (xy -15.633 -5.341)
        (xy -15.652 -5.329)
        (xy -15.673 -5.318)
        (xy -15.695 -5.307)
        (xy -15.716 -5.299)
        (xy -15.737 -5.291)
        (xy -15.76 -5.285)
        (xy -15.782 -5.28)
        (xy -15.805 -5.275)
        (xy -15.828 -5.272)
        (xy -15.852 -5.27)
        (xy -15.875 -5.269)
        (xy -15.899 -5.27)
        (xy -15.923 -5.272)
        (xy -15.946 -5.275)
        (xy -15.969 -5.28)
        (xy -15.991 -5.285)
        (xy -16.014 -5.291)
        (xy -16.035 -5.299)
        (xy -16.057 -5.307)
        (xy -16.078 -5.317)
        (xy -16.098 -5.328)
        (xy -16.118 -5.341)
        (xy -16.138 -5.355)
        (xy -16.156 -5.368)
        (xy -16.173 -5.384)
        (xy -16.191 -5.4)
        (xy -16.206 -5.416)
        (xy -16.221 -5.434)
        (xy -16.235 -5.453)
        (xy -16.249 -5.472)
        (xy -16.261 -5.491)
        (xy -16.272 -5.511)
        (xy -16.282 -5.533)
        (xy -16.292 -5.554)
        (xy -16.298 -5.576)
        (xy -16.305 -5.599)
        (xy -16.31 -5.621)
        (xy -16.316 -5.644)
        (xy -16.319 -5.666)
        (xy -16.319 -5.69)
        (xy -16.32 -5.712)
        (xy -15.875 -5.712)
        (xy -15.875 -5.717)
      )

      (stroke (width 0.001) (type solid)) (fill solid) (layer "B.Paste"))
    (fp_poly
      (pts
        (xy -15.875 -3.177)
        (xy -16.32 -3.177)
        (xy -16.319 -3.198)
        (xy -16.319 -3.222)
        (xy -16.316 -3.245)
        (xy -16.31 -3.269)
        (xy -16.305 -3.29)
        (xy -16.298 -3.313)
        (xy -16.292 -3.334)
        (xy -16.282 -3.357)
        (xy -16.272 -3.378)
        (xy -16.261 -3.398)
        (xy -16.249 -3.418)
        (xy -16.235 -3.436)
        (xy -16.221 -3.455)
        (xy -16.206 -3.472)
        (xy -16.191 -3.49)
        (xy -16.173 -3.505)
        (xy -16.156 -3.52)
        (xy -16.138 -3.535)
        (xy -16.118 -3.547)
        (xy -16.098 -3.56)
        (xy -16.078 -3.571)
        (xy -16.057 -3.581)
        (xy -16.035 -3.591)
        (xy -16.014 -3.597)
        (xy -15.991 -3.604)
        (xy -15.969 -3.609)
        (xy -15.946 -3.615)
        (xy -15.923 -3.617)
        (xy -15.899 -3.619)
        (xy -15.875 -3.62)
        (xy -15.852 -3.619)
        (xy -15.828 -3.617)
        (xy -15.805 -3.615)
        (xy -15.782 -3.609)
        (xy -15.76 -3.604)
        (xy -15.737 -3.597)
        (xy -15.716 -3.589)
        (xy -15.695 -3.581)
        (xy -15.673 -3.571)
        (xy -15.652 -3.559)
        (xy -15.633 -3.547)
        (xy -15.613 -3.535)
        (xy -15.596 -3.52)
        (xy -15.577 -3.505)
        (xy -15.561 -3.49)
        (xy -15.545 -3.472)
        (xy -15.529 -3.454)
        (xy -15.516 -3.436)
        (xy -15.503 -3.416)
        (xy -15.49 -3.396)
        (xy -15.479 -3.376)
        (xy -15.468 -3.355)
        (xy -15.461 -3.334)
        (xy -15.452 -3.313)
        (xy -15.445 -3.289)
        (xy -15.44 -3.267)
        (xy -15.436 -3.245)
        (xy -15.433 -3.221)
        (xy -15.431 -3.197)
        (xy -15.43 -3.174)
        (xy -15.431 -3.152)
        (xy -15.433 -3.128)
        (xy -15.436 -3.104)
        (xy -15.44 -3.081)
        (xy -15.445 -3.059)
        (xy -15.452 -3.036)
        (xy -15.461 -3.015)
        (xy -15.468 -2.994)
        (xy -15.479 -2.972)
        (xy -15.49 -2.951)
        (xy -15.503 -2.932)
        (xy -15.516 -2.912)
        (xy -15.529 -2.894)
        (xy -15.545 -2.876)
        (xy -15.561 -2.859)
        (xy -15.577 -2.843)
        (xy -15.596 -2.829)
        (xy -15.613 -2.814)
        (xy -15.633 -2.801)
        (xy -15.652 -2.789)
        (xy -15.673 -2.778)
        (xy -15.695 -2.767)
        (xy -15.716 -2.759)
        (xy -15.737 -2.751)
        (xy -15.76 -2.745)
        (xy -15.782 -2.74)
        (xy -15.805 -2.734)
        (xy -15.828 -2.732)
        (xy -15.852 -2.73)
        (xy -15.875 -2.729)
        (xy -15.899 -2.73)
        (xy -15.923 -2.732)
        (xy -15.946 -2.734)
        (xy -15.969 -2.74)
        (xy -15.991 -2.745)
        (xy -16.014 -2.751)
        (xy -16.035 -2.758)
        (xy -16.057 -2.767)
        (xy -16.078 -2.777)
        (xy -16.098 -2.789)
        (xy -16.118 -2.801)
        (xy -16.138 -2.814)
        (xy -16.156 -2.829)
        (xy -16.173 -2.843)
        (xy -16.191 -2.859)
        (xy -16.206 -2.876)
        (xy -16.221 -2.894)
        (xy -16.235 -2.912)
        (xy -16.249 -2.931)
        (xy -16.261 -2.951)
        (xy -16.272 -2.971)
        (xy -16.282 -2.992)
        (xy -16.292 -3.015)
        (xy -16.298 -3.036)
        (xy -16.305 -3.059)
        (xy -16.31 -3.08)
        (xy -16.316 -3.104)
        (xy -16.319 -3.126)
        (xy -16.319 -3.15)
        (xy -16.32 -3.172)
        (xy -15.875 -3.172)
        (xy -15.875 -3.177)
      )

      (stroke (width 0.001) (type solid)) (fill solid) (layer "B.Paste"))
    (fp_poly
      (pts
        (xy -15.875 1.903)
        (xy -16.32 1.903)
        (xy -16.319 1.881)
        (xy -16.319 1.857)
        (xy -16.316 1.835)
        (xy -16.31 1.811)
        (xy -16.305 1.789)
        (xy -16.298 1.767)
        (xy -16.292 1.746)
        (xy -16.282 1.724)
        (xy -16.272 1.702)
        (xy -16.261 1.682)
        (xy -16.249 1.662)
        (xy -16.235 1.643)
        (xy -16.221 1.625)
        (xy -16.206 1.607)
        (xy -16.191 1.591)
        (xy -16.173 1.575)
        (xy -16.156 1.559)
        (xy -16.138 1.545)
        (xy -16.118 1.532)
        (xy -16.098 1.519)
        (xy -16.078 1.508)
        (xy -16.057 1.498)
        (xy -16.035 1.49)
        (xy -16.014 1.482)
        (xy -15.991 1.476)
        (xy -15.969 1.47)
        (xy -15.946 1.466)
        (xy -15.923 1.462)
        (xy -15.899 1.462)
        (xy -15.875 1.46)
        (xy -15.852 1.462)
        (xy -15.828 1.462)
        (xy -15.805 1.466)
        (xy -15.782 1.47)
        (xy -15.76 1.476)
        (xy -15.737 1.482)
        (xy -15.716 1.49)
        (xy -15.695 1.498)
        (xy -15.673 1.509)
        (xy -15.652 1.52)
        (xy -15.633 1.532)
        (xy -15.613 1.545)
        (xy -15.596 1.559)
        (xy -15.577 1.575)
        (xy -15.561 1.591)
        (xy -15.545 1.607)
        (xy -15.529 1.625)
        (xy -15.516 1.643)
        (xy -15.503 1.663)
        (xy -15.49 1.684)
        (xy -15.479 1.704)
        (xy -15.468 1.724)
        (xy -15.461 1.746)
        (xy -15.452 1.767)
        (xy -15.445 1.79)
        (xy -15.44 1.813)
        (xy -15.436 1.835)
        (xy -15.433 1.859)
        (xy -15.431 1.882)
        (xy -15.43 1.905)
        (xy -15.431 1.928)
        (xy -15.433 1.952)
        (xy -15.436 1.976)
        (xy -15.44 1.998)
        (xy -15.445 2.02)
        (xy -15.452 2.044)
        (xy -15.461 2.065)
        (xy -15.468 2.086)
        (xy -15.479 2.108)
        (xy -15.49 2.127)
        (xy -15.503 2.147)
        (xy -15.516 2.167)
        (xy -15.529 2.186)
        (xy -15.545 2.203)
        (xy -15.561 2.221)
        (xy -15.577 2.237)
        (xy -15.596 2.251)
        (xy -15.613 2.266)
        (xy -15.633 2.278)
        (xy -15.652 2.29)
        (xy -15.673 2.302)
        (xy -15.695 2.312)
        (xy -15.716 2.32)
        (xy -15.737 2.328)
        (xy -15.76 2.335)
        (xy -15.782 2.34)
        (xy -15.805 2.346)
        (xy -15.828 2.348)
        (xy -15.852 2.35)
        (xy -15.875 2.351)
        (xy -15.899 2.35)
        (xy -15.923 2.348)
        (xy -15.946 2.346)
        (xy -15.969 2.34)
        (xy -15.991 2.335)
        (xy -16.014 2.328)
        (xy -16.035 2.322)
        (xy -16.057 2.312)
        (xy -16.078 2.302)
        (xy -16.098 2.291)
        (xy -16.118 2.278)
        (xy -16.138 2.266)
        (xy -16.156 2.251)
        (xy -16.173 2.237)
        (xy -16.191 2.221)
        (xy -16.206 2.203)
        (xy -16.221 2.186)
        (xy -16.235 2.167)
        (xy -16.249 2.149)
        (xy -16.261 2.129)
        (xy -16.272 2.109)
        (xy -16.282 2.088)
        (xy -16.292 2.065)
        (xy -16.298 2.044)
        (xy -16.305 2.021)
        (xy -16.31 2)
        (xy -16.316 1.976)
        (xy -16.319 1.954)
        (xy -16.319 1.93)
        (xy -16.32 1.907)
        (xy -15.875 1.907)
        (xy -15.875 1.903)
      )

      (stroke (width 0.001) (type solid)) (fill solid) (layer "B.Paste"))
    (fp_poly
      (pts
        (xy -15.875 3.173)
        (xy -16.32 3.173)
        (xy -16.319 3.151)
        (xy -16.319 3.127)
        (xy -16.316 3.105)
        (xy -16.31 3.081)
        (xy -16.305 3.06)
        (xy -16.298 3.037)
        (xy -16.292 3.016)
        (xy -16.282 2.993)
        (xy -16.272 2.972)
        (xy -16.261 2.952)
        (xy -16.249 2.932)
        (xy -16.235 2.913)
        (xy -16.221 2.895)
        (xy -16.206 2.877)
        (xy -16.191 2.86)
        (xy -16.173 2.844)
        (xy -16.156 2.83)
        (xy -16.138 2.815)
        (xy -16.118 2.802)
        (xy -16.098 2.79)
        (xy -16.078 2.778)
        (xy -16.057 2.768)
        (xy -16.035 2.759)
        (xy -16.014 2.752)
        (xy -15.991 2.746)
        (xy -15.969 2.741)
        (xy -15.946 2.735)
        (xy -15.923 2.733)
        (xy -15.899 2.731)
        (xy -15.875 2.73)
        (xy -15.852 2.731)
        (xy -15.828 2.733)
        (xy -15.805 2.735)
        (xy -15.782 2.741)
        (xy -15.76 2.746)
        (xy -15.737 2.752)
        (xy -15.716 2.76)
        (xy -15.695 2.768)
        (xy -15.673 2.779)
        (xy -15.652 2.79)
        (xy -15.633 2.802)
        (xy -15.613 2.815)
        (xy -15.596 2.83)
        (xy -15.577 2.844)
        (xy -15.561 2.86)
        (xy -15.545 2.877)
        (xy -15.529 2.895)
        (xy -15.516 2.913)
        (xy -15.503 2.933)
        (xy -15.49 2.952)
        (xy -15.479 2.973)
        (xy -15.468 2.995)
        (xy -15.461 3.016)
        (xy -15.452 3.037)
        (xy -15.445 3.06)
        (xy -15.44 3.082)
        (xy -15.436 3.105)
        (xy -15.433 3.129)
        (xy -15.431 3.153)
        (xy -15.43 3.175)
        (xy -15.431 3.198)
        (xy -15.433 3.222)
        (xy -15.436 3.246)
        (xy -15.44 3.268)
        (xy -15.445 3.29)
        (xy -15.452 3.314)
        (xy -15.461 3.335)
        (xy -15.468 3.356)
        (xy -15.479 3.377)
        (xy -15.49 3.397)
        (xy -15.503 3.417)
        (xy -15.516 3.437)
        (xy -15.529 3.455)
        (xy -15.545 3.473)
        (xy -15.561 3.491)
        (xy -15.577 3.506)
        (xy -15.596 3.521)
        (xy -15.613 3.536)
        (xy -15.633 3.548)
        (xy -15.652 3.56)
        (xy -15.673 3.572)
        (xy -15.695 3.582)
        (xy -15.716 3.59)
        (xy -15.737 3.598)
        (xy -15.76 3.605)
        (xy -15.782 3.61)
        (xy -15.805 3.616)
        (xy -15.828 3.618)
        (xy -15.852 3.62)
        (xy -15.875 3.621)
        (xy -15.899 3.62)
        (xy -15.923 3.618)
        (xy -15.946 3.616)
        (xy -15.969 3.61)
        (xy -15.991 3.605)
        (xy -16.014 3.598)
        (xy -16.035 3.592)
        (xy -16.057 3.582)
        (xy -16.078 3.572)
        (xy -16.098 3.561)
        (xy -16.118 3.548)
        (xy -16.138 3.536)
        (xy -16.156 3.521)
        (xy -16.173 3.506)
        (xy -16.191 3.491)
        (xy -16.206 3.473)
        (xy -16.221 3.456)
        (xy -16.235 3.437)
        (xy -16.249 3.419)
        (xy -16.261 3.399)
        (xy -16.272 3.379)
        (xy -16.282 3.358)
        (xy -16.292 3.335)
        (xy -16.298 3.314)
        (xy -16.305 3.291)
        (xy -16.31 3.27)
        (xy -16.316 3.246)
        (xy -16.319 3.223)
        (xy -16.319 3.199)
        (xy -16.32 3.178)
        (xy -15.875 3.178)
        (xy -15.875 3.173)
      )

      (stroke (width 0.001) (type solid)) (fill solid) (layer "B.Paste"))
    (fp_poly
      (pts
        (xy -15.875 4.443)
        (xy -16.32 4.443)
        (xy -16.319 4.422)
        (xy -16.319 4.398)
        (xy -16.316 4.374)
        (xy -16.31 4.351)
        (xy -16.305 4.329)
        (xy -16.298 4.308)
        (xy -16.292 4.286)
        (xy -16.282 4.263)
        (xy -16.272 4.242)
        (xy -16.261 4.223)
        (xy -16.249 4.202)
        (xy -16.235 4.183)
        (xy -16.221 4.164)
        (xy -16.206 4.148)
        (xy -16.191 4.13)
        (xy -16.173 4.114)
        (xy -16.156 4.1)
        (xy -16.138 4.085)
        (xy -16.118 4.072)
        (xy -16.098 4.06)
        (xy -16.078 4.048)
        (xy -16.057 4.039)
        (xy -16.035 4.029)
        (xy -16.014 4.023)
        (xy -15.991 4.015)
        (xy -15.969 4.01)
        (xy -15.946 4.005)
        (xy -15.923 4.002)
        (xy -15.899 4.002)
        (xy -15.875 4)
        (xy -15.852 4.002)
        (xy -15.828 4.002)
        (xy -15.805 4.005)
        (xy -15.782 4.01)
        (xy -15.76 4.015)
        (xy -15.737 4.023)
        (xy -15.716 4.031)
        (xy -15.695 4.039)
        (xy -15.673 4.05)
        (xy -15.652 4.06)
        (xy -15.633 4.072)
        (xy -15.613 4.085)
        (xy -15.596 4.1)
        (xy -15.577 4.114)
        (xy -15.561 4.13)
        (xy -15.545 4.148)
        (xy -15.529 4.165)
        (xy -15.516 4.183)
        (xy -15.503 4.204)
        (xy -15.49 4.223)
        (xy -15.479 4.244)
        (xy -15.468 4.265)
        (xy -15.461 4.286)
        (xy -15.452 4.308)
        (xy -15.445 4.33)
        (xy -15.44 4.353)
        (xy -15.436 4.375)
        (xy -15.433 4.398)
        (xy -15.431 4.422)
        (xy -15.43 4.446)
        (xy -15.431 4.468)
        (xy -15.433 4.492)
        (xy -15.436 4.515)
        (xy -15.44 4.539)
        (xy -15.445 4.56)
        (xy -15.452 4.584)
        (xy -15.461 4.604)
        (xy -15.468 4.627)
        (xy -15.479 4.648)
        (xy -15.49 4.669)
        (xy -15.503 4.688)
        (xy -15.516 4.707)
        (xy -15.529 4.725)
        (xy -15.545 4.744)
        (xy -15.561 4.76)
        (xy -15.577 4.776)
        (xy -15.596 4.792)
        (xy -15.613 4.805)
        (xy -15.633 4.818)
        (xy -15.652 4.83)
        (xy -15.673 4.842)
        (xy -15.695 4.853)
        (xy -15.716 4.861)
        (xy -15.737 4.869)
        (xy -15.76 4.875)
        (xy -15.782 4.88)
        (xy -15.805 4.885)
        (xy -15.828 4.888)
        (xy -15.852 4.89)
        (xy -15.875 4.89)
        (xy -15.899 4.89)
        (xy -15.923 4.888)
        (xy -15.946 4.885)
        (xy -15.969 4.88)
        (xy -15.991 4.875)
        (xy -16.014 4.869)
        (xy -16.035 4.861)
        (xy -16.057 4.853)
        (xy -16.078 4.842)
        (xy -16.098 4.832)
        (xy -16.118 4.818)
        (xy -16.138 4.805)
        (xy -16.156 4.792)
        (xy -16.173 4.776)
        (xy -16.191 4.76)
        (xy -16.206 4.744)
        (xy -16.221 4.726)
        (xy -16.235 4.707)
        (xy -16.249 4.688)
        (xy -16.261 4.669)
        (xy -16.272 4.648)
        (xy -16.282 4.627)
        (xy -16.292 4.606)
        (xy -16.298 4.584)
        (xy -16.305 4.561)
        (xy -16.31 4.539)
        (xy -16.316 4.516)
        (xy -16.319 4.494)
        (xy -16.319 4.47)
        (xy -16.32 4.447)
        (xy -15.875 4.447)
        (xy -15.875 4.443)
      )

      (stroke (width 0.001) (type solid)) (fill solid) (layer "B.Paste"))
    (fp_poly
      (pts
        (xy -15.875 5.713)
        (xy -16.32 5.713)
        (xy -16.319 5.691)
        (xy -16.319 5.667)
        (xy -16.316 5.645)
        (xy -16.31 5.622)
        (xy -16.305 5.6)
        (xy -16.298 5.577)
        (xy -16.292 5.555)
        (xy -16.282 5.534)
        (xy -16.272 5.512)
        (xy -16.261 5.492)
        (xy -16.249 5.473)
        (xy -16.235 5.454)
        (xy -16.221 5.435)
        (xy -16.206 5.417)
        (xy -16.191 5.401)
        (xy -16.173 5.385)
        (xy -16.156 5.369)
        (xy -16.138 5.356)
        (xy -16.118 5.342)
        (xy -16.098 5.329)
        (xy -16.078 5.318)
        (xy -16.057 5.308)
        (xy -16.035 5.3)
        (xy -16.014 5.292)
        (xy -15.991 5.286)
        (xy -15.969 5.281)
        (xy -15.946 5.276)
        (xy -15.923 5.273)
        (xy -15.899 5.271)
        (xy -15.875 5.27)
        (xy -15.852 5.271)
        (xy -15.828 5.273)
        (xy -15.805 5.276)
        (xy -15.782 5.281)
        (xy -15.76 5.286)
        (xy -15.737 5.292)
        (xy -15.716 5.3)
        (xy -15.695 5.308)
        (xy -15.673 5.319)
        (xy -15.652 5.33)
        (xy -15.633 5.342)
        (xy -15.613 5.356)
        (xy -15.596 5.369)
        (xy -15.577 5.385)
        (xy -15.561 5.401)
        (xy -15.545 5.417)
        (xy -15.529 5.435)
        (xy -15.516 5.454)
        (xy -15.503 5.473)
        (xy -15.49 5.492)
        (xy -15.479 5.513)
        (xy -15.468 5.534)
        (xy -15.461 5.556)
        (xy -15.452 5.577)
        (xy -15.445 5.6)
        (xy -15.44 5.622)
        (xy -15.436 5.645)
        (xy -15.433 5.669)
        (xy -15.431 5.693)
        (xy -15.43 5.715)
        (xy -15.431 5.739)
        (xy -15.433 5.762)
        (xy -15.436 5.786)
        (xy -15.44 5.808)
        (xy -15.445 5.83)
        (xy -15.452 5.853)
        (xy -15.461 5.874)
        (xy -15.468 5.896)
        (xy -15.479 5.917)
        (xy -15.49 5.938)
        (xy -15.503 5.957)
        (xy -15.516 5.978)
        (xy -15.529 5.995)
        (xy -15.545 6.013)
        (xy -15.561 6.031)
        (xy -15.577 6.047)
        (xy -15.596 6.061)
        (xy -15.613 6.076)
        (xy -15.633 6.088)
        (xy -15.652 6.1)
        (xy -15.673 6.111)
        (xy -15.695 6.122)
        (xy -15.716 6.13)
        (xy -15.737 6.138)
        (xy -15.76 6.145)
        (xy -15.782 6.151)
        (xy -15.805 6.156)
        (xy -15.828 6.159)
        (xy -15.852 6.159)
        (xy -15.875 6.161)
        (xy -15.899 6.159)
        (xy -15.923 6.159)
        (xy -15.946 6.156)
        (xy -15.969 6.151)
        (xy -15.991 6.145)
        (xy -16.014 6.138)
        (xy -16.035 6.132)
        (xy -16.057 6.122)
        (xy -16.078 6.112)
        (xy -16.098 6.101)
        (xy -16.118 6.088)
        (xy -16.138 6.076)
        (xy -16.156 6.061)
        (xy -16.173 6.047)
        (xy -16.191 6.031)
        (xy -16.206 6.013)
        (xy -16.221 5.997)
        (xy -16.235 5.978)
        (xy -16.249 5.959)
        (xy -16.261 5.938)
        (xy -16.272 5.919)
        (xy -16.282 5.898)
        (xy -16.292 5.875)
        (xy -16.298 5.853)
        (xy -16.305 5.832)
        (xy -16.31 5.81)
        (xy -16.316 5.786)
        (xy -16.319 5.763)
        (xy -16.319 5.739)
        (xy -16.32 5.718)
        (xy -15.875 5.718)
        (xy -15.875 5.713)
      )

      (stroke (width 0.001) (type solid)) (fill solid) (layer "B.Paste"))
    (fp_poly
      (pts
        (xy -14.606 -5.717)
        (xy -15.051 -5.717)
        (xy -15.049 -5.738)
        (xy -15.048 -5.762)
        (xy -15.045 -5.785)
        (xy -15.04 -5.809)
        (xy -15.035 -5.831)
        (xy -15.029 -5.852)
        (xy -15.022 -5.874)
        (xy -15.013 -5.897)
        (xy -15.003 -5.918)
        (xy -14.991 -5.937)
        (xy -14.978 -5.958)
        (xy -14.965 -5.977)
        (xy -14.952 -5.996)
        (xy -14.936 -6.012)
        (xy -14.92 -6.03)
        (xy -14.904 -6.046)
        (xy -14.886 -6.06)
        (xy -14.868 -6.075)
        (xy -14.849 -6.087)
        (xy -14.828 -6.1)
        (xy -14.808 -6.111)
        (xy -14.788 -6.121)
        (xy -14.766 -6.131)
        (xy -14.744 -6.137)
        (xy -14.721 -6.144)
        (xy -14.699 -6.15)
        (xy -14.676 -6.155)
        (xy -14.654 -6.158)
        (xy -14.629 -6.158)
        (xy -14.606 -6.16)
        (xy -14.583 -6.158)
        (xy -14.558 -6.158)
        (xy -14.535 -6.155)
        (xy -14.513 -6.15)
        (xy -14.49 -6.144)
        (xy -14.468 -6.137)
        (xy -14.446 -6.129)
        (xy -14.424 -6.121)
        (xy -14.404 -6.11)
        (xy -14.383 -6.099)
        (xy -14.363 -6.087)
        (xy -14.343 -6.075)
        (xy -14.325 -6.06)
        (xy -14.308 -6.046)
        (xy -14.29 -6.03)
        (xy -14.274 -6.012)
        (xy -14.26 -5.994)
        (xy -14.245 -5.977)
        (xy -14.232 -5.956)
        (xy -14.221 -5.937)
        (xy -14.209 -5.916)
        (xy -14.199 -5.895)
        (xy -14.19 -5.873)
        (xy -14.183 -5.852)
        (xy -14.176 -5.829)
        (xy -14.17 -5.807)
        (xy -14.165 -5.785)
        (xy -14.163 -5.761)
        (xy -14.161 -5.738)
        (xy -14.16 -5.714)
        (xy -14.161 -5.692)
        (xy -14.163 -5.668)
        (xy -14.165 -5.644)
        (xy -14.17 -5.621)
        (xy -14.176 -5.599)
        (xy -14.183 -5.576)
        (xy -14.19 -5.555)
        (xy -14.199 -5.533)
        (xy -14.209 -5.512)
        (xy -14.221 -5.491)
        (xy -14.232 -5.472)
        (xy -14.245 -5.453)
        (xy -14.26 -5.434)
        (xy -14.274 -5.416)
        (xy -14.29 -5.4)
        (xy -14.308 -5.384)
        (xy -14.325 -5.368)
        (xy -14.343 -5.355)
        (xy -14.363 -5.341)
        (xy -14.383 -5.329)
        (xy -14.404 -5.318)
        (xy -14.424 -5.307)
        (xy -14.446 -5.299)
        (xy -14.468 -5.291)
        (xy -14.49 -5.285)
        (xy -14.513 -5.28)
        (xy -14.535 -5.275)
        (xy -14.558 -5.272)
        (xy -14.583 -5.27)
        (xy -14.606 -5.269)
        (xy -14.629 -5.27)
        (xy -14.654 -5.272)
        (xy -14.676 -5.275)
        (xy -14.699 -5.28)
        (xy -14.721 -5.285)
        (xy -14.744 -5.291)
        (xy -14.766 -5.299)
        (xy -14.788 -5.307)
        (xy -14.808 -5.317)
        (xy -14.828 -5.328)
        (xy -14.849 -5.341)
        (xy -14.868 -5.355)
        (xy -14.886 -5.368)
        (xy -14.904 -5.384)
        (xy -14.92 -5.4)
        (xy -14.936 -5.416)
        (xy -14.952 -5.434)
        (xy -14.965 -5.453)
        (xy -14.978 -5.472)
        (xy -14.991 -5.491)
        (xy -15.003 -5.511)
        (xy -15.013 -5.533)
        (xy -15.022 -5.554)
        (xy -15.029 -5.576)
        (xy -15.035 -5.599)
        (xy -15.04 -5.621)
        (xy -15.045 -5.644)
        (xy -15.048 -5.666)
        (xy -15.049 -5.69)
        (xy -15.051 -5.712)
        (xy -14.606 -5.712)
        (xy -14.606 -5.717)
      )

      (stroke (width 0.001) (type solid)) (fill solid) (layer "B.Paste"))
    (fp_poly
      (pts
        (xy -14.606 -3.177)
        (xy -15.051 -3.177)
        (xy -15.049 -3.198)
        (xy -15.048 -3.222)
        (xy -15.045 -3.245)
        (xy -15.04 -3.269)
        (xy -15.035 -3.29)
        (xy -15.029 -3.313)
        (xy -15.022 -3.334)
        (xy -15.013 -3.357)
        (xy -15.003 -3.378)
        (xy -14.991 -3.398)
        (xy -14.978 -3.418)
        (xy -14.965 -3.436)
        (xy -14.952 -3.455)
        (xy -14.936 -3.472)
        (xy -14.92 -3.49)
        (xy -14.904 -3.505)
        (xy -14.886 -3.52)
        (xy -14.868 -3.535)
        (xy -14.849 -3.547)
        (xy -14.828 -3.56)
        (xy -14.808 -3.571)
        (xy -14.788 -3.581)
        (xy -14.766 -3.591)
        (xy -14.744 -3.597)
        (xy -14.721 -3.604)
        (xy -14.699 -3.609)
        (xy -14.676 -3.615)
        (xy -14.654 -3.617)
        (xy -14.629 -3.619)
        (xy -14.606 -3.62)
        (xy -14.583 -3.619)
        (xy -14.558 -3.617)
        (xy -14.535 -3.615)
        (xy -14.513 -3.609)
        (xy -14.49 -3.604)
        (xy -14.468 -3.597)
        (xy -14.446 -3.589)
        (xy -14.424 -3.581)
        (xy -14.404 -3.571)
        (xy -14.383 -3.559)
        (xy -14.363 -3.547)
        (xy -14.343 -3.535)
        (xy -14.325 -3.52)
        (xy -14.308 -3.505)
        (xy -14.29 -3.49)
        (xy -14.274 -3.472)
        (xy -14.26 -3.454)
        (xy -14.245 -3.436)
        (xy -14.232 -3.416)
        (xy -14.221 -3.396)
        (xy -14.209 -3.376)
        (xy -14.199 -3.355)
        (xy -14.19 -3.334)
        (xy -14.183 -3.313)
        (xy -14.176 -3.289)
        (xy -14.17 -3.267)
        (xy -14.165 -3.245)
        (xy -14.163 -3.221)
        (xy -14.161 -3.197)
        (xy -14.16 -3.174)
        (xy -14.161 -3.152)
        (xy -14.163 -3.128)
        (xy -14.165 -3.104)
        (xy -14.17 -3.081)
        (xy -14.176 -3.059)
        (xy -14.183 -3.036)
        (xy -14.19 -3.015)
        (xy -14.199 -2.994)
        (xy -14.209 -2.972)
        (xy -14.221 -2.951)
        (xy -14.232 -2.932)
        (xy -14.245 -2.912)
        (xy -14.26 -2.894)
        (xy -14.274 -2.876)
        (xy -14.29 -2.859)
        (xy -14.308 -2.843)
        (xy -14.325 -2.829)
        (xy -14.343 -2.814)
        (xy -14.363 -2.801)
        (xy -14.383 -2.789)
        (xy -14.404 -2.778)
        (xy -14.424 -2.767)
        (xy -14.446 -2.759)
        (xy -14.468 -2.751)
        (xy -14.49 -2.745)
        (xy -14.513 -2.74)
        (xy -14.535 -2.734)
        (xy -14.558 -2.732)
        (xy -14.583 -2.73)
        (xy -14.606 -2.729)
        (xy -14.629 -2.73)
        (xy -14.654 -2.732)
        (xy -14.676 -2.734)
        (xy -14.699 -2.74)
        (xy -14.721 -2.745)
        (xy -14.744 -2.751)
        (xy -14.766 -2.758)
        (xy -14.788 -2.767)
        (xy -14.808 -2.777)
        (xy -14.828 -2.789)
        (xy -14.849 -2.801)
        (xy -14.868 -2.814)
        (xy -14.886 -2.829)
        (xy -14.904 -2.843)
        (xy -14.92 -2.859)
        (xy -14.936 -2.876)
        (xy -14.952 -2.894)
        (xy -14.965 -2.912)
        (xy -14.978 -2.931)
        (xy -14.991 -2.951)
        (xy -15.003 -2.971)
        (xy -15.013 -2.992)
        (xy -15.022 -3.015)
        (xy -15.029 -3.036)
        (xy -15.035 -3.059)
        (xy -15.04 -3.08)
        (xy -15.045 -3.104)
        (xy -15.048 -3.126)
        (xy -15.049 -3.15)
        (xy -15.051 -3.172)
        (xy -14.606 -3.172)
        (xy -14.606 -3.177)
      )

      (stroke (width 0.001) (type solid)) (fill solid) (layer "B.Paste"))
    (fp_poly
      (pts
        (xy -14.606 1.903)
        (xy -15.051 1.903)
        (xy -15.049 1.881)
        (xy -15.048 1.857)
        (xy -15.045 1.835)
        (xy -15.04 1.811)
        (xy -15.035 1.789)
        (xy -15.029 1.767)
        (xy -15.022 1.746)
        (xy -15.013 1.724)
        (xy -15.003 1.702)
        (xy -14.991 1.682)
        (xy -14.978 1.662)
        (xy -14.965 1.643)
        (xy -14.952 1.625)
        (xy -14.936 1.607)
        (xy -14.92 1.591)
        (xy -14.904 1.575)
        (xy -14.886 1.559)
        (xy -14.868 1.545)
        (xy -14.849 1.532)
        (xy -14.828 1.519)
        (xy -14.808 1.508)
        (xy -14.788 1.498)
        (xy -14.766 1.49)
        (xy -14.744 1.482)
        (xy -14.721 1.476)
        (xy -14.699 1.47)
        (xy -14.676 1.466)
        (xy -14.654 1.462)
        (xy -14.629 1.462)
        (xy -14.606 1.46)
        (xy -14.583 1.462)
        (xy -14.558 1.462)
        (xy -14.535 1.466)
        (xy -14.513 1.47)
        (xy -14.49 1.476)
        (xy -14.468 1.482)
        (xy -14.446 1.49)
        (xy -14.424 1.498)
        (xy -14.404 1.509)
        (xy -14.383 1.52)
        (xy -14.363 1.532)
        (xy -14.343 1.545)
        (xy -14.325 1.559)
        (xy -14.308 1.575)
        (xy -14.29 1.591)
        (xy -14.274 1.607)
        (xy -14.26 1.625)
        (xy -14.245 1.643)
        (xy -14.232 1.663)
        (xy -14.221 1.684)
        (xy -14.209 1.704)
        (xy -14.199 1.724)
        (xy -14.19 1.746)
        (xy -14.183 1.767)
        (xy -14.176 1.79)
        (xy -14.17 1.813)
        (xy -14.165 1.835)
        (xy -14.163 1.859)
        (xy -14.161 1.882)
        (xy -14.16 1.905)
        (xy -14.161 1.928)
        (xy -14.163 1.952)
        (xy -14.165 1.976)
        (xy -14.17 1.998)
        (xy -14.176 2.02)
        (xy -14.183 2.044)
        (xy -14.19 2.065)
        (xy -14.199 2.086)
        (xy -14.209 2.108)
        (xy -14.221 2.127)
        (xy -14.232 2.147)
        (xy -14.245 2.167)
        (xy -14.26 2.186)
        (xy -14.274 2.203)
        (xy -14.29 2.221)
        (xy -14.308 2.237)
        (xy -14.325 2.251)
        (xy -14.343 2.266)
        (xy -14.363 2.278)
        (xy -14.383 2.29)
        (xy -14.404 2.302)
        (xy -14.424 2.312)
        (xy -14.446 2.32)
        (xy -14.468 2.328)
        (xy -14.49 2.335)
        (xy -14.513 2.34)
        (xy -14.535 2.346)
        (xy -14.558 2.348)
        (xy -14.583 2.35)
        (xy -14.606 2.351)
        (xy -14.629 2.35)
        (xy -14.654 2.348)
        (xy -14.676 2.346)
        (xy -14.699 2.34)
        (xy -14.721 2.335)
        (xy -14.744 2.328)
        (xy -14.766 2.322)
        (xy -14.788 2.312)
        (xy -14.808 2.302)
        (xy -14.828 2.291)
        (xy -14.849 2.278)
        (xy -14.868 2.266)
        (xy -14.886 2.251)
        (xy -14.904 2.237)
        (xy -14.92 2.221)
        (xy -14.936 2.203)
        (xy -14.952 2.186)
        (xy -14.965 2.167)
        (xy -14.978 2.149)
        (xy -14.991 2.129)
        (xy -15.003 2.109)
        (xy -15.013 2.088)
        (xy -15.022 2.065)
        (xy -15.029 2.044)
        (xy -15.035 2.021)
        (xy -15.04 2)
        (xy -15.045 1.976)
        (xy -15.048 1.954)
        (xy -15.049 1.93)
        (xy -15.051 1.907)
        (xy -14.606 1.907)
        (xy -14.606 1.903)
      )

      (stroke (width 0.001) (type solid)) (fill solid) (layer "B.Paste"))
    (fp_poly
      (pts
        (xy -14.606 3.173)
        (xy -15.051 3.173)
        (xy -15.049 3.151)
        (xy -15.048 3.127)
        (xy -15.045 3.105)
        (xy -15.04 3.081)
        (xy -15.035 3.06)
        (xy -15.029 3.037)
        (xy -15.022 3.016)
        (xy -15.013 2.993)
        (xy -15.003 2.972)
        (xy -14.991 2.952)
        (xy -14.978 2.932)
        (xy -14.965 2.913)
        (xy -14.952 2.895)
        (xy -14.936 2.877)
        (xy -14.92 2.86)
        (xy -14.904 2.844)
        (xy -14.886 2.83)
        (xy -14.868 2.815)
        (xy -14.849 2.802)
        (xy -14.828 2.79)
        (xy -14.808 2.778)
        (xy -14.788 2.768)
        (xy -14.766 2.759)
        (xy -14.744 2.752)
        (xy -14.721 2.746)
        (xy -14.699 2.741)
        (xy -14.676 2.735)
        (xy -14.654 2.733)
        (xy -14.629 2.731)
        (xy -14.606 2.73)
        (xy -14.583 2.731)
        (xy -14.558 2.733)
        (xy -14.535 2.735)
        (xy -14.513 2.741)
        (xy -14.49 2.746)
        (xy -14.468 2.752)
        (xy -14.446 2.76)
        (xy -14.424 2.768)
        (xy -14.404 2.779)
        (xy -14.383 2.79)
        (xy -14.363 2.802)
        (xy -14.343 2.815)
        (xy -14.325 2.83)
        (xy -14.308 2.844)
        (xy -14.29 2.86)
        (xy -14.274 2.877)
        (xy -14.26 2.895)
        (xy -14.245 2.913)
        (xy -14.232 2.933)
        (xy -14.221 2.952)
        (xy -14.209 2.973)
        (xy -14.199 2.995)
        (xy -14.19 3.016)
        (xy -14.183 3.037)
        (xy -14.176 3.06)
        (xy -14.17 3.082)
        (xy -14.165 3.105)
        (xy -14.163 3.129)
        (xy -14.161 3.153)
        (xy -14.16 3.175)
        (xy -14.161 3.198)
        (xy -14.163 3.222)
        (xy -14.165 3.246)
        (xy -14.17 3.268)
        (xy -14.176 3.29)
        (xy -14.183 3.314)
        (xy -14.19 3.335)
        (xy -14.199 3.356)
        (xy -14.209 3.377)
        (xy -14.221 3.397)
        (xy -14.232 3.417)
        (xy -14.245 3.437)
        (xy -14.26 3.455)
        (xy -14.274 3.473)
        (xy -14.29 3.491)
        (xy -14.308 3.506)
        (xy -14.325 3.521)
        (xy -14.343 3.536)
        (xy -14.363 3.548)
        (xy -14.383 3.56)
        (xy -14.404 3.572)
        (xy -14.424 3.582)
        (xy -14.446 3.59)
        (xy -14.468 3.598)
        (xy -14.49 3.605)
        (xy -14.513 3.61)
        (xy -14.535 3.616)
        (xy -14.558 3.618)
        (xy -14.583 3.62)
        (xy -14.606 3.621)
        (xy -14.629 3.62)
        (xy -14.654 3.618)
        (xy -14.676 3.616)
        (xy -14.699 3.61)
        (xy -14.721 3.605)
        (xy -14.744 3.598)
        (xy -14.766 3.592)
        (xy -14.788 3.582)
        (xy -14.808 3.572)
        (xy -14.828 3.561)
        (xy -14.849 3.548)
        (xy -14.868 3.536)
        (xy -14.886 3.521)
        (xy -14.904 3.506)
        (xy -14.92 3.491)
        (xy -14.936 3.473)
        (xy -14.952 3.456)
        (xy -14.965 3.437)
        (xy -14.978 3.419)
        (xy -14.991 3.399)
        (xy -15.003 3.379)
        (xy -15.013 3.358)
        (xy -15.022 3.335)
        (xy -15.029 3.314)
        (xy -15.035 3.291)
        (xy -15.04 3.27)
        (xy -15.045 3.246)
        (xy -15.048 3.223)
        (xy -15.049 3.199)
        (xy -15.051 3.178)
        (xy -14.606 3.178)
        (xy -14.606 3.173)
      )

      (stroke (width 0.001) (type solid)) (fill solid) (layer "B.Paste"))
    (fp_poly
      (pts
        (xy -14.606 4.443)
        (xy -15.051 4.443)
        (xy -15.049 4.422)
        (xy -15.048 4.398)
        (xy -15.045 4.374)
        (xy -15.04 4.351)
        (xy -15.035 4.329)
        (xy -15.029 4.308)
        (xy -15.022 4.286)
        (xy -15.013 4.263)
        (xy -15.003 4.242)
        (xy -14.991 4.223)
        (xy -14.978 4.202)
        (xy -14.965 4.183)
        (xy -14.952 4.164)
        (xy -14.936 4.148)
        (xy -14.92 4.13)
        (xy -14.904 4.114)
        (xy -14.886 4.1)
        (xy -14.868 4.085)
        (xy -14.849 4.072)
        (xy -14.828 4.06)
        (xy -14.808 4.048)
        (xy -14.788 4.039)
        (xy -14.766 4.029)
        (xy -14.744 4.023)
        (xy -14.721 4.015)
        (xy -14.699 4.01)
        (xy -14.676 4.005)
        (xy -14.654 4.002)
        (xy -14.629 4.002)
        (xy -14.606 4)
        (xy -14.583 4.002)
        (xy -14.558 4.002)
        (xy -14.535 4.005)
        (xy -14.513 4.01)
        (xy -14.49 4.015)
        (xy -14.468 4.023)
        (xy -14.446 4.031)
        (xy -14.424 4.039)
        (xy -14.404 4.05)
        (xy -14.383 4.06)
        (xy -14.363 4.072)
        (xy -14.343 4.085)
        (xy -14.325 4.1)
        (xy -14.308 4.114)
        (xy -14.29 4.13)
        (xy -14.274 4.148)
        (xy -14.26 4.165)
        (xy -14.245 4.183)
        (xy -14.232 4.204)
        (xy -14.221 4.223)
        (xy -14.209 4.244)
        (xy -14.199 4.265)
        (xy -14.19 4.286)
        (xy -14.183 4.308)
        (xy -14.176 4.33)
        (xy -14.17 4.353)
        (xy -14.165 4.375)
        (xy -14.163 4.398)
        (xy -14.161 4.422)
        (xy -14.16 4.446)
        (xy -14.161 4.468)
        (xy -14.163 4.492)
        (xy -14.165 4.515)
        (xy -14.17 4.539)
        (xy -14.176 4.56)
        (xy -14.183 4.584)
        (xy -14.19 4.604)
        (xy -14.199 4.627)
        (xy -14.209 4.648)
        (xy -14.221 4.669)
        (xy -14.232 4.688)
        (xy -14.245 4.707)
        (xy -14.26 4.725)
        (xy -14.274 4.744)
        (xy -14.29 4.76)
        (xy -14.308 4.776)
        (xy -14.325 4.792)
        (xy -14.343 4.805)
        (xy -14.363 4.818)
        (xy -14.383 4.83)
        (xy -14.404 4.842)
        (xy -14.424 4.853)
        (xy -14.446 4.861)
        (xy -14.468 4.869)
        (xy -14.49 4.875)
        (xy -14.513 4.88)
        (xy -14.535 4.885)
        (xy -14.558 4.888)
        (xy -14.583 4.89)
        (xy -14.606 4.89)
        (xy -14.629 4.89)
        (xy -14.654 4.888)
        (xy -14.676 4.885)
        (xy -14.699 4.88)
        (xy -14.721 4.875)
        (xy -14.744 4.869)
        (xy -14.766 4.861)
        (xy -14.788 4.853)
        (xy -14.808 4.842)
        (xy -14.828 4.832)
        (xy -14.849 4.818)
        (xy -14.868 4.805)
        (xy -14.886 4.792)
        (xy -14.904 4.776)
        (xy -14.92 4.76)
        (xy -14.936 4.744)
        (xy -14.952 4.726)
        (xy -14.965 4.707)
        (xy -14.978 4.688)
        (xy -14.991 4.669)
        (xy -15.003 4.648)
        (xy -15.013 4.627)
        (xy -15.022 4.606)
        (xy -15.029 4.584)
        (xy -15.035 4.561)
        (xy -15.04 4.539)
        (xy -15.045 4.516)
        (xy -15.048 4.494)
        (xy -15.049 4.47)
        (xy -15.051 4.447)
        (xy -14.606 4.447)
        (xy -14.606 4.443)
      )

      (stroke (width 0.001) (type solid)) (fill solid) (layer "B.Paste"))
    (fp_poly
      (pts
        (xy -14.606 5.713)
        (xy -15.051 5.713)
        (xy -15.049 5.691)
        (xy -15.048 5.667)
        (xy -15.045 5.645)
        (xy -15.04 5.622)
        (xy -15.035 5.6)
        (xy -15.029 5.577)
        (xy -15.022 5.555)
        (xy -15.013 5.534)
        (xy -15.003 5.512)
        (xy -14.991 5.492)
        (xy -14.978 5.473)
        (xy -14.965 5.454)
        (xy -14.952 5.435)
        (xy -14.936 5.417)
        (xy -14.92 5.401)
        (xy -14.904 5.385)
        (xy -14.886 5.369)
        (xy -14.868 5.356)
        (xy -14.849 5.342)
        (xy -14.828 5.329)
        (xy -14.808 5.318)
        (xy -14.788 5.308)
        (xy -14.766 5.3)
        (xy -14.744 5.292)
        (xy -14.721 5.286)
        (xy -14.699 5.281)
        (xy -14.676 5.276)
        (xy -14.654 5.273)
        (xy -14.629 5.271)
        (xy -14.606 5.27)
        (xy -14.583 5.271)
        (xy -14.558 5.273)
        (xy -14.535 5.276)
        (xy -14.513 5.281)
        (xy -14.49 5.286)
        (xy -14.468 5.292)
        (xy -14.446 5.3)
        (xy -14.424 5.308)
        (xy -14.404 5.319)
        (xy -14.383 5.33)
        (xy -14.363 5.342)
        (xy -14.343 5.356)
        (xy -14.325 5.369)
        (xy -14.308 5.385)
        (xy -14.29 5.401)
        (xy -14.274 5.417)
        (xy -14.26 5.435)
        (xy -14.245 5.454)
        (xy -14.232 5.473)
        (xy -14.221 5.492)
        (xy -14.209 5.513)
        (xy -14.199 5.534)
        (xy -14.19 5.556)
        (xy -14.183 5.577)
        (xy -14.176 5.6)
        (xy -14.17 5.622)
        (xy -14.165 5.645)
        (xy -14.163 5.669)
        (xy -14.161 5.693)
        (xy -14.16 5.715)
        (xy -14.161 5.739)
        (xy -14.163 5.762)
        (xy -14.165 5.786)
        (xy -14.17 5.808)
        (xy -14.176 5.83)
        (xy -14.183 5.853)
        (xy -14.19 5.874)
        (xy -14.199 5.896)
        (xy -14.209 5.917)
        (xy -14.221 5.938)
        (xy -14.232 5.957)
        (xy -14.245 5.978)
        (xy -14.26 5.995)
        (xy -14.274 6.013)
        (xy -14.29 6.031)
        (xy -14.308 6.047)
        (xy -14.325 6.061)
        (xy -14.343 6.076)
        (xy -14.363 6.088)
        (xy -14.383 6.1)
        (xy -14.404 6.111)
        (xy -14.424 6.122)
        (xy -14.446 6.13)
        (xy -14.468 6.138)
        (xy -14.49 6.145)
        (xy -14.513 6.151)
        (xy -14.535 6.156)
        (xy -14.558 6.159)
        (xy -14.583 6.159)
        (xy -14.606 6.161)
        (xy -14.629 6.159)
        (xy -14.654 6.159)
        (xy -14.676 6.156)
        (xy -14.699 6.151)
        (xy -14.721 6.145)
        (xy -14.744 6.138)
        (xy -14.766 6.132)
        (xy -14.788 6.122)
        (xy -14.808 6.112)
        (xy -14.828 6.101)
        (xy -14.849 6.088)
        (xy -14.868 6.076)
        (xy -14.886 6.061)
        (xy -14.904 6.047)
        (xy -14.92 6.031)
        (xy -14.936 6.013)
        (xy -14.952 5.997)
        (xy -14.965 5.978)
        (xy -14.978 5.959)
        (xy -14.991 5.938)
        (xy -15.003 5.919)
        (xy -15.013 5.898)
        (xy -15.022 5.875)
        (xy -15.029 5.853)
        (xy -15.035 5.832)
        (xy -15.04 5.81)
        (xy -15.045 5.786)
        (xy -15.048 5.763)
        (xy -15.049 5.739)
        (xy -15.051 5.718)
        (xy -14.606 5.718)
        (xy -14.606 5.713)
      )

      (stroke (width 0.001) (type solid)) (fill solid) (layer "B.Paste"))
    (fp_poly
      (pts
        (xy -13.336 -5.717)
        (xy -13.78 -5.717)
        (xy -13.779 -5.738)
        (xy -13.779 -5.762)
        (xy -13.776 -5.785)
        (xy -13.77 -5.809)
        (xy -13.766 -5.831)
        (xy -13.758 -5.852)
        (xy -13.751 -5.874)
        (xy -13.743 -5.897)
        (xy -13.732 -5.918)
        (xy -13.721 -5.937)
        (xy -13.708 -5.958)
        (xy -13.695 -5.977)
        (xy -13.681 -5.996)
        (xy -13.667 -6.012)
        (xy -13.651 -6.03)
        (xy -13.633 -6.046)
        (xy -13.616 -6.06)
        (xy -13.597 -6.075)
        (xy -13.578 -6.087)
        (xy -13.558 -6.1)
        (xy -13.538 -6.111)
        (xy -13.517 -6.121)
        (xy -13.495 -6.131)
        (xy -13.474 -6.137)
        (xy -13.452 -6.144)
        (xy -13.429 -6.15)
        (xy -13.407 -6.155)
        (xy -13.383 -6.158)
        (xy -13.359 -6.158)
        (xy -13.336 -6.16)
        (xy -13.312 -6.158)
        (xy -13.288 -6.158)
        (xy -13.266 -6.155)
        (xy -13.243 -6.15)
        (xy -13.221 -6.144)
        (xy -13.197 -6.137)
        (xy -13.176 -6.129)
        (xy -13.154 -6.121)
        (xy -13.133 -6.11)
        (xy -13.113 -6.099)
        (xy -13.093 -6.087)
        (xy -13.074 -6.075)
        (xy -13.055 -6.06)
        (xy -13.038 -6.046)
        (xy -13.02 -6.03)
        (xy -13.004 -6.012)
        (xy -12.99 -5.994)
        (xy -12.975 -5.977)
        (xy -12.962 -5.956)
        (xy -12.95 -5.937)
        (xy -12.939 -5.916)
        (xy -12.929 -5.895)
        (xy -12.92 -5.873)
        (xy -12.913 -5.852)
        (xy -12.905 -5.829)
        (xy -12.901 -5.807)
        (xy -12.895 -5.785)
        (xy -12.892 -5.761)
        (xy -12.891 -5.738)
        (xy -12.891 -5.714)
        (xy -12.891 -5.692)
        (xy -12.892 -5.668)
        (xy -12.895 -5.644)
        (xy -12.901 -5.621)
        (xy -12.905 -5.599)
        (xy -12.913 -5.576)
        (xy -12.92 -5.555)
        (xy -12.929 -5.533)
        (xy -12.939 -5.512)
        (xy -12.95 -5.491)
        (xy -12.962 -5.472)
        (xy -12.975 -5.453)
        (xy -12.99 -5.434)
        (xy -13.004 -5.416)
        (xy -13.02 -5.4)
        (xy -13.038 -5.384)
        (xy -13.055 -5.368)
        (xy -13.074 -5.355)
        (xy -13.093 -5.341)
        (xy -13.113 -5.329)
        (xy -13.133 -5.318)
        (xy -13.154 -5.307)
        (xy -13.176 -5.299)
        (xy -13.197 -5.291)
        (xy -13.221 -5.285)
        (xy -13.243 -5.28)
        (xy -13.266 -5.275)
        (xy -13.288 -5.272)
        (xy -13.312 -5.27)
        (xy -13.336 -5.269)
        (xy -13.359 -5.27)
        (xy -13.383 -5.272)
        (xy -13.407 -5.275)
        (xy -13.429 -5.28)
        (xy -13.452 -5.285)
        (xy -13.474 -5.291)
        (xy -13.495 -5.299)
        (xy -13.517 -5.307)
        (xy -13.538 -5.317)
        (xy -13.558 -5.328)
        (xy -13.578 -5.341)
        (xy -13.597 -5.355)
        (xy -13.616 -5.368)
        (xy -13.633 -5.384)
        (xy -13.651 -5.4)
        (xy -13.667 -5.416)
        (xy -13.681 -5.434)
        (xy -13.695 -5.453)
        (xy -13.708 -5.472)
        (xy -13.721 -5.491)
        (xy -13.732 -5.511)
        (xy -13.743 -5.533)
        (xy -13.751 -5.554)
        (xy -13.758 -5.576)
        (xy -13.766 -5.599)
        (xy -13.77 -5.621)
        (xy -13.776 -5.644)
        (xy -13.779 -5.666)
        (xy -13.779 -5.69)
        (xy -13.78 -5.712)
        (xy -13.336 -5.712)
        (xy -13.336 -5.717)
      )

      (stroke (width 0.001) (type solid)) (fill solid) (layer "B.Paste"))
    (fp_poly
      (pts
        (xy -13.336 -3.177)
        (xy -13.78 -3.177)
        (xy -13.779 -3.198)
        (xy -13.779 -3.222)
        (xy -13.776 -3.245)
        (xy -13.77 -3.269)
        (xy -13.766 -3.29)
        (xy -13.758 -3.313)
        (xy -13.751 -3.334)
        (xy -13.743 -3.357)
        (xy -13.732 -3.378)
        (xy -13.721 -3.398)
        (xy -13.708 -3.418)
        (xy -13.695 -3.436)
        (xy -13.681 -3.455)
        (xy -13.667 -3.472)
        (xy -13.651 -3.49)
        (xy -13.633 -3.505)
        (xy -13.616 -3.52)
        (xy -13.597 -3.535)
        (xy -13.578 -3.547)
        (xy -13.558 -3.56)
        (xy -13.538 -3.571)
        (xy -13.517 -3.581)
        (xy -13.495 -3.591)
        (xy -13.474 -3.597)
        (xy -13.452 -3.604)
        (xy -13.429 -3.609)
        (xy -13.407 -3.615)
        (xy -13.383 -3.617)
        (xy -13.359 -3.619)
        (xy -13.336 -3.62)
        (xy -13.312 -3.619)
        (xy -13.288 -3.617)
        (xy -13.266 -3.615)
        (xy -13.243 -3.609)
        (xy -13.221 -3.604)
        (xy -13.197 -3.597)
        (xy -13.176 -3.589)
        (xy -13.154 -3.581)
        (xy -13.133 -3.571)
        (xy -13.113 -3.559)
        (xy -13.093 -3.547)
        (xy -13.074 -3.535)
        (xy -13.055 -3.52)
        (xy -13.038 -3.505)
        (xy -13.02 -3.49)
        (xy -13.004 -3.472)
        (xy -12.99 -3.454)
        (xy -12.975 -3.436)
        (xy -12.962 -3.416)
        (xy -12.95 -3.396)
        (xy -12.939 -3.376)
        (xy -12.929 -3.355)
        (xy -12.92 -3.334)
        (xy -12.913 -3.313)
        (xy -12.905 -3.289)
        (xy -12.901 -3.267)
        (xy -12.895 -3.245)
        (xy -12.892 -3.221)
        (xy -12.891 -3.197)
        (xy -12.891 -3.174)
        (xy -12.891 -3.152)
        (xy -12.892 -3.128)
        (xy -12.895 -3.104)
        (xy -12.901 -3.081)
        (xy -12.905 -3.059)
        (xy -12.913 -3.036)
        (xy -12.92 -3.015)
        (xy -12.929 -2.994)
        (xy -12.939 -2.972)
        (xy -12.95 -2.951)
        (xy -12.962 -2.932)
        (xy -12.975 -2.912)
        (xy -12.99 -2.894)
        (xy -13.004 -2.876)
        (xy -13.02 -2.859)
        (xy -13.038 -2.843)
        (xy -13.055 -2.829)
        (xy -13.074 -2.814)
        (xy -13.093 -2.801)
        (xy -13.113 -2.789)
        (xy -13.133 -2.778)
        (xy -13.154 -2.767)
        (xy -13.176 -2.759)
        (xy -13.197 -2.751)
        (xy -13.221 -2.745)
        (xy -13.243 -2.74)
        (xy -13.266 -2.734)
        (xy -13.288 -2.732)
        (xy -13.312 -2.73)
        (xy -13.336 -2.729)
        (xy -13.359 -2.73)
        (xy -13.383 -2.732)
        (xy -13.407 -2.734)
        (xy -13.429 -2.74)
        (xy -13.452 -2.745)
        (xy -13.474 -2.751)
        (xy -13.495 -2.758)
        (xy -13.517 -2.767)
        (xy -13.538 -2.777)
        (xy -13.558 -2.789)
        (xy -13.578 -2.801)
        (xy -13.597 -2.814)
        (xy -13.616 -2.829)
        (xy -13.633 -2.843)
        (xy -13.651 -2.859)
        (xy -13.667 -2.876)
        (xy -13.681 -2.894)
        (xy -13.695 -2.912)
        (xy -13.708 -2.931)
        (xy -13.721 -2.951)
        (xy -13.732 -2.971)
        (xy -13.743 -2.992)
        (xy -13.751 -3.015)
        (xy -13.758 -3.036)
        (xy -13.766 -3.059)
        (xy -13.77 -3.08)
        (xy -13.776 -3.104)
        (xy -13.779 -3.126)
        (xy -13.779 -3.15)
        (xy -13.78 -3.172)
        (xy -13.336 -3.172)
        (xy -13.336 -3.177)
      )

      (stroke (width 0.001) (type solid)) (fill solid) (layer "B.Paste"))
    (fp_poly
      (pts
        (xy -13.336 1.903)
        (xy -13.78 1.903)
        (xy -13.779 1.881)
        (xy -13.779 1.857)
        (xy -13.776 1.835)
        (xy -13.77 1.811)
        (xy -13.766 1.789)
        (xy -13.758 1.767)
        (xy -13.751 1.746)
        (xy -13.743 1.724)
        (xy -13.732 1.702)
        (xy -13.721 1.682)
        (xy -13.708 1.662)
        (xy -13.695 1.643)
        (xy -13.681 1.625)
        (xy -13.667 1.607)
        (xy -13.651 1.591)
        (xy -13.633 1.575)
        (xy -13.616 1.559)
        (xy -13.597 1.545)
        (xy -13.578 1.532)
        (xy -13.558 1.519)
        (xy -13.538 1.508)
        (xy -13.517 1.498)
        (xy -13.495 1.49)
        (xy -13.474 1.482)
        (xy -13.452 1.476)
        (xy -13.429 1.47)
        (xy -13.407 1.466)
        (xy -13.383 1.462)
        (xy -13.359 1.462)
        (xy -13.336 1.46)
        (xy -13.312 1.462)
        (xy -13.288 1.462)
        (xy -13.266 1.466)
        (xy -13.243 1.47)
        (xy -13.221 1.476)
        (xy -13.197 1.482)
        (xy -13.176 1.49)
        (xy -13.154 1.498)
        (xy -13.133 1.509)
        (xy -13.113 1.52)
        (xy -13.093 1.532)
        (xy -13.074 1.545)
        (xy -13.055 1.559)
        (xy -13.038 1.575)
        (xy -13.02 1.591)
        (xy -13.004 1.607)
        (xy -12.99 1.625)
        (xy -12.975 1.643)
        (xy -12.962 1.663)
        (xy -12.95 1.684)
        (xy -12.939 1.704)
        (xy -12.929 1.724)
        (xy -12.92 1.746)
        (xy -12.913 1.767)
        (xy -12.905 1.79)
        (xy -12.901 1.813)
        (xy -12.895 1.835)
        (xy -12.892 1.859)
        (xy -12.891 1.882)
        (xy -12.891 1.905)
        (xy -12.891 1.928)
        (xy -12.892 1.952)
        (xy -12.895 1.976)
        (xy -12.901 1.998)
        (xy -12.905 2.02)
        (xy -12.913 2.044)
        (xy -12.92 2.065)
        (xy -12.929 2.086)
        (xy -12.939 2.108)
        (xy -12.95 2.127)
        (xy -12.962 2.147)
        (xy -12.975 2.167)
        (xy -12.99 2.186)
        (xy -13.004 2.203)
        (xy -13.02 2.221)
        (xy -13.038 2.237)
        (xy -13.055 2.251)
        (xy -13.074 2.266)
        (xy -13.093 2.278)
        (xy -13.113 2.29)
        (xy -13.133 2.302)
        (xy -13.154 2.312)
        (xy -13.176 2.32)
        (xy -13.197 2.328)
        (xy -13.221 2.335)
        (xy -13.243 2.34)
        (xy -13.266 2.346)
        (xy -13.288 2.348)
        (xy -13.312 2.35)
        (xy -13.336 2.351)
        (xy -13.359 2.35)
        (xy -13.383 2.348)
        (xy -13.407 2.346)
        (xy -13.429 2.34)
        (xy -13.452 2.335)
        (xy -13.474 2.328)
        (xy -13.495 2.322)
        (xy -13.517 2.312)
        (xy -13.538 2.302)
        (xy -13.558 2.291)
        (xy -13.578 2.278)
        (xy -13.597 2.266)
        (xy -13.616 2.251)
        (xy -13.633 2.237)
        (xy -13.651 2.221)
        (xy -13.667 2.203)
        (xy -13.681 2.186)
        (xy -13.695 2.167)
        (xy -13.708 2.149)
        (xy -13.721 2.129)
        (xy -13.732 2.109)
        (xy -13.743 2.088)
        (xy -13.751 2.065)
        (xy -13.758 2.044)
        (xy -13.766 2.021)
        (xy -13.77 2)
        (xy -13.776 1.976)
        (xy -13.779 1.954)
        (xy -13.779 1.93)
        (xy -13.78 1.907)
        (xy -13.336 1.907)
        (xy -13.336 1.903)
      )

      (stroke (width 0.001) (type solid)) (fill solid) (layer "B.Paste"))
    (fp_poly
      (pts
        (xy -13.336 3.173)
        (xy -13.78 3.173)
        (xy -13.779 3.151)
        (xy -13.779 3.127)
        (xy -13.776 3.105)
        (xy -13.77 3.081)
        (xy -13.766 3.06)
        (xy -13.758 3.037)
        (xy -13.751 3.016)
        (xy -13.743 2.993)
        (xy -13.732 2.972)
        (xy -13.721 2.952)
        (xy -13.708 2.932)
        (xy -13.695 2.913)
        (xy -13.681 2.895)
        (xy -13.667 2.877)
        (xy -13.651 2.86)
        (xy -13.633 2.844)
        (xy -13.616 2.83)
        (xy -13.597 2.815)
        (xy -13.578 2.802)
        (xy -13.558 2.79)
        (xy -13.538 2.778)
        (xy -13.517 2.768)
        (xy -13.495 2.759)
        (xy -13.474 2.752)
        (xy -13.452 2.746)
        (xy -13.429 2.741)
        (xy -13.407 2.735)
        (xy -13.383 2.733)
        (xy -13.359 2.731)
        (xy -13.336 2.73)
        (xy -13.312 2.731)
        (xy -13.288 2.733)
        (xy -13.266 2.735)
        (xy -13.243 2.741)
        (xy -13.221 2.746)
        (xy -13.197 2.752)
        (xy -13.176 2.76)
        (xy -13.154 2.768)
        (xy -13.133 2.779)
        (xy -13.113 2.79)
        (xy -13.093 2.802)
        (xy -13.074 2.815)
        (xy -13.055 2.83)
        (xy -13.038 2.844)
        (xy -13.02 2.86)
        (xy -13.004 2.877)
        (xy -12.99 2.895)
        (xy -12.975 2.913)
        (xy -12.962 2.933)
        (xy -12.95 2.952)
        (xy -12.939 2.973)
        (xy -12.929 2.995)
        (xy -12.92 3.016)
        (xy -12.913 3.037)
        (xy -12.905 3.06)
        (xy -12.901 3.082)
        (xy -12.895 3.105)
        (xy -12.892 3.129)
        (xy -12.891 3.153)
        (xy -12.891 3.175)
        (xy -12.891 3.198)
        (xy -12.892 3.222)
        (xy -12.895 3.246)
        (xy -12.901 3.268)
        (xy -12.905 3.29)
        (xy -12.913 3.314)
        (xy -12.92 3.335)
        (xy -12.929 3.356)
        (xy -12.939 3.377)
        (xy -12.95 3.397)
        (xy -12.962 3.417)
        (xy -12.975 3.437)
        (xy -12.99 3.455)
        (xy -13.004 3.473)
        (xy -13.02 3.491)
        (xy -13.038 3.506)
        (xy -13.055 3.521)
        (xy -13.074 3.536)
        (xy -13.093 3.548)
        (xy -13.113 3.56)
        (xy -13.133 3.572)
        (xy -13.154 3.582)
        (xy -13.176 3.59)
        (xy -13.197 3.598)
        (xy -13.221 3.605)
        (xy -13.243 3.61)
        (xy -13.266 3.616)
        (xy -13.288 3.618)
        (xy -13.312 3.62)
        (xy -13.336 3.621)
        (xy -13.359 3.62)
        (xy -13.383 3.618)
        (xy -13.407 3.616)
        (xy -13.429 3.61)
        (xy -13.452 3.605)
        (xy -13.474 3.598)
        (xy -13.495 3.592)
        (xy -13.517 3.582)
        (xy -13.538 3.572)
        (xy -13.558 3.561)
        (xy -13.578 3.548)
        (xy -13.597 3.536)
        (xy -13.616 3.521)
        (xy -13.633 3.506)
        (xy -13.651 3.491)
        (xy -13.667 3.473)
        (xy -13.681 3.456)
        (xy -13.695 3.437)
        (xy -13.708 3.419)
        (xy -13.721 3.399)
        (xy -13.732 3.379)
        (xy -13.743 3.358)
        (xy -13.751 3.335)
        (xy -13.758 3.314)
        (xy -13.766 3.291)
        (xy -13.77 3.27)
        (xy -13.776 3.246)
        (xy -13.779 3.223)
        (xy -13.779 3.199)
        (xy -13.78 3.178)
        (xy -13.336 3.178)
        (xy -13.336 3.173)
      )

      (stroke (width 0.001) (type solid)) (fill solid) (layer "B.Paste"))
    (fp_poly
      (pts
        (xy -13.336 4.443)
        (xy -13.78 4.443)
        (xy -13.779 4.422)
        (xy -13.779 4.398)
        (xy -13.776 4.374)
        (xy -13.77 4.351)
        (xy -13.766 4.329)
        (xy -13.758 4.308)
        (xy -13.751 4.286)
        (xy -13.743 4.263)
        (xy -13.732 4.242)
        (xy -13.721 4.223)
        (xy -13.708 4.202)
        (xy -13.695 4.183)
        (xy -13.681 4.164)
        (xy -13.667 4.148)
        (xy -13.651 4.13)
        (xy -13.633 4.114)
        (xy -13.616 4.1)
        (xy -13.597 4.085)
        (xy -13.578 4.072)
        (xy -13.558 4.06)
        (xy -13.538 4.048)
        (xy -13.517 4.039)
        (xy -13.495 4.029)
        (xy -13.474 4.023)
        (xy -13.452 4.015)
        (xy -13.429 4.01)
        (xy -13.407 4.005)
        (xy -13.383 4.002)
        (xy -13.359 4.002)
        (xy -13.336 4)
        (xy -13.312 4.002)
        (xy -13.288 4.002)
        (xy -13.266 4.005)
        (xy -13.243 4.01)
        (xy -13.221 4.015)
        (xy -13.197 4.023)
        (xy -13.176 4.031)
        (xy -13.154 4.039)
        (xy -13.133 4.05)
        (xy -13.113 4.06)
        (xy -13.093 4.072)
        (xy -13.074 4.085)
        (xy -13.055 4.1)
        (xy -13.038 4.114)
        (xy -13.02 4.13)
        (xy -13.004 4.148)
        (xy -12.99 4.165)
        (xy -12.975 4.183)
        (xy -12.962 4.204)
        (xy -12.95 4.223)
        (xy -12.939 4.244)
        (xy -12.929 4.265)
        (xy -12.92 4.286)
        (xy -12.913 4.308)
        (xy -12.905 4.33)
        (xy -12.901 4.353)
        (xy -12.895 4.375)
        (xy -12.892 4.398)
        (xy -12.891 4.422)
        (xy -12.891 4.446)
        (xy -12.891 4.468)
        (xy -12.892 4.492)
        (xy -12.895 4.515)
        (xy -12.901 4.539)
        (xy -12.905 4.56)
        (xy -12.913 4.584)
        (xy -12.92 4.604)
        (xy -12.929 4.627)
        (xy -12.939 4.648)
        (xy -12.95 4.669)
        (xy -12.962 4.688)
        (xy -12.975 4.707)
        (xy -12.99 4.725)
        (xy -13.004 4.744)
        (xy -13.02 4.76)
        (xy -13.038 4.776)
        (xy -13.055 4.792)
        (xy -13.074 4.805)
        (xy -13.093 4.818)
        (xy -13.113 4.83)
        (xy -13.133 4.842)
        (xy -13.154 4.853)
        (xy -13.176 4.861)
        (xy -13.197 4.869)
        (xy -13.221 4.875)
        (xy -13.243 4.88)
        (xy -13.266 4.885)
        (xy -13.288 4.888)
        (xy -13.312 4.89)
        (xy -13.336 4.89)
        (xy -13.359 4.89)
        (xy -13.383 4.888)
        (xy -13.407 4.885)
        (xy -13.429 4.88)
        (xy -13.452 4.875)
        (xy -13.474 4.869)
        (xy -13.495 4.861)
        (xy -13.517 4.853)
        (xy -13.538 4.842)
        (xy -13.558 4.832)
        (xy -13.578 4.818)
        (xy -13.597 4.805)
        (xy -13.616 4.792)
        (xy -13.633 4.776)
        (xy -13.651 4.76)
        (xy -13.667 4.744)
        (xy -13.681 4.726)
        (xy -13.695 4.707)
        (xy -13.708 4.688)
        (xy -13.721 4.669)
        (xy -13.732 4.648)
        (xy -13.743 4.627)
        (xy -13.751 4.606)
        (xy -13.758 4.584)
        (xy -13.766 4.561)
        (xy -13.77 4.539)
        (xy -13.776 4.516)
        (xy -13.779 4.494)
        (xy -13.779 4.47)
        (xy -13.78 4.447)
        (xy -13.336 4.447)
        (xy -13.336 4.443)
      )

      (stroke (width 0.001) (type solid)) (fill solid) (layer "B.Paste"))
    (fp_poly
      (pts
        (xy -13.336 5.713)
        (xy -13.78 5.713)
        (xy -13.779 5.691)
        (xy -13.779 5.667)
        (xy -13.776 5.645)
        (xy -13.77 5.622)
        (xy -13.766 5.6)
        (xy -13.758 5.577)
        (xy -13.751 5.555)
        (xy -13.743 5.534)
        (xy -13.732 5.512)
        (xy -13.721 5.492)
        (xy -13.708 5.473)
        (xy -13.695 5.454)
        (xy -13.681 5.435)
        (xy -13.667 5.417)
        (xy -13.651 5.401)
        (xy -13.633 5.385)
        (xy -13.616 5.369)
        (xy -13.597 5.356)
        (xy -13.578 5.342)
        (xy -13.558 5.329)
        (xy -13.538 5.318)
        (xy -13.517 5.308)
        (xy -13.495 5.3)
        (xy -13.474 5.292)
        (xy -13.452 5.286)
        (xy -13.429 5.281)
        (xy -13.407 5.276)
        (xy -13.383 5.273)
        (xy -13.359 5.271)
        (xy -13.336 5.27)
        (xy -13.312 5.271)
        (xy -13.288 5.273)
        (xy -13.266 5.276)
        (xy -13.243 5.281)
        (xy -13.221 5.286)
        (xy -13.197 5.292)
        (xy -13.176 5.3)
        (xy -13.154 5.308)
        (xy -13.133 5.319)
        (xy -13.113 5.33)
        (xy -13.093 5.342)
        (xy -13.074 5.356)
        (xy -13.055 5.369)
        (xy -13.038 5.385)
        (xy -13.02 5.401)
        (xy -13.004 5.417)
        (xy -12.99 5.435)
        (xy -12.975 5.454)
        (xy -12.962 5.473)
        (xy -12.95 5.492)
        (xy -12.939 5.513)
        (xy -12.929 5.534)
        (xy -12.92 5.556)
        (xy -12.913 5.577)
        (xy -12.905 5.6)
        (xy -12.901 5.622)
        (xy -12.895 5.645)
        (xy -12.892 5.669)
        (xy -12.891 5.693)
        (xy -12.891 5.715)
        (xy -12.891 5.739)
        (xy -12.892 5.762)
        (xy -12.895 5.786)
        (xy -12.901 5.808)
        (xy -12.905 5.83)
        (xy -12.913 5.853)
        (xy -12.92 5.874)
        (xy -12.929 5.896)
        (xy -12.939 5.917)
        (xy -12.95 5.938)
        (xy -12.962 5.957)
        (xy -12.975 5.978)
        (xy -12.99 5.995)
        (xy -13.004 6.013)
        (xy -13.02 6.031)
        (xy -13.038 6.047)
        (xy -13.055 6.061)
        (xy -13.074 6.076)
        (xy -13.093 6.088)
        (xy -13.113 6.1)
        (xy -13.133 6.111)
        (xy -13.154 6.122)
        (xy -13.176 6.13)
        (xy -13.197 6.138)
        (xy -13.221 6.145)
        (xy -13.243 6.151)
        (xy -13.266 6.156)
        (xy -13.288 6.159)
        (xy -13.312 6.159)
        (xy -13.336 6.161)
        (xy -13.359 6.159)
        (xy -13.383 6.159)
        (xy -13.407 6.156)
        (xy -13.429 6.151)
        (xy -13.452 6.145)
        (xy -13.474 6.138)
        (xy -13.495 6.132)
        (xy -13.517 6.122)
        (xy -13.538 6.112)
        (xy -13.558 6.101)
        (xy -13.578 6.088)
        (xy -13.597 6.076)
        (xy -13.616 6.061)
        (xy -13.633 6.047)
        (xy -13.651 6.031)
        (xy -13.667 6.013)
        (xy -13.681 5.997)
        (xy -13.695 5.978)
        (xy -13.708 5.959)
        (xy -13.721 5.938)
        (xy -13.732 5.919)
        (xy -13.743 5.898)
        (xy -13.751 5.875)
        (xy -13.758 5.853)
        (xy -13.766 5.832)
        (xy -13.77 5.81)
        (xy -13.776 5.786)
        (xy -13.779 5.763)
        (xy -13.779 5.739)
        (xy -13.78 5.718)
        (xy -13.336 5.718)
        (xy -13.336 5.713)
      )

      (stroke (width 0.001) (type solid)) (fill solid) (layer "B.Paste"))
    (fp_poly
      (pts
        (xy -12.065 -5.717)
        (xy -12.51 -5.717)
        (xy -12.51 -5.738)
        (xy -12.508 -5.762)
        (xy -12.506 -5.785)
        (xy -12.5 -5.809)
        (xy -12.495 -5.831)
        (xy -12.488 -5.852)
        (xy -12.481 -5.874)
        (xy -12.472 -5.897)
        (xy -12.462 -5.918)
        (xy -12.452 -5.937)
        (xy -12.439 -5.958)
        (xy -12.426 -5.977)
        (xy -12.411 -5.996)
        (xy -12.397 -6.012)
        (xy -12.381 -6.03)
        (xy -12.363 -6.046)
        (xy -12.346 -6.06)
        (xy -12.327 -6.075)
        (xy -12.308 -6.087)
        (xy -12.288 -6.1)
        (xy -12.269 -6.111)
        (xy -12.247 -6.121)
        (xy -12.225 -6.131)
        (xy -12.203 -6.137)
        (xy -12.181 -6.144)
        (xy -12.16 -6.15)
        (xy -12.136 -6.155)
        (xy -12.113 -6.158)
        (xy -12.09 -6.158)
        (xy -12.065 -6.16)
        (xy -12.042 -6.158)
        (xy -12.019 -6.158)
        (xy -11.995 -6.155)
        (xy -11.972 -6.15)
        (xy -11.95 -6.144)
        (xy -11.927 -6.137)
        (xy -11.907 -6.129)
        (xy -11.885 -6.121)
        (xy -11.863 -6.11)
        (xy -11.843 -6.099)
        (xy -11.824 -6.087)
        (xy -11.804 -6.075)
        (xy -11.785 -6.06)
        (xy -11.767 -6.046)
        (xy -11.75 -6.03)
        (xy -11.734 -6.012)
        (xy -11.719 -5.994)
        (xy -11.705 -5.977)
        (xy -11.692 -5.956)
        (xy -11.68 -5.937)
        (xy -11.67 -5.916)
        (xy -11.658 -5.895)
        (xy -11.651 -5.873)
        (xy -11.642 -5.852)
        (xy -11.635 -5.829)
        (xy -11.631 -5.807)
        (xy -11.625 -5.785)
        (xy -11.622 -5.761)
        (xy -11.622 -5.738)
        (xy -11.62 -5.714)
        (xy -11.622 -5.692)
        (xy -11.622 -5.668)
        (xy -11.625 -5.644)
        (xy -11.631 -5.621)
        (xy -11.635 -5.599)
        (xy -11.642 -5.576)
        (xy -11.651 -5.555)
        (xy -11.658 -5.533)
        (xy -11.67 -5.512)
        (xy -11.68 -5.491)
        (xy -11.692 -5.472)
        (xy -11.705 -5.453)
        (xy -11.719 -5.434)
        (xy -11.734 -5.416)
        (xy -11.75 -5.4)
        (xy -11.767 -5.384)
        (xy -11.785 -5.368)
        (xy -11.804 -5.355)
        (xy -11.824 -5.341)
        (xy -11.843 -5.329)
        (xy -11.863 -5.318)
        (xy -11.885 -5.307)
        (xy -11.907 -5.299)
        (xy -11.927 -5.291)
        (xy -11.95 -5.285)
        (xy -11.972 -5.28)
        (xy -11.995 -5.275)
        (xy -12.019 -5.272)
        (xy -12.042 -5.27)
        (xy -12.065 -5.269)
        (xy -12.09 -5.27)
        (xy -12.113 -5.272)
        (xy -12.136 -5.275)
        (xy -12.16 -5.28)
        (xy -12.181 -5.285)
        (xy -12.203 -5.291)
        (xy -12.225 -5.299)
        (xy -12.247 -5.307)
        (xy -12.269 -5.317)
        (xy -12.288 -5.328)
        (xy -12.308 -5.341)
        (xy -12.327 -5.355)
        (xy -12.346 -5.368)
        (xy -12.363 -5.384)
        (xy -12.381 -5.4)
        (xy -12.397 -5.416)
        (xy -12.411 -5.434)
        (xy -12.426 -5.453)
        (xy -12.439 -5.472)
        (xy -12.452 -5.491)
        (xy -12.462 -5.511)
        (xy -12.472 -5.533)
        (xy -12.481 -5.554)
        (xy -12.488 -5.576)
        (xy -12.495 -5.599)
        (xy -12.5 -5.621)
        (xy -12.506 -5.644)
        (xy -12.508 -5.666)
        (xy -12.51 -5.69)
        (xy -12.51 -5.712)
        (xy -12.065 -5.712)
        (xy -12.065 -5.717)
      )

      (stroke (width 0.001) (type solid)) (fill solid) (layer "B.Paste"))
    (fp_poly
      (pts
        (xy -12.065 -3.177)
        (xy -12.51 -3.177)
        (xy -12.51 -3.198)
        (xy -12.508 -3.222)
        (xy -12.506 -3.245)
        (xy -12.5 -3.269)
        (xy -12.495 -3.29)
        (xy -12.488 -3.313)
        (xy -12.481 -3.334)
        (xy -12.472 -3.357)
        (xy -12.462 -3.378)
        (xy -12.452 -3.398)
        (xy -12.439 -3.418)
        (xy -12.426 -3.436)
        (xy -12.411 -3.455)
        (xy -12.397 -3.472)
        (xy -12.381 -3.49)
        (xy -12.363 -3.505)
        (xy -12.346 -3.52)
        (xy -12.327 -3.535)
        (xy -12.308 -3.547)
        (xy -12.288 -3.56)
        (xy -12.269 -3.571)
        (xy -12.247 -3.581)
        (xy -12.225 -3.591)
        (xy -12.203 -3.597)
        (xy -12.181 -3.604)
        (xy -12.16 -3.609)
        (xy -12.136 -3.615)
        (xy -12.113 -3.617)
        (xy -12.09 -3.619)
        (xy -12.065 -3.62)
        (xy -12.042 -3.619)
        (xy -12.019 -3.617)
        (xy -11.995 -3.615)
        (xy -11.972 -3.609)
        (xy -11.95 -3.604)
        (xy -11.927 -3.597)
        (xy -11.907 -3.589)
        (xy -11.885 -3.581)
        (xy -11.863 -3.571)
        (xy -11.843 -3.559)
        (xy -11.824 -3.547)
        (xy -11.804 -3.535)
        (xy -11.785 -3.52)
        (xy -11.767 -3.505)
        (xy -11.75 -3.49)
        (xy -11.734 -3.472)
        (xy -11.719 -3.454)
        (xy -11.705 -3.436)
        (xy -11.692 -3.416)
        (xy -11.68 -3.396)
        (xy -11.67 -3.376)
        (xy -11.658 -3.355)
        (xy -11.651 -3.334)
        (xy -11.642 -3.313)
        (xy -11.635 -3.289)
        (xy -11.631 -3.267)
        (xy -11.625 -3.245)
        (xy -11.622 -3.221)
        (xy -11.622 -3.197)
        (xy -11.62 -3.174)
        (xy -11.622 -3.152)
        (xy -11.622 -3.128)
        (xy -11.625 -3.104)
        (xy -11.631 -3.081)
        (xy -11.635 -3.059)
        (xy -11.642 -3.036)
        (xy -11.651 -3.015)
        (xy -11.658 -2.994)
        (xy -11.67 -2.972)
        (xy -11.68 -2.951)
        (xy -11.692 -2.932)
        (xy -11.705 -2.912)
        (xy -11.719 -2.894)
        (xy -11.734 -2.876)
        (xy -11.75 -2.859)
        (xy -11.767 -2.843)
        (xy -11.785 -2.829)
        (xy -11.804 -2.814)
        (xy -11.824 -2.801)
        (xy -11.843 -2.789)
        (xy -11.863 -2.778)
        (xy -11.885 -2.767)
        (xy -11.907 -2.759)
        (xy -11.927 -2.751)
        (xy -11.95 -2.745)
        (xy -11.972 -2.74)
        (xy -11.995 -2.734)
        (xy -12.019 -2.732)
        (xy -12.042 -2.73)
        (xy -12.065 -2.729)
        (xy -12.09 -2.73)
        (xy -12.113 -2.732)
        (xy -12.136 -2.734)
        (xy -12.16 -2.74)
        (xy -12.181 -2.745)
        (xy -12.203 -2.751)
        (xy -12.225 -2.758)
        (xy -12.247 -2.767)
        (xy -12.269 -2.777)
        (xy -12.288 -2.789)
        (xy -12.308 -2.801)
        (xy -12.327 -2.814)
        (xy -12.346 -2.829)
        (xy -12.363 -2.843)
        (xy -12.381 -2.859)
        (xy -12.397 -2.876)
        (xy -12.411 -2.894)
        (xy -12.426 -2.912)
        (xy -12.439 -2.931)
        (xy -12.452 -2.951)
        (xy -12.462 -2.971)
        (xy -12.472 -2.992)
        (xy -12.481 -3.015)
        (xy -12.488 -3.036)
        (xy -12.495 -3.059)
        (xy -12.5 -3.08)
        (xy -12.506 -3.104)
        (xy -12.508 -3.126)
        (xy -12.51 -3.15)
        (xy -12.51 -3.172)
        (xy -12.065 -3.172)
        (xy -12.065 -3.177)
      )

      (stroke (width 0.001) (type solid)) (fill solid) (layer "B.Paste"))
    (fp_poly
      (pts
        (xy -12.065 1.903)
        (xy -12.51 1.903)
        (xy -12.51 1.881)
        (xy -12.508 1.857)
        (xy -12.506 1.835)
        (xy -12.5 1.811)
        (xy -12.495 1.789)
        (xy -12.488 1.767)
        (xy -12.481 1.746)
        (xy -12.472 1.724)
        (xy -12.462 1.702)
        (xy -12.452 1.682)
        (xy -12.439 1.662)
        (xy -12.426 1.643)
        (xy -12.411 1.625)
        (xy -12.397 1.607)
        (xy -12.381 1.591)
        (xy -12.363 1.575)
        (xy -12.346 1.559)
        (xy -12.327 1.545)
        (xy -12.308 1.532)
        (xy -12.288 1.519)
        (xy -12.269 1.508)
        (xy -12.247 1.498)
        (xy -12.225 1.49)
        (xy -12.203 1.482)
        (xy -12.181 1.476)
        (xy -12.16 1.47)
        (xy -12.136 1.466)
        (xy -12.113 1.462)
        (xy -12.09 1.462)
        (xy -12.065 1.46)
        (xy -12.042 1.462)
        (xy -12.019 1.462)
        (xy -11.995 1.466)
        (xy -11.972 1.47)
        (xy -11.95 1.476)
        (xy -11.927 1.482)
        (xy -11.907 1.49)
        (xy -11.885 1.498)
        (xy -11.863 1.509)
        (xy -11.843 1.52)
        (xy -11.824 1.532)
        (xy -11.804 1.545)
        (xy -11.785 1.559)
        (xy -11.767 1.575)
        (xy -11.75 1.591)
        (xy -11.734 1.607)
        (xy -11.719 1.625)
        (xy -11.705 1.643)
        (xy -11.692 1.663)
        (xy -11.68 1.684)
        (xy -11.67 1.704)
        (xy -11.658 1.724)
        (xy -11.651 1.746)
        (xy -11.642 1.767)
        (xy -11.635 1.79)
        (xy -11.631 1.813)
        (xy -11.625 1.835)
        (xy -11.622 1.859)
        (xy -11.622 1.882)
        (xy -11.62 1.905)
        (xy -11.622 1.928)
        (xy -11.622 1.952)
        (xy -11.625 1.976)
        (xy -11.631 1.998)
        (xy -11.635 2.02)
        (xy -11.642 2.044)
        (xy -11.651 2.065)
        (xy -11.658 2.086)
        (xy -11.67 2.108)
        (xy -11.68 2.127)
        (xy -11.692 2.147)
        (xy -11.705 2.167)
        (xy -11.719 2.186)
        (xy -11.734 2.203)
        (xy -11.75 2.221)
        (xy -11.767 2.237)
        (xy -11.785 2.251)
        (xy -11.804 2.266)
        (xy -11.824 2.278)
        (xy -11.843 2.29)
        (xy -11.863 2.302)
        (xy -11.885 2.312)
        (xy -11.907 2.32)
        (xy -11.927 2.328)
        (xy -11.95 2.335)
        (xy -11.972 2.34)
        (xy -11.995 2.346)
        (xy -12.019 2.348)
        (xy -12.042 2.35)
        (xy -12.065 2.351)
        (xy -12.09 2.35)
        (xy -12.113 2.348)
        (xy -12.136 2.346)
        (xy -12.16 2.34)
        (xy -12.181 2.335)
        (xy -12.203 2.328)
        (xy -12.225 2.322)
        (xy -12.247 2.312)
        (xy -12.269 2.302)
        (xy -12.288 2.291)
        (xy -12.308 2.278)
        (xy -12.327 2.266)
        (xy -12.346 2.251)
        (xy -12.363 2.237)
        (xy -12.381 2.221)
        (xy -12.397 2.203)
        (xy -12.411 2.186)
        (xy -12.426 2.167)
        (xy -12.439 2.149)
        (xy -12.452 2.129)
        (xy -12.462 2.109)
        (xy -12.472 2.088)
        (xy -12.481 2.065)
        (xy -12.488 2.044)
        (xy -12.495 2.021)
        (xy -12.5 2)
        (xy -12.506 1.976)
        (xy -12.508 1.954)
        (xy -12.51 1.93)
        (xy -12.51 1.907)
        (xy -12.065 1.907)
        (xy -12.065 1.903)
      )

      (stroke (width 0.001) (type solid)) (fill solid) (layer "B.Paste"))
    (fp_poly
      (pts
        (xy -12.065 3.173)
        (xy -12.51 3.173)
        (xy -12.51 3.151)
        (xy -12.508 3.127)
        (xy -12.506 3.105)
        (xy -12.5 3.081)
        (xy -12.495 3.06)
        (xy -12.488 3.037)
        (xy -12.481 3.016)
        (xy -12.472 2.993)
        (xy -12.462 2.972)
        (xy -12.452 2.952)
        (xy -12.439 2.932)
        (xy -12.426 2.913)
        (xy -12.411 2.895)
        (xy -12.397 2.877)
        (xy -12.381 2.86)
        (xy -12.363 2.844)
        (xy -12.346 2.83)
        (xy -12.327 2.815)
        (xy -12.308 2.802)
        (xy -12.288 2.79)
        (xy -12.269 2.778)
        (xy -12.247 2.768)
        (xy -12.225 2.759)
        (xy -12.203 2.752)
        (xy -12.181 2.746)
        (xy -12.16 2.741)
        (xy -12.136 2.735)
        (xy -12.113 2.733)
        (xy -12.09 2.731)
        (xy -12.065 2.73)
        (xy -12.042 2.731)
        (xy -12.019 2.733)
        (xy -11.995 2.735)
        (xy -11.972 2.741)
        (xy -11.95 2.746)
        (xy -11.927 2.752)
        (xy -11.907 2.76)
        (xy -11.885 2.768)
        (xy -11.863 2.779)
        (xy -11.843 2.79)
        (xy -11.824 2.802)
        (xy -11.804 2.815)
        (xy -11.785 2.83)
        (xy -11.767 2.844)
        (xy -11.75 2.86)
        (xy -11.734 2.877)
        (xy -11.719 2.895)
        (xy -11.705 2.913)
        (xy -11.692 2.933)
        (xy -11.68 2.952)
        (xy -11.67 2.973)
        (xy -11.658 2.995)
        (xy -11.651 3.016)
        (xy -11.642 3.037)
        (xy -11.635 3.06)
        (xy -11.631 3.082)
        (xy -11.625 3.105)
        (xy -11.622 3.129)
        (xy -11.622 3.153)
        (xy -11.62 3.175)
        (xy -11.622 3.198)
        (xy -11.622 3.222)
        (xy -11.625 3.246)
        (xy -11.631 3.268)
        (xy -11.635 3.29)
        (xy -11.642 3.314)
        (xy -11.651 3.335)
        (xy -11.658 3.356)
        (xy -11.67 3.377)
        (xy -11.68 3.397)
        (xy -11.692 3.417)
        (xy -11.705 3.437)
        (xy -11.719 3.455)
        (xy -11.734 3.473)
        (xy -11.75 3.491)
        (xy -11.767 3.506)
        (xy -11.785 3.521)
        (xy -11.804 3.536)
        (xy -11.824 3.548)
        (xy -11.843 3.56)
        (xy -11.863 3.572)
        (xy -11.885 3.582)
        (xy -11.907 3.59)
        (xy -11.927 3.598)
        (xy -11.95 3.605)
        (xy -11.972 3.61)
        (xy -11.995 3.616)
        (xy -12.019 3.618)
        (xy -12.042 3.62)
        (xy -12.065 3.621)
        (xy -12.09 3.62)
        (xy -12.113 3.618)
        (xy -12.136 3.616)
        (xy -12.16 3.61)
        (xy -12.181 3.605)
        (xy -12.203 3.598)
        (xy -12.225 3.592)
        (xy -12.247 3.582)
        (xy -12.269 3.572)
        (xy -12.288 3.561)
        (xy -12.308 3.548)
        (xy -12.327 3.536)
        (xy -12.346 3.521)
        (xy -12.363 3.506)
        (xy -12.381 3.491)
        (xy -12.397 3.473)
        (xy -12.411 3.456)
        (xy -12.426 3.437)
        (xy -12.439 3.419)
        (xy -12.452 3.399)
        (xy -12.462 3.379)
        (xy -12.472 3.358)
        (xy -12.481 3.335)
        (xy -12.488 3.314)
        (xy -12.495 3.291)
        (xy -12.5 3.27)
        (xy -12.506 3.246)
        (xy -12.508 3.223)
        (xy -12.51 3.199)
        (xy -12.51 3.178)
        (xy -12.065 3.178)
        (xy -12.065 3.173)
      )

      (stroke (width 0.001) (type solid)) (fill solid) (layer "B.Paste"))
    (fp_poly
      (pts
        (xy -12.065 4.443)
        (xy -12.51 4.443)
        (xy -12.51 4.422)
        (xy -12.508 4.398)
        (xy -12.506 4.374)
        (xy -12.5 4.351)
        (xy -12.495 4.329)
        (xy -12.488 4.308)
        (xy -12.481 4.286)
        (xy -12.472 4.263)
        (xy -12.462 4.242)
        (xy -12.452 4.223)
        (xy -12.439 4.202)
        (xy -12.426 4.183)
        (xy -12.411 4.164)
        (xy -12.397 4.148)
        (xy -12.381 4.13)
        (xy -12.363 4.114)
        (xy -12.346 4.1)
        (xy -12.327 4.085)
        (xy -12.308 4.072)
        (xy -12.288 4.06)
        (xy -12.269 4.048)
        (xy -12.247 4.039)
        (xy -12.225 4.029)
        (xy -12.203 4.023)
        (xy -12.181 4.015)
        (xy -12.16 4.01)
        (xy -12.136 4.005)
        (xy -12.113 4.002)
        (xy -12.09 4.002)
        (xy -12.065 4)
        (xy -12.042 4.002)
        (xy -12.019 4.002)
        (xy -11.995 4.005)
        (xy -11.972 4.01)
        (xy -11.95 4.015)
        (xy -11.927 4.023)
        (xy -11.907 4.031)
        (xy -11.885 4.039)
        (xy -11.863 4.05)
        (xy -11.843 4.06)
        (xy -11.824 4.072)
        (xy -11.804 4.085)
        (xy -11.785 4.1)
        (xy -11.767 4.114)
        (xy -11.75 4.13)
        (xy -11.734 4.148)
        (xy -11.719 4.165)
        (xy -11.705 4.183)
        (xy -11.692 4.204)
        (xy -11.68 4.223)
        (xy -11.67 4.244)
        (xy -11.658 4.265)
        (xy -11.651 4.286)
        (xy -11.642 4.308)
        (xy -11.635 4.33)
        (xy -11.631 4.353)
        (xy -11.625 4.375)
        (xy -11.622 4.398)
        (xy -11.622 4.422)
        (xy -11.62 4.446)
        (xy -11.622 4.468)
        (xy -11.622 4.492)
        (xy -11.625 4.515)
        (xy -11.631 4.539)
        (xy -11.635 4.56)
        (xy -11.642 4.584)
        (xy -11.651 4.604)
        (xy -11.658 4.627)
        (xy -11.67 4.648)
        (xy -11.68 4.669)
        (xy -11.692 4.688)
        (xy -11.705 4.707)
        (xy -11.719 4.725)
        (xy -11.734 4.744)
        (xy -11.75 4.76)
        (xy -11.767 4.776)
        (xy -11.785 4.792)
        (xy -11.804 4.805)
        (xy -11.824 4.818)
        (xy -11.843 4.83)
        (xy -11.863 4.842)
        (xy -11.885 4.853)
        (xy -11.907 4.861)
        (xy -11.927 4.869)
        (xy -11.95 4.875)
        (xy -11.972 4.88)
        (xy -11.995 4.885)
        (xy -12.019 4.888)
        (xy -12.042 4.89)
        (xy -12.065 4.89)
        (xy -12.09 4.89)
        (xy -12.113 4.888)
        (xy -12.136 4.885)
        (xy -12.16 4.88)
        (xy -12.181 4.875)
        (xy -12.203 4.869)
        (xy -12.225 4.861)
        (xy -12.247 4.853)
        (xy -12.269 4.842)
        (xy -12.288 4.832)
        (xy -12.308 4.818)
        (xy -12.327 4.805)
        (xy -12.346 4.792)
        (xy -12.363 4.776)
        (xy -12.381 4.76)
        (xy -12.397 4.744)
        (xy -12.411 4.726)
        (xy -12.426 4.707)
        (xy -12.439 4.688)
        (xy -12.452 4.669)
        (xy -12.462 4.648)
        (xy -12.472 4.627)
        (xy -12.481 4.606)
        (xy -12.488 4.584)
        (xy -12.495 4.561)
        (xy -12.5 4.539)
        (xy -12.506 4.516)
        (xy -12.508 4.494)
        (xy -12.51 4.47)
        (xy -12.51 4.447)
        (xy -12.065 4.447)
        (xy -12.065 4.443)
      )

      (stroke (width 0.001) (type solid)) (fill solid) (layer "B.Paste"))
    (fp_poly
      (pts
        (xy -12.065 5.713)
        (xy -12.51 5.713)
        (xy -12.51 5.691)
        (xy -12.508 5.667)
        (xy -12.506 5.645)
        (xy -12.5 5.622)
        (xy -12.495 5.6)
        (xy -12.488 5.577)
        (xy -12.481 5.555)
        (xy -12.472 5.534)
        (xy -12.462 5.512)
        (xy -12.452 5.492)
        (xy -12.439 5.473)
        (xy -12.426 5.454)
        (xy -12.411 5.435)
        (xy -12.397 5.417)
        (xy -12.381 5.401)
        (xy -12.363 5.385)
        (xy -12.346 5.369)
        (xy -12.327 5.356)
        (xy -12.308 5.342)
        (xy -12.288 5.329)
        (xy -12.269 5.318)
        (xy -12.247 5.308)
        (xy -12.225 5.3)
        (xy -12.203 5.292)
        (xy -12.181 5.286)
        (xy -12.16 5.281)
        (xy -12.136 5.276)
        (xy -12.113 5.273)
        (xy -12.09 5.271)
        (xy -12.065 5.27)
        (xy -12.042 5.271)
        (xy -12.019 5.273)
        (xy -11.995 5.276)
        (xy -11.972 5.281)
        (xy -11.95 5.286)
        (xy -11.927 5.292)
        (xy -11.907 5.3)
        (xy -11.885 5.308)
        (xy -11.863 5.319)
        (xy -11.843 5.33)
        (xy -11.824 5.342)
        (xy -11.804 5.356)
        (xy -11.785 5.369)
        (xy -11.767 5.385)
        (xy -11.75 5.401)
        (xy -11.734 5.417)
        (xy -11.719 5.435)
        (xy -11.705 5.454)
        (xy -11.692 5.473)
        (xy -11.68 5.492)
        (xy -11.67 5.513)
        (xy -11.658 5.534)
        (xy -11.651 5.556)
        (xy -11.642 5.577)
        (xy -11.635 5.6)
        (xy -11.631 5.622)
        (xy -11.625 5.645)
        (xy -11.622 5.669)
        (xy -11.622 5.693)
        (xy -11.62 5.715)
        (xy -11.622 5.739)
        (xy -11.622 5.762)
        (xy -11.625 5.786)
        (xy -11.631 5.808)
        (xy -11.635 5.83)
        (xy -11.642 5.853)
        (xy -11.651 5.874)
        (xy -11.658 5.896)
        (xy -11.67 5.917)
        (xy -11.68 5.938)
        (xy -11.692 5.957)
        (xy -11.705 5.978)
        (xy -11.719 5.995)
        (xy -11.734 6.013)
        (xy -11.75 6.031)
        (xy -11.767 6.047)
        (xy -11.785 6.061)
        (xy -11.804 6.076)
        (xy -11.824 6.088)
        (xy -11.843 6.1)
        (xy -11.863 6.111)
        (xy -11.885 6.122)
        (xy -11.907 6.13)
        (xy -11.927 6.138)
        (xy -11.95 6.145)
        (xy -11.972 6.151)
        (xy -11.995 6.156)
        (xy -12.019 6.159)
        (xy -12.042 6.159)
        (xy -12.065 6.161)
        (xy -12.09 6.159)
        (xy -12.113 6.159)
        (xy -12.136 6.156)
        (xy -12.16 6.151)
        (xy -12.181 6.145)
        (xy -12.203 6.138)
        (xy -12.225 6.132)
        (xy -12.247 6.122)
        (xy -12.269 6.112)
        (xy -12.288 6.101)
        (xy -12.308 6.088)
        (xy -12.327 6.076)
        (xy -12.346 6.061)
        (xy -12.363 6.047)
        (xy -12.381 6.031)
        (xy -12.397 6.013)
        (xy -12.411 5.997)
        (xy -12.426 5.978)
        (xy -12.439 5.959)
        (xy -12.452 5.938)
        (xy -12.462 5.919)
        (xy -12.472 5.898)
        (xy -12.481 5.875)
        (xy -12.488 5.853)
        (xy -12.495 5.832)
        (xy -12.5 5.81)
        (xy -12.506 5.786)
        (xy -12.508 5.763)
        (xy -12.51 5.739)
        (xy -12.51 5.718)
        (xy -12.065 5.718)
        (xy -12.065 5.713)
      )

      (stroke (width 0.001) (type solid)) (fill solid) (layer "B.Paste"))
    (fp_poly
      (pts
        (xy -10.795 -5.717)
        (xy -11.24 -5.717)
        (xy -11.24 -5.738)
        (xy -11.238 -5.762)
        (xy -11.235 -5.785)
        (xy -11.231 -5.809)
        (xy -11.225 -5.831)
        (xy -11.218 -5.852)
        (xy -11.212 -5.874)
        (xy -11.202 -5.897)
        (xy -11.192 -5.918)
        (xy -11.181 -5.937)
        (xy -11.168 -5.958)
        (xy -11.155 -5.977)
        (xy -11.141 -5.996)
        (xy -11.126 -6.012)
        (xy -11.11 -6.03)
        (xy -11.093 -6.046)
        (xy -11.077 -6.06)
        (xy -11.058 -6.075)
        (xy -11.039 -6.087)
        (xy -11.019 -6.1)
        (xy -10.998 -6.111)
        (xy -10.978 -6.121)
        (xy -10.955 -6.131)
        (xy -10.933 -6.137)
        (xy -10.911 -6.144)
        (xy -10.889 -6.15)
        (xy -10.866 -6.155)
        (xy -10.843 -6.158)
        (xy -10.82 -6.158)
        (xy -10.795 -6.16)
        (xy -10.773 -6.158)
        (xy -10.748 -6.158)
        (xy -10.725 -6.155)
        (xy -10.702 -6.15)
        (xy -10.68 -6.144)
        (xy -10.657 -6.137)
        (xy -10.636 -6.129)
        (xy -10.615 -6.121)
        (xy -10.593 -6.11)
        (xy -10.572 -6.099)
        (xy -10.554 -6.087)
        (xy -10.533 -6.075)
        (xy -10.516 -6.06)
        (xy -10.497 -6.046)
        (xy -10.481 -6.03)
        (xy -10.465 -6.012)
        (xy -10.449 -5.994)
        (xy -10.436 -5.977)
        (xy -10.423 -5.956)
        (xy -10.41 -5.937)
        (xy -10.399 -5.916)
        (xy -10.388 -5.895)
        (xy -10.381 -5.873)
        (xy -10.372 -5.852)
        (xy -10.365 -5.829)
        (xy -10.36 -5.807)
        (xy -10.356 -5.785)
        (xy -10.353 -5.761)
        (xy -10.352 -5.738)
        (xy -10.35 -5.714)
        (xy -10.352 -5.692)
        (xy -10.353 -5.668)
        (xy -10.356 -5.644)
        (xy -10.36 -5.621)
        (xy -10.365 -5.599)
        (xy -10.372 -5.576)
        (xy -10.381 -5.555)
        (xy -10.388 -5.533)
        (xy -10.399 -5.512)
        (xy -10.41 -5.491)
        (xy -10.423 -5.472)
        (xy -10.436 -5.453)
        (xy -10.449 -5.434)
        (xy -10.465 -5.416)
        (xy -10.481 -5.4)
        (xy -10.497 -5.384)
        (xy -10.516 -5.368)
        (xy -10.533 -5.355)
        (xy -10.554 -5.341)
        (xy -10.572 -5.329)
        (xy -10.593 -5.318)
        (xy -10.615 -5.307)
        (xy -10.636 -5.299)
        (xy -10.657 -5.291)
        (xy -10.68 -5.285)
        (xy -10.702 -5.28)
        (xy -10.725 -5.275)
        (xy -10.748 -5.272)
        (xy -10.773 -5.27)
        (xy -10.795 -5.269)
        (xy -10.82 -5.27)
        (xy -10.843 -5.272)
        (xy -10.866 -5.275)
        (xy -10.889 -5.28)
        (xy -10.911 -5.285)
        (xy -10.933 -5.291)
        (xy -10.955 -5.299)
        (xy -10.978 -5.307)
        (xy -10.998 -5.317)
        (xy -11.019 -5.328)
        (xy -11.039 -5.341)
        (xy -11.058 -5.355)
        (xy -11.077 -5.368)
        (xy -11.093 -5.384)
        (xy -11.11 -5.4)
        (xy -11.126 -5.416)
        (xy -11.141 -5.434)
        (xy -11.155 -5.453)
        (xy -11.168 -5.472)
        (xy -11.181 -5.491)
        (xy -11.192 -5.511)
        (xy -11.202 -5.533)
        (xy -11.212 -5.554)
        (xy -11.218 -5.576)
        (xy -11.225 -5.599)
        (xy -11.231 -5.621)
        (xy -11.235 -5.644)
        (xy -11.238 -5.666)
        (xy -11.24 -5.69)
        (xy -11.24 -5.712)
        (xy -10.795 -5.712)
        (xy -10.795 -5.717)
      )

      (stroke (width 0.001) (type solid)) (fill solid) (layer "B.Paste"))
    (fp_poly
      (pts
        (xy -10.795 -3.177)
        (xy -11.24 -3.177)
        (xy -11.24 -3.198)
        (xy -11.238 -3.222)
        (xy -11.235 -3.245)
        (xy -11.231 -3.269)
        (xy -11.225 -3.29)
        (xy -11.218 -3.313)
        (xy -11.212 -3.334)
        (xy -11.202 -3.357)
        (xy -11.192 -3.378)
        (xy -11.181 -3.398)
        (xy -11.168 -3.418)
        (xy -11.155 -3.436)
        (xy -11.141 -3.455)
        (xy -11.126 -3.472)
        (xy -11.11 -3.49)
        (xy -11.093 -3.505)
        (xy -11.077 -3.52)
        (xy -11.058 -3.535)
        (xy -11.039 -3.547)
        (xy -11.019 -3.56)
        (xy -10.998 -3.571)
        (xy -10.978 -3.581)
        (xy -10.955 -3.591)
        (xy -10.933 -3.597)
        (xy -10.911 -3.604)
        (xy -10.889 -3.609)
        (xy -10.866 -3.615)
        (xy -10.843 -3.617)
        (xy -10.82 -3.619)
        (xy -10.795 -3.62)
        (xy -10.773 -3.619)
        (xy -10.748 -3.617)
        (xy -10.725 -3.615)
        (xy -10.702 -3.609)
        (xy -10.68 -3.604)
        (xy -10.657 -3.597)
        (xy -10.636 -3.589)
        (xy -10.615 -3.581)
        (xy -10.593 -3.571)
        (xy -10.572 -3.559)
        (xy -10.554 -3.547)
        (xy -10.533 -3.535)
        (xy -10.516 -3.52)
        (xy -10.497 -3.505)
        (xy -10.481 -3.49)
        (xy -10.465 -3.472)
        (xy -10.449 -3.454)
        (xy -10.436 -3.436)
        (xy -10.423 -3.416)
        (xy -10.41 -3.396)
        (xy -10.399 -3.376)
        (xy -10.388 -3.355)
        (xy -10.381 -3.334)
        (xy -10.372 -3.313)
        (xy -10.365 -3.289)
        (xy -10.36 -3.267)
        (xy -10.356 -3.245)
        (xy -10.353 -3.221)
        (xy -10.352 -3.197)
        (xy -10.35 -3.174)
        (xy -10.352 -3.152)
        (xy -10.353 -3.128)
        (xy -10.356 -3.104)
        (xy -10.36 -3.081)
        (xy -10.365 -3.059)
        (xy -10.372 -3.036)
        (xy -10.381 -3.015)
        (xy -10.388 -2.994)
        (xy -10.399 -2.972)
        (xy -10.41 -2.951)
        (xy -10.423 -2.932)
        (xy -10.436 -2.912)
        (xy -10.449 -2.894)
        (xy -10.465 -2.876)
        (xy -10.481 -2.859)
        (xy -10.497 -2.843)
        (xy -10.516 -2.829)
        (xy -10.533 -2.814)
        (xy -10.554 -2.801)
        (xy -10.572 -2.789)
        (xy -10.593 -2.778)
        (xy -10.615 -2.767)
        (xy -10.636 -2.759)
        (xy -10.657 -2.751)
        (xy -10.68 -2.745)
        (xy -10.702 -2.74)
        (xy -10.725 -2.734)
        (xy -10.748 -2.732)
        (xy -10.773 -2.73)
        (xy -10.795 -2.729)
        (xy -10.82 -2.73)
        (xy -10.843 -2.732)
        (xy -10.866 -2.734)
        (xy -10.889 -2.74)
        (xy -10.911 -2.745)
        (xy -10.933 -2.751)
        (xy -10.955 -2.758)
        (xy -10.978 -2.767)
        (xy -10.998 -2.777)
        (xy -11.019 -2.789)
        (xy -11.039 -2.801)
        (xy -11.058 -2.814)
        (xy -11.077 -2.829)
        (xy -11.093 -2.843)
        (xy -11.11 -2.859)
        (xy -11.126 -2.876)
        (xy -11.141 -2.894)
        (xy -11.155 -2.912)
        (xy -11.168 -2.931)
        (xy -11.181 -2.951)
        (xy -11.192 -2.971)
        (xy -11.202 -2.992)
        (xy -11.212 -3.015)
        (xy -11.218 -3.036)
        (xy -11.225 -3.059)
        (xy -11.231 -3.08)
        (xy -11.235 -3.104)
        (xy -11.238 -3.126)
        (xy -11.24 -3.15)
        (xy -11.24 -3.172)
        (xy -10.795 -3.172)
        (xy -10.795 -3.177)
      )

      (stroke (width 0.001) (type solid)) (fill solid) (layer "B.Paste"))
    (fp_poly
      (pts
        (xy -10.795 1.903)
        (xy -11.24 1.903)
        (xy -11.24 1.881)
        (xy -11.238 1.857)
        (xy -11.235 1.835)
        (xy -11.231 1.811)
        (xy -11.225 1.789)
        (xy -11.218 1.767)
        (xy -11.212 1.746)
        (xy -11.202 1.724)
        (xy -11.192 1.702)
        (xy -11.181 1.682)
        (xy -11.168 1.662)
        (xy -11.155 1.643)
        (xy -11.141 1.625)
        (xy -11.126 1.607)
        (xy -11.11 1.591)
        (xy -11.093 1.575)
        (xy -11.077 1.559)
        (xy -11.058 1.545)
        (xy -11.039 1.532)
        (xy -11.019 1.519)
        (xy -10.998 1.508)
        (xy -10.978 1.498)
        (xy -10.955 1.49)
        (xy -10.933 1.482)
        (xy -10.911 1.476)
        (xy -10.889 1.47)
        (xy -10.866 1.466)
        (xy -10.843 1.462)
        (xy -10.82 1.462)
        (xy -10.795 1.46)
        (xy -10.773 1.462)
        (xy -10.748 1.462)
        (xy -10.725 1.466)
        (xy -10.702 1.47)
        (xy -10.68 1.476)
        (xy -10.657 1.482)
        (xy -10.636 1.49)
        (xy -10.615 1.498)
        (xy -10.593 1.509)
        (xy -10.572 1.52)
        (xy -10.554 1.532)
        (xy -10.533 1.545)
        (xy -10.516 1.559)
        (xy -10.497 1.575)
        (xy -10.481 1.591)
        (xy -10.465 1.607)
        (xy -10.449 1.625)
        (xy -10.436 1.643)
        (xy -10.423 1.663)
        (xy -10.41 1.684)
        (xy -10.399 1.704)
        (xy -10.388 1.724)
        (xy -10.381 1.746)
        (xy -10.372 1.767)
        (xy -10.365 1.79)
        (xy -10.36 1.813)
        (xy -10.356 1.835)
        (xy -10.353 1.859)
        (xy -10.352 1.882)
        (xy -10.35 1.905)
        (xy -10.352 1.928)
        (xy -10.353 1.952)
        (xy -10.356 1.976)
        (xy -10.36 1.998)
        (xy -10.365 2.02)
        (xy -10.372 2.044)
        (xy -10.381 2.065)
        (xy -10.388 2.086)
        (xy -10.399 2.108)
        (xy -10.41 2.127)
        (xy -10.423 2.147)
        (xy -10.436 2.167)
        (xy -10.449 2.186)
        (xy -10.465 2.203)
        (xy -10.481 2.221)
        (xy -10.497 2.237)
        (xy -10.516 2.251)
        (xy -10.533 2.266)
        (xy -10.554 2.278)
        (xy -10.572 2.29)
        (xy -10.593 2.302)
        (xy -10.615 2.312)
        (xy -10.636 2.32)
        (xy -10.657 2.328)
        (xy -10.68 2.335)
        (xy -10.702 2.34)
        (xy -10.725 2.346)
        (xy -10.748 2.348)
        (xy -10.773 2.35)
        (xy -10.795 2.351)
        (xy -10.82 2.35)
        (xy -10.843 2.348)
        (xy -10.866 2.346)
        (xy -10.889 2.34)
        (xy -10.911 2.335)
        (xy -10.933 2.328)
        (xy -10.955 2.322)
        (xy -10.978 2.312)
        (xy -10.998 2.302)
        (xy -11.019 2.291)
        (xy -11.039 2.278)
        (xy -11.058 2.266)
        (xy -11.077 2.251)
        (xy -11.093 2.237)
        (xy -11.11 2.221)
        (xy -11.126 2.203)
        (xy -11.141 2.186)
        (xy -11.155 2.167)
        (xy -11.168 2.149)
        (xy -11.181 2.129)
        (xy -11.192 2.109)
        (xy -11.202 2.088)
        (xy -11.212 2.065)
        (xy -11.218 2.044)
        (xy -11.225 2.021)
        (xy -11.231 2)
        (xy -11.235 1.976)
        (xy -11.238 1.954)
        (xy -11.24 1.93)
        (xy -11.24 1.907)
        (xy -10.795 1.907)
        (xy -10.795 1.903)
      )

      (stroke (width 0.001) (type solid)) (fill solid) (layer "B.Paste"))
    (fp_poly
      (pts
        (xy -10.795 3.173)
        (xy -11.24 3.173)
        (xy -11.24 3.151)
        (xy -11.238 3.127)
        (xy -11.235 3.105)
        (xy -11.231 3.081)
        (xy -11.225 3.06)
        (xy -11.218 3.037)
        (xy -11.212 3.016)
        (xy -11.202 2.993)
        (xy -11.192 2.972)
        (xy -11.181 2.952)
        (xy -11.168 2.932)
        (xy -11.155 2.913)
        (xy -11.141 2.895)
        (xy -11.126 2.877)
        (xy -11.11 2.86)
        (xy -11.093 2.844)
        (xy -11.077 2.83)
        (xy -11.058 2.815)
        (xy -11.039 2.802)
        (xy -11.019 2.79)
        (xy -10.998 2.778)
        (xy -10.978 2.768)
        (xy -10.955 2.759)
        (xy -10.933 2.752)
        (xy -10.911 2.746)
        (xy -10.889 2.741)
        (xy -10.866 2.735)
        (xy -10.843 2.733)
        (xy -10.82 2.731)
        (xy -10.795 2.73)
        (xy -10.773 2.731)
        (xy -10.748 2.733)
        (xy -10.725 2.735)
        (xy -10.702 2.741)
        (xy -10.68 2.746)
        (xy -10.657 2.752)
        (xy -10.636 2.76)
        (xy -10.615 2.768)
        (xy -10.593 2.779)
        (xy -10.572 2.79)
        (xy -10.554 2.802)
        (xy -10.533 2.815)
        (xy -10.516 2.83)
        (xy -10.497 2.844)
        (xy -10.481 2.86)
        (xy -10.465 2.877)
        (xy -10.449 2.895)
        (xy -10.436 2.913)
        (xy -10.423 2.933)
        (xy -10.41 2.952)
        (xy -10.399 2.973)
        (xy -10.388 2.995)
        (xy -10.381 3.016)
        (xy -10.372 3.037)
        (xy -10.365 3.06)
        (xy -10.36 3.082)
        (xy -10.356 3.105)
        (xy -10.353 3.129)
        (xy -10.352 3.153)
        (xy -10.35 3.175)
        (xy -10.352 3.198)
        (xy -10.353 3.222)
        (xy -10.356 3.246)
        (xy -10.36 3.268)
        (xy -10.365 3.29)
        (xy -10.372 3.314)
        (xy -10.381 3.335)
        (xy -10.388 3.356)
        (xy -10.399 3.377)
        (xy -10.41 3.397)
        (xy -10.423 3.417)
        (xy -10.436 3.437)
        (xy -10.449 3.455)
        (xy -10.465 3.473)
        (xy -10.481 3.491)
        (xy -10.497 3.506)
        (xy -10.516 3.521)
        (xy -10.533 3.536)
        (xy -10.554 3.548)
        (xy -10.572 3.56)
        (xy -10.593 3.572)
        (xy -10.615 3.582)
        (xy -10.636 3.59)
        (xy -10.657 3.598)
        (xy -10.68 3.605)
        (xy -10.702 3.61)
        (xy -10.725 3.616)
        (xy -10.748 3.618)
        (xy -10.773 3.62)
        (xy -10.795 3.621)
        (xy -10.82 3.62)
        (xy -10.843 3.618)
        (xy -10.866 3.616)
        (xy -10.889 3.61)
        (xy -10.911 3.605)
        (xy -10.933 3.598)
        (xy -10.955 3.592)
        (xy -10.978 3.582)
        (xy -10.998 3.572)
        (xy -11.019 3.561)
        (xy -11.039 3.548)
        (xy -11.058 3.536)
        (xy -11.077 3.521)
        (xy -11.093 3.506)
        (xy -11.11 3.491)
        (xy -11.126 3.473)
        (xy -11.141 3.456)
        (xy -11.155 3.437)
        (xy -11.168 3.419)
        (xy -11.181 3.399)
        (xy -11.192 3.379)
        (xy -11.202 3.358)
        (xy -11.212 3.335)
        (xy -11.218 3.314)
        (xy -11.225 3.291)
        (xy -11.231 3.27)
        (xy -11.235 3.246)
        (xy -11.238 3.223)
        (xy -11.24 3.199)
        (xy -11.24 3.178)
        (xy -10.795 3.178)
        (xy -10.795 3.173)
      )

      (stroke (width 0.001) (type solid)) (fill solid) (layer "B.Paste"))
    (fp_poly
      (pts
        (xy -10.795 4.443)
        (xy -11.24 4.443)
        (xy -11.24 4.422)
        (xy -11.238 4.398)
        (xy -11.235 4.374)
        (xy -11.231 4.351)
        (xy -11.225 4.329)
        (xy -11.218 4.308)
        (xy -11.212 4.286)
        (xy -11.202 4.263)
        (xy -11.192 4.242)
        (xy -11.181 4.223)
        (xy -11.168 4.202)
        (xy -11.155 4.183)
        (xy -11.141 4.164)
        (xy -11.126 4.148)
        (xy -11.11 4.13)
        (xy -11.093 4.114)
        (xy -11.077 4.1)
        (xy -11.058 4.085)
        (xy -11.039 4.072)
        (xy -11.019 4.06)
        (xy -10.998 4.048)
        (xy -10.978 4.039)
        (xy -10.955 4.029)
        (xy -10.933 4.023)
        (xy -10.911 4.015)
        (xy -10.889 4.01)
        (xy -10.866 4.005)
        (xy -10.843 4.002)
        (xy -10.82 4.002)
        (xy -10.795 4)
        (xy -10.773 4.002)
        (xy -10.748 4.002)
        (xy -10.725 4.005)
        (xy -10.702 4.01)
        (xy -10.68 4.015)
        (xy -10.657 4.023)
        (xy -10.636 4.031)
        (xy -10.615 4.039)
        (xy -10.593 4.05)
        (xy -10.572 4.06)
        (xy -10.554 4.072)
        (xy -10.533 4.085)
        (xy -10.516 4.1)
        (xy -10.497 4.114)
        (xy -10.481 4.13)
        (xy -10.465 4.148)
        (xy -10.449 4.165)
        (xy -10.436 4.183)
        (xy -10.423 4.204)
        (xy -10.41 4.223)
        (xy -10.399 4.244)
        (xy -10.388 4.265)
        (xy -10.381 4.286)
        (xy -10.372 4.308)
        (xy -10.365 4.33)
        (xy -10.36 4.353)
        (xy -10.356 4.375)
        (xy -10.353 4.398)
        (xy -10.352 4.422)
        (xy -10.35 4.446)
        (xy -10.352 4.468)
        (xy -10.353 4.492)
        (xy -10.356 4.515)
        (xy -10.36 4.539)
        (xy -10.365 4.56)
        (xy -10.372 4.584)
        (xy -10.381 4.604)
        (xy -10.388 4.627)
        (xy -10.399 4.648)
        (xy -10.41 4.669)
        (xy -10.423 4.688)
        (xy -10.436 4.707)
        (xy -10.449 4.725)
        (xy -10.465 4.744)
        (xy -10.481 4.76)
        (xy -10.497 4.776)
        (xy -10.516 4.792)
        (xy -10.533 4.805)
        (xy -10.554 4.818)
        (xy -10.572 4.83)
        (xy -10.593 4.842)
        (xy -10.615 4.853)
        (xy -10.636 4.861)
        (xy -10.657 4.869)
        (xy -10.68 4.875)
        (xy -10.702 4.88)
        (xy -10.725 4.885)
        (xy -10.748 4.888)
        (xy -10.773 4.89)
        (xy -10.795 4.89)
        (xy -10.82 4.89)
        (xy -10.843 4.888)
        (xy -10.866 4.885)
        (xy -10.889 4.88)
        (xy -10.911 4.875)
        (xy -10.933 4.869)
        (xy -10.955 4.861)
        (xy -10.978 4.853)
        (xy -10.998 4.842)
        (xy -11.019 4.832)
        (xy -11.039 4.818)
        (xy -11.058 4.805)
        (xy -11.077 4.792)
        (xy -11.093 4.776)
        (xy -11.11 4.76)
        (xy -11.126 4.744)
        (xy -11.141 4.726)
        (xy -11.155 4.707)
        (xy -11.168 4.688)
        (xy -11.181 4.669)
        (xy -11.192 4.648)
        (xy -11.202 4.627)
        (xy -11.212 4.606)
        (xy -11.218 4.584)
        (xy -11.225 4.561)
        (xy -11.231 4.539)
        (xy -11.235 4.516)
        (xy -11.238 4.494)
        (xy -11.24 4.47)
        (xy -11.24 4.447)
        (xy -10.795 4.447)
        (xy -10.795 4.443)
      )

      (stroke (width 0.001) (type solid)) (fill solid) (layer "B.Paste"))
    (fp_poly
      (pts
        (xy -10.795 5.713)
        (xy -11.24 5.713)
        (xy -11.24 5.691)
        (xy -11.238 5.667)
        (xy -11.235 5.645)
        (xy -11.231 5.622)
        (xy -11.225 5.6)
        (xy -11.218 5.577)
        (xy -11.212 5.555)
        (xy -11.202 5.534)
        (xy -11.192 5.512)
        (xy -11.181 5.492)
        (xy -11.168 5.473)
        (xy -11.155 5.454)
        (xy -11.141 5.435)
        (xy -11.126 5.417)
        (xy -11.11 5.401)
        (xy -11.093 5.385)
        (xy -11.077 5.369)
        (xy -11.058 5.356)
        (xy -11.039 5.342)
        (xy -11.019 5.329)
        (xy -10.998 5.318)
        (xy -10.978 5.308)
        (xy -10.955 5.3)
        (xy -10.933 5.292)
        (xy -10.911 5.286)
        (xy -10.889 5.281)
        (xy -10.866 5.276)
        (xy -10.843 5.273)
        (xy -10.82 5.271)
        (xy -10.795 5.27)
        (xy -10.773 5.271)
        (xy -10.748 5.273)
        (xy -10.725 5.276)
        (xy -10.702 5.281)
        (xy -10.68 5.286)
        (xy -10.657 5.292)
        (xy -10.636 5.3)
        (xy -10.615 5.308)
        (xy -10.593 5.319)
        (xy -10.572 5.33)
        (xy -10.554 5.342)
        (xy -10.533 5.356)
        (xy -10.516 5.369)
        (xy -10.497 5.385)
        (xy -10.481 5.401)
        (xy -10.465 5.417)
        (xy -10.449 5.435)
        (xy -10.436 5.454)
        (xy -10.423 5.473)
        (xy -10.41 5.492)
        (xy -10.399 5.513)
        (xy -10.388 5.534)
        (xy -10.381 5.556)
        (xy -10.372 5.577)
        (xy -10.365 5.6)
        (xy -10.36 5.622)
        (xy -10.356 5.645)
        (xy -10.353 5.669)
        (xy -10.352 5.693)
        (xy -10.35 5.715)
        (xy -10.352 5.739)
        (xy -10.353 5.762)
        (xy -10.356 5.786)
        (xy -10.36 5.808)
        (xy -10.365 5.83)
        (xy -10.372 5.853)
        (xy -10.381 5.874)
        (xy -10.388 5.896)
        (xy -10.399 5.917)
        (xy -10.41 5.938)
        (xy -10.423 5.957)
        (xy -10.436 5.978)
        (xy -10.449 5.995)
        (xy -10.465 6.013)
        (xy -10.481 6.031)
        (xy -10.497 6.047)
        (xy -10.516 6.061)
        (xy -10.533 6.076)
        (xy -10.554 6.088)
        (xy -10.572 6.1)
        (xy -10.593 6.111)
        (xy -10.615 6.122)
        (xy -10.636 6.13)
        (xy -10.657 6.138)
        (xy -10.68 6.145)
        (xy -10.702 6.151)
        (xy -10.725 6.156)
        (xy -10.748 6.159)
        (xy -10.773 6.159)
        (xy -10.795 6.161)
        (xy -10.82 6.159)
        (xy -10.843 6.159)
        (xy -10.866 6.156)
        (xy -10.889 6.151)
        (xy -10.911 6.145)
        (xy -10.933 6.138)
        (xy -10.955 6.132)
        (xy -10.978 6.122)
        (xy -10.998 6.112)
        (xy -11.019 6.101)
        (xy -11.039 6.088)
        (xy -11.058 6.076)
        (xy -11.077 6.061)
        (xy -11.093 6.047)
        (xy -11.11 6.031)
        (xy -11.126 6.013)
        (xy -11.141 5.997)
        (xy -11.155 5.978)
        (xy -11.168 5.959)
        (xy -11.181 5.938)
        (xy -11.192 5.919)
        (xy -11.202 5.898)
        (xy -11.212 5.875)
        (xy -11.218 5.853)
        (xy -11.225 5.832)
        (xy -11.231 5.81)
        (xy -11.235 5.786)
        (xy -11.238 5.763)
        (xy -11.24 5.739)
        (xy -11.24 5.718)
        (xy -10.795 5.718)
        (xy -10.795 5.713)
      )

      (stroke (width 0.001) (type solid)) (fill solid) (layer "B.Paste"))
    (fp_poly
      (pts
        (xy -9.526 -5.717)
        (xy -9.971 -5.717)
        (xy -9.969 -5.738)
        (xy -9.968 -5.762)
        (xy -9.965 -5.785)
        (xy -9.961 -5.809)
        (xy -9.955 -5.831)
        (xy -9.949 -5.852)
        (xy -9.942 -5.874)
        (xy -9.933 -5.897)
        (xy -9.923 -5.918)
        (xy -9.911 -5.937)
        (xy -9.898 -5.958)
        (xy -9.885 -5.977)
        (xy -9.872 -5.996)
        (xy -9.856 -6.012)
        (xy -9.84 -6.03)
        (xy -9.824 -6.046)
        (xy -9.806 -6.06)
        (xy -9.788 -6.075)
        (xy -9.769 -6.087)
        (xy -9.748 -6.1)
        (xy -9.728 -6.111)
        (xy -9.708 -6.121)
        (xy -9.686 -6.131)
        (xy -9.664 -6.137)
        (xy -9.641 -6.144)
        (xy -9.619 -6.15)
        (xy -9.596 -6.155)
        (xy -9.574 -6.158)
        (xy -9.549 -6.158)
        (xy -9.526 -6.16)
        (xy -9.503 -6.158)
        (xy -9.478 -6.158)
        (xy -9.455 -6.155)
        (xy -9.433 -6.15)
        (xy -9.41 -6.144)
        (xy -9.388 -6.137)
        (xy -9.366 -6.129)
        (xy -9.344 -6.121)
        (xy -9.324 -6.11)
        (xy -9.304 -6.099)
        (xy -9.283 -6.087)
        (xy -9.263 -6.075)
        (xy -9.245 -6.06)
        (xy -9.228 -6.046)
        (xy -9.211 -6.03)
        (xy -9.195 -6.012)
        (xy -9.18 -5.994)
        (xy -9.165 -5.977)
        (xy -9.152 -5.956)
        (xy -9.141 -5.937)
        (xy -9.129 -5.916)
        (xy -9.119 -5.895)
        (xy -9.11 -5.873)
        (xy -9.103 -5.852)
        (xy -9.096 -5.829)
        (xy -9.09 -5.807)
        (xy -9.086 -5.785)
        (xy -9.083 -5.761)
        (xy -9.081 -5.738)
        (xy -9.08 -5.714)
        (xy -9.081 -5.692)
        (xy -9.083 -5.668)
        (xy -9.086 -5.644)
        (xy -9.09 -5.621)
        (xy -9.096 -5.599)
        (xy -9.103 -5.576)
        (xy -9.11 -5.555)
        (xy -9.119 -5.533)
        (xy -9.129 -5.512)
        (xy -9.141 -5.491)
        (xy -9.152 -5.472)
        (xy -9.165 -5.453)
        (xy -9.18 -5.434)
        (xy -9.195 -5.416)
        (xy -9.211 -5.4)
        (xy -9.228 -5.384)
        (xy -9.245 -5.368)
        (xy -9.263 -5.355)
        (xy -9.283 -5.341)
        (xy -9.304 -5.329)
        (xy -9.324 -5.318)
        (xy -9.344 -5.307)
        (xy -9.366 -5.299)
        (xy -9.388 -5.291)
        (xy -9.41 -5.285)
        (xy -9.433 -5.28)
        (xy -9.455 -5.275)
        (xy -9.478 -5.272)
        (xy -9.503 -5.27)
        (xy -9.526 -5.269)
        (xy -9.549 -5.27)
        (xy -9.574 -5.272)
        (xy -9.596 -5.275)
        (xy -9.619 -5.28)
        (xy -9.641 -5.285)
        (xy -9.664 -5.291)
        (xy -9.686 -5.299)
        (xy -9.708 -5.307)
        (xy -9.728 -5.317)
        (xy -9.748 -5.328)
        (xy -9.769 -5.341)
        (xy -9.788 -5.355)
        (xy -9.806 -5.368)
        (xy -9.824 -5.384)
        (xy -9.84 -5.4)
        (xy -9.856 -5.416)
        (xy -9.872 -5.434)
        (xy -9.885 -5.453)
        (xy -9.898 -5.472)
        (xy -9.911 -5.491)
        (xy -9.923 -5.511)
        (xy -9.933 -5.533)
        (xy -9.942 -5.554)
        (xy -9.949 -5.576)
        (xy -9.955 -5.599)
        (xy -9.961 -5.621)
        (xy -9.965 -5.644)
        (xy -9.968 -5.666)
        (xy -9.969 -5.69)
        (xy -9.971 -5.712)
        (xy -9.526 -5.712)
        (xy -9.526 -5.717)
      )

      (stroke (width 0.001) (type solid)) (fill solid) (layer "B.Paste"))
    (fp_poly
      (pts
        (xy -9.526 -3.177)
        (xy -9.971 -3.177)
        (xy -9.969 -3.198)
        (xy -9.968 -3.222)
        (xy -9.965 -3.245)
        (xy -9.961 -3.269)
        (xy -9.955 -3.29)
        (xy -9.949 -3.313)
        (xy -9.942 -3.334)
        (xy -9.933 -3.357)
        (xy -9.923 -3.378)
        (xy -9.911 -3.398)
        (xy -9.898 -3.418)
        (xy -9.885 -3.436)
        (xy -9.872 -3.455)
        (xy -9.856 -3.472)
        (xy -9.84 -3.49)
        (xy -9.824 -3.505)
        (xy -9.806 -3.52)
        (xy -9.788 -3.535)
        (xy -9.769 -3.547)
        (xy -9.748 -3.56)
        (xy -9.728 -3.571)
        (xy -9.708 -3.581)
        (xy -9.686 -3.591)
        (xy -9.664 -3.597)
        (xy -9.641 -3.604)
        (xy -9.619 -3.609)
        (xy -9.596 -3.615)
        (xy -9.574 -3.617)
        (xy -9.549 -3.619)
        (xy -9.526 -3.62)
        (xy -9.503 -3.619)
        (xy -9.478 -3.617)
        (xy -9.455 -3.615)
        (xy -9.433 -3.609)
        (xy -9.41 -3.604)
        (xy -9.388 -3.597)
        (xy -9.366 -3.589)
        (xy -9.344 -3.581)
        (xy -9.324 -3.571)
        (xy -9.304 -3.559)
        (xy -9.283 -3.547)
        (xy -9.263 -3.535)
        (xy -9.245 -3.52)
        (xy -9.228 -3.505)
        (xy -9.211 -3.49)
        (xy -9.195 -3.472)
        (xy -9.18 -3.454)
        (xy -9.165 -3.436)
        (xy -9.152 -3.416)
        (xy -9.141 -3.396)
        (xy -9.129 -3.376)
        (xy -9.119 -3.355)
        (xy -9.11 -3.334)
        (xy -9.103 -3.313)
        (xy -9.096 -3.289)
        (xy -9.09 -3.267)
        (xy -9.086 -3.245)
        (xy -9.083 -3.221)
        (xy -9.081 -3.197)
        (xy -9.08 -3.174)
        (xy -9.081 -3.152)
        (xy -9.083 -3.128)
        (xy -9.086 -3.104)
        (xy -9.09 -3.081)
        (xy -9.096 -3.059)
        (xy -9.103 -3.036)
        (xy -9.11 -3.015)
        (xy -9.119 -2.994)
        (xy -9.129 -2.972)
        (xy -9.141 -2.951)
        (xy -9.152 -2.932)
        (xy -9.165 -2.912)
        (xy -9.18 -2.894)
        (xy -9.195 -2.876)
        (xy -9.211 -2.859)
        (xy -9.228 -2.843)
        (xy -9.245 -2.829)
        (xy -9.263 -2.814)
        (xy -9.283 -2.801)
        (xy -9.304 -2.789)
        (xy -9.324 -2.778)
        (xy -9.344 -2.767)
        (xy -9.366 -2.759)
        (xy -9.388 -2.751)
        (xy -9.41 -2.745)
        (xy -9.433 -2.74)
        (xy -9.455 -2.734)
        (xy -9.478 -2.732)
        (xy -9.503 -2.73)
        (xy -9.526 -2.729)
        (xy -9.549 -2.73)
        (xy -9.574 -2.732)
        (xy -9.596 -2.734)
        (xy -9.619 -2.74)
        (xy -9.641 -2.745)
        (xy -9.664 -2.751)
        (xy -9.686 -2.758)
        (xy -9.708 -2.767)
        (xy -9.728 -2.777)
        (xy -9.748 -2.789)
        (xy -9.769 -2.801)
        (xy -9.788 -2.814)
        (xy -9.806 -2.829)
        (xy -9.824 -2.843)
        (xy -9.84 -2.859)
        (xy -9.856 -2.876)
        (xy -9.872 -2.894)
        (xy -9.885 -2.912)
        (xy -9.898 -2.931)
        (xy -9.911 -2.951)
        (xy -9.923 -2.971)
        (xy -9.933 -2.992)
        (xy -9.942 -3.015)
        (xy -9.949 -3.036)
        (xy -9.955 -3.059)
        (xy -9.961 -3.08)
        (xy -9.965 -3.104)
        (xy -9.968 -3.126)
        (xy -9.969 -3.15)
        (xy -9.971 -3.172)
        (xy -9.526 -3.172)
        (xy -9.526 -3.177)
      )

      (stroke (width 0.001) (type solid)) (fill solid) (layer "B.Paste"))
    (fp_poly
      (pts
        (xy -9.526 1.903)
        (xy -9.971 1.903)
        (xy -9.969 1.881)
        (xy -9.968 1.857)
        (xy -9.965 1.835)
        (xy -9.961 1.811)
        (xy -9.955 1.789)
        (xy -9.949 1.767)
        (xy -9.942 1.746)
        (xy -9.933 1.724)
        (xy -9.923 1.702)
        (xy -9.911 1.682)
        (xy -9.898 1.662)
        (xy -9.885 1.643)
        (xy -9.872 1.625)
        (xy -9.856 1.607)
        (xy -9.84 1.591)
        (xy -9.824 1.575)
        (xy -9.806 1.559)
        (xy -9.788 1.545)
        (xy -9.769 1.532)
        (xy -9.748 1.519)
        (xy -9.728 1.508)
        (xy -9.708 1.498)
        (xy -9.686 1.49)
        (xy -9.664 1.482)
        (xy -9.641 1.476)
        (xy -9.619 1.47)
        (xy -9.596 1.466)
        (xy -9.574 1.462)
        (xy -9.549 1.462)
        (xy -9.526 1.46)
        (xy -9.503 1.462)
        (xy -9.478 1.462)
        (xy -9.455 1.466)
        (xy -9.433 1.47)
        (xy -9.41 1.476)
        (xy -9.388 1.482)
        (xy -9.366 1.49)
        (xy -9.344 1.498)
        (xy -9.324 1.509)
        (xy -9.304 1.52)
        (xy -9.283 1.532)
        (xy -9.263 1.545)
        (xy -9.245 1.559)
        (xy -9.228 1.575)
        (xy -9.211 1.591)
        (xy -9.195 1.607)
        (xy -9.18 1.625)
        (xy -9.165 1.643)
        (xy -9.152 1.663)
        (xy -9.141 1.684)
        (xy -9.129 1.704)
        (xy -9.119 1.724)
        (xy -9.11 1.746)
        (xy -9.103 1.767)
        (xy -9.096 1.79)
        (xy -9.09 1.813)
        (xy -9.086 1.835)
        (xy -9.083 1.859)
        (xy -9.081 1.882)
        (xy -9.08 1.905)
        (xy -9.081 1.928)
        (xy -9.083 1.952)
        (xy -9.086 1.976)
        (xy -9.09 1.998)
        (xy -9.096 2.02)
        (xy -9.103 2.044)
        (xy -9.11 2.065)
        (xy -9.119 2.086)
        (xy -9.129 2.108)
        (xy -9.141 2.127)
        (xy -9.152 2.147)
        (xy -9.165 2.167)
        (xy -9.18 2.186)
        (xy -9.195 2.203)
        (xy -9.211 2.221)
        (xy -9.228 2.237)
        (xy -9.245 2.251)
        (xy -9.263 2.266)
        (xy -9.283 2.278)
        (xy -9.304 2.29)
        (xy -9.324 2.302)
        (xy -9.344 2.312)
        (xy -9.366 2.32)
        (xy -9.388 2.328)
        (xy -9.41 2.335)
        (xy -9.433 2.34)
        (xy -9.455 2.346)
        (xy -9.478 2.348)
        (xy -9.503 2.35)
        (xy -9.526 2.351)
        (xy -9.549 2.35)
        (xy -9.574 2.348)
        (xy -9.596 2.346)
        (xy -9.619 2.34)
        (xy -9.641 2.335)
        (xy -9.664 2.328)
        (xy -9.686 2.322)
        (xy -9.708 2.312)
        (xy -9.728 2.302)
        (xy -9.748 2.291)
        (xy -9.769 2.278)
        (xy -9.788 2.266)
        (xy -9.806 2.251)
        (xy -9.824 2.237)
        (xy -9.84 2.221)
        (xy -9.856 2.203)
        (xy -9.872 2.186)
        (xy -9.885 2.167)
        (xy -9.898 2.149)
        (xy -9.911 2.129)
        (xy -9.923 2.109)
        (xy -9.933 2.088)
        (xy -9.942 2.065)
        (xy -9.949 2.044)
        (xy -9.955 2.021)
        (xy -9.961 2)
        (xy -9.965 1.976)
        (xy -9.968 1.954)
        (xy -9.969 1.93)
        (xy -9.971 1.907)
        (xy -9.526 1.907)
        (xy -9.526 1.903)
      )

      (stroke (width 0.001) (type solid)) (fill solid) (layer "B.Paste"))
    (fp_poly
      (pts
        (xy -9.526 3.173)
        (xy -9.971 3.173)
        (xy -9.969 3.151)
        (xy -9.968 3.127)
        (xy -9.965 3.105)
        (xy -9.961 3.081)
        (xy -9.955 3.06)
        (xy -9.949 3.037)
        (xy -9.942 3.016)
        (xy -9.933 2.993)
        (xy -9.923 2.972)
        (xy -9.911 2.952)
        (xy -9.898 2.932)
        (xy -9.885 2.913)
        (xy -9.872 2.895)
        (xy -9.856 2.877)
        (xy -9.84 2.86)
        (xy -9.824 2.844)
        (xy -9.806 2.83)
        (xy -9.788 2.815)
        (xy -9.769 2.802)
        (xy -9.748 2.79)
        (xy -9.728 2.778)
        (xy -9.708 2.768)
        (xy -9.686 2.759)
        (xy -9.664 2.752)
        (xy -9.641 2.746)
        (xy -9.619 2.741)
        (xy -9.596 2.735)
        (xy -9.574 2.733)
        (xy -9.549 2.731)
        (xy -9.526 2.73)
        (xy -9.503 2.731)
        (xy -9.478 2.733)
        (xy -9.455 2.735)
        (xy -9.433 2.741)
        (xy -9.41 2.746)
        (xy -9.388 2.752)
        (xy -9.366 2.76)
        (xy -9.344 2.768)
        (xy -9.324 2.779)
        (xy -9.304 2.79)
        (xy -9.283 2.802)
        (xy -9.263 2.815)
        (xy -9.245 2.83)
        (xy -9.228 2.844)
        (xy -9.211 2.86)
        (xy -9.195 2.877)
        (xy -9.18 2.895)
        (xy -9.165 2.913)
        (xy -9.152 2.933)
        (xy -9.141 2.952)
        (xy -9.129 2.973)
        (xy -9.119 2.995)
        (xy -9.11 3.016)
        (xy -9.103 3.037)
        (xy -9.096 3.06)
        (xy -9.09 3.082)
        (xy -9.086 3.105)
        (xy -9.083 3.129)
        (xy -9.081 3.153)
        (xy -9.08 3.175)
        (xy -9.081 3.198)
        (xy -9.083 3.222)
        (xy -9.086 3.246)
        (xy -9.09 3.268)
        (xy -9.096 3.29)
        (xy -9.103 3.314)
        (xy -9.11 3.335)
        (xy -9.119 3.356)
        (xy -9.129 3.377)
        (xy -9.141 3.397)
        (xy -9.152 3.417)
        (xy -9.165 3.437)
        (xy -9.18 3.455)
        (xy -9.195 3.473)
        (xy -9.211 3.491)
        (xy -9.228 3.506)
        (xy -9.245 3.521)
        (xy -9.263 3.536)
        (xy -9.283 3.548)
        (xy -9.304 3.56)
        (xy -9.324 3.572)
        (xy -9.344 3.582)
        (xy -9.366 3.59)
        (xy -9.388 3.598)
        (xy -9.41 3.605)
        (xy -9.433 3.61)
        (xy -9.455 3.616)
        (xy -9.478 3.618)
        (xy -9.503 3.62)
        (xy -9.526 3.621)
        (xy -9.549 3.62)
        (xy -9.574 3.618)
        (xy -9.596 3.616)
        (xy -9.619 3.61)
        (xy -9.641 3.605)
        (xy -9.664 3.598)
        (xy -9.686 3.592)
        (xy -9.708 3.582)
        (xy -9.728 3.572)
        (xy -9.748 3.561)
        (xy -9.769 3.548)
        (xy -9.788 3.536)
        (xy -9.806 3.521)
        (xy -9.824 3.506)
        (xy -9.84 3.491)
        (xy -9.856 3.473)
        (xy -9.872 3.456)
        (xy -9.885 3.437)
        (xy -9.898 3.419)
        (xy -9.911 3.399)
        (xy -9.923 3.379)
        (xy -9.933 3.358)
        (xy -9.942 3.335)
        (xy -9.949 3.314)
        (xy -9.955 3.291)
        (xy -9.961 3.27)
        (xy -9.965 3.246)
        (xy -9.968 3.223)
        (xy -9.969 3.199)
        (xy -9.971 3.178)
        (xy -9.526 3.178)
        (xy -9.526 3.173)
      )

      (stroke (width 0.001) (type solid)) (fill solid) (layer "B.Paste"))
    (fp_poly
      (pts
        (xy -9.526 4.443)
        (xy -9.971 4.443)
        (xy -9.969 4.422)
        (xy -9.968 4.398)
        (xy -9.965 4.374)
        (xy -9.961 4.351)
        (xy -9.955 4.329)
        (xy -9.949 4.308)
        (xy -9.942 4.286)
        (xy -9.933 4.263)
        (xy -9.923 4.242)
        (xy -9.911 4.223)
        (xy -9.898 4.202)
        (xy -9.885 4.183)
        (xy -9.872 4.164)
        (xy -9.856 4.148)
        (xy -9.84 4.13)
        (xy -9.824 4.114)
        (xy -9.806 4.1)
        (xy -9.788 4.085)
        (xy -9.769 4.072)
        (xy -9.748 4.06)
        (xy -9.728 4.048)
        (xy -9.708 4.039)
        (xy -9.686 4.029)
        (xy -9.664 4.023)
        (xy -9.641 4.015)
        (xy -9.619 4.01)
        (xy -9.596 4.005)
        (xy -9.574 4.002)
        (xy -9.549 4.002)
        (xy -9.526 4)
        (xy -9.503 4.002)
        (xy -9.478 4.002)
        (xy -9.455 4.005)
        (xy -9.433 4.01)
        (xy -9.41 4.015)
        (xy -9.388 4.023)
        (xy -9.366 4.031)
        (xy -9.344 4.039)
        (xy -9.324 4.05)
        (xy -9.304 4.06)
        (xy -9.283 4.072)
        (xy -9.263 4.085)
        (xy -9.245 4.1)
        (xy -9.228 4.114)
        (xy -9.211 4.13)
        (xy -9.195 4.148)
        (xy -9.18 4.165)
        (xy -9.165 4.183)
        (xy -9.152 4.204)
        (xy -9.141 4.223)
        (xy -9.129 4.244)
        (xy -9.119 4.265)
        (xy -9.11 4.286)
        (xy -9.103 4.308)
        (xy -9.096 4.33)
        (xy -9.09 4.353)
        (xy -9.086 4.375)
        (xy -9.083 4.398)
        (xy -9.081 4.422)
        (xy -9.08 4.446)
        (xy -9.081 4.468)
        (xy -9.083 4.492)
        (xy -9.086 4.515)
        (xy -9.09 4.539)
        (xy -9.096 4.56)
        (xy -9.103 4.584)
        (xy -9.11 4.604)
        (xy -9.119 4.627)
        (xy -9.129 4.648)
        (xy -9.141 4.669)
        (xy -9.152 4.688)
        (xy -9.165 4.707)
        (xy -9.18 4.725)
        (xy -9.195 4.744)
        (xy -9.211 4.76)
        (xy -9.228 4.776)
        (xy -9.245 4.792)
        (xy -9.263 4.805)
        (xy -9.283 4.818)
        (xy -9.304 4.83)
        (xy -9.324 4.842)
        (xy -9.344 4.853)
        (xy -9.366 4.861)
        (xy -9.388 4.869)
        (xy -9.41 4.875)
        (xy -9.433 4.88)
        (xy -9.455 4.885)
        (xy -9.478 4.888)
        (xy -9.503 4.89)
        (xy -9.526 4.89)
        (xy -9.549 4.89)
        (xy -9.574 4.888)
        (xy -9.596 4.885)
        (xy -9.619 4.88)
        (xy -9.641 4.875)
        (xy -9.664 4.869)
        (xy -9.686 4.861)
        (xy -9.708 4.853)
        (xy -9.728 4.842)
        (xy -9.748 4.832)
        (xy -9.769 4.818)
        (xy -9.788 4.805)
        (xy -9.806 4.792)
        (xy -9.824 4.776)
        (xy -9.84 4.76)
        (xy -9.856 4.744)
        (xy -9.872 4.726)
        (xy -9.885 4.707)
        (xy -9.898 4.688)
        (xy -9.911 4.669)
        (xy -9.923 4.648)
        (xy -9.933 4.627)
        (xy -9.942 4.606)
        (xy -9.949 4.584)
        (xy -9.955 4.561)
        (xy -9.961 4.539)
        (xy -9.965 4.516)
        (xy -9.968 4.494)
        (xy -9.969 4.47)
        (xy -9.971 4.447)
        (xy -9.526 4.447)
        (xy -9.526 4.443)
      )

      (stroke (width 0.001) (type solid)) (fill solid) (layer "B.Paste"))
    (fp_poly
      (pts
        (xy -9.526 5.713)
        (xy -9.971 5.713)
        (xy -9.969 5.691)
        (xy -9.968 5.667)
        (xy -9.965 5.645)
        (xy -9.961 5.622)
        (xy -9.955 5.6)
        (xy -9.949 5.577)
        (xy -9.942 5.555)
        (xy -9.933 5.534)
        (xy -9.923 5.512)
        (xy -9.911 5.492)
        (xy -9.898 5.473)
        (xy -9.885 5.454)
        (xy -9.872 5.435)
        (xy -9.856 5.417)
        (xy -9.84 5.401)
        (xy -9.824 5.385)
        (xy -9.806 5.369)
        (xy -9.788 5.356)
        (xy -9.769 5.342)
        (xy -9.748 5.329)
        (xy -9.728 5.318)
        (xy -9.708 5.308)
        (xy -9.686 5.3)
        (xy -9.664 5.292)
        (xy -9.641 5.286)
        (xy -9.619 5.281)
        (xy -9.596 5.276)
        (xy -9.574 5.273)
        (xy -9.549 5.271)
        (xy -9.526 5.27)
        (xy -9.503 5.271)
        (xy -9.478 5.273)
        (xy -9.455 5.276)
        (xy -9.433 5.281)
        (xy -9.41 5.286)
        (xy -9.388 5.292)
        (xy -9.366 5.3)
        (xy -9.344 5.308)
        (xy -9.324 5.319)
        (xy -9.304 5.33)
        (xy -9.283 5.342)
        (xy -9.263 5.356)
        (xy -9.245 5.369)
        (xy -9.228 5.385)
        (xy -9.211 5.401)
        (xy -9.195 5.417)
        (xy -9.18 5.435)
        (xy -9.165 5.454)
        (xy -9.152 5.473)
        (xy -9.141 5.492)
        (xy -9.129 5.513)
        (xy -9.119 5.534)
        (xy -9.11 5.556)
        (xy -9.103 5.577)
        (xy -9.096 5.6)
        (xy -9.09 5.622)
        (xy -9.086 5.645)
        (xy -9.083 5.669)
        (xy -9.081 5.693)
        (xy -9.08 5.715)
        (xy -9.081 5.739)
        (xy -9.083 5.762)
        (xy -9.086 5.786)
        (xy -9.09 5.808)
        (xy -9.096 5.83)
        (xy -9.103 5.853)
        (xy -9.11 5.874)
        (xy -9.119 5.896)
        (xy -9.129 5.917)
        (xy -9.141 5.938)
        (xy -9.152 5.957)
        (xy -9.165 5.978)
        (xy -9.18 5.995)
        (xy -9.195 6.013)
        (xy -9.211 6.031)
        (xy -9.228 6.047)
        (xy -9.245 6.061)
        (xy -9.263 6.076)
        (xy -9.283 6.088)
        (xy -9.304 6.1)
        (xy -9.324 6.111)
        (xy -9.344 6.122)
        (xy -9.366 6.13)
        (xy -9.388 6.138)
        (xy -9.41 6.145)
        (xy -9.433 6.151)
        (xy -9.455 6.156)
        (xy -9.478 6.159)
        (xy -9.503 6.159)
        (xy -9.526 6.161)
        (xy -9.549 6.159)
        (xy -9.574 6.159)
        (xy -9.596 6.156)
        (xy -9.619 6.151)
        (xy -9.641 6.145)
        (xy -9.664 6.138)
        (xy -9.686 6.132)
        (xy -9.708 6.122)
        (xy -9.728 6.112)
        (xy -9.748 6.101)
        (xy -9.769 6.088)
        (xy -9.788 6.076)
        (xy -9.806 6.061)
        (xy -9.824 6.047)
        (xy -9.84 6.031)
        (xy -9.856 6.013)
        (xy -9.872 5.997)
        (xy -9.885 5.978)
        (xy -9.898 5.959)
        (xy -9.911 5.938)
        (xy -9.923 5.919)
        (xy -9.933 5.898)
        (xy -9.942 5.875)
        (xy -9.949 5.853)
        (xy -9.955 5.832)
        (xy -9.961 5.81)
        (xy -9.965 5.786)
        (xy -9.968 5.763)
        (xy -9.969 5.739)
        (xy -9.971 5.718)
        (xy -9.526 5.718)
        (xy -9.526 5.713)
      )

      (stroke (width 0.001) (type solid)) (fill solid) (layer "B.Paste"))
    (fp_poly
      (pts
        (xy -8.256 -5.717)
        (xy -8.7 -5.717)
        (xy -8.699 -5.738)
        (xy -8.699 -5.762)
        (xy -8.696 -5.785)
        (xy -8.69 -5.809)
        (xy -8.686 -5.831)
        (xy -8.679 -5.852)
        (xy -8.671 -5.874)
        (xy -8.663 -5.897)
        (xy -8.652 -5.918)
        (xy -8.641 -5.937)
        (xy -8.628 -5.958)
        (xy -8.616 -5.977)
        (xy -8.602 -5.996)
        (xy -8.587 -6.012)
        (xy -8.571 -6.03)
        (xy -8.554 -6.046)
        (xy -8.536 -6.06)
        (xy -8.517 -6.075)
        (xy -8.498 -6.087)
        (xy -8.478 -6.1)
        (xy -8.459 -6.111)
        (xy -8.437 -6.121)
        (xy -8.415 -6.131)
        (xy -8.394 -6.137)
        (xy -8.372 -6.144)
        (xy -8.35 -6.15)
        (xy -8.327 -6.155)
        (xy -8.304 -6.158)
        (xy -8.279 -6.158)
        (xy -8.256 -6.16)
        (xy -8.232 -6.158)
        (xy -8.209 -6.158)
        (xy -8.186 -6.155)
        (xy -8.163 -6.15)
        (xy -8.141 -6.144)
        (xy -8.118 -6.137)
        (xy -8.096 -6.129)
        (xy -8.074 -6.121)
        (xy -8.054 -6.11)
        (xy -8.033 -6.099)
        (xy -8.013 -6.087)
        (xy -7.994 -6.075)
        (xy -7.975 -6.06)
        (xy -7.957 -6.046)
        (xy -7.941 -6.03)
        (xy -7.925 -6.012)
        (xy -7.909 -5.994)
        (xy -7.895 -5.977)
        (xy -7.882 -5.956)
        (xy -7.87 -5.937)
        (xy -7.859 -5.916)
        (xy -7.848 -5.895)
        (xy -7.84 -5.873)
        (xy -7.832 -5.852)
        (xy -7.826 -5.829)
        (xy -7.821 -5.807)
        (xy -7.816 -5.785)
        (xy -7.813 -5.761)
        (xy -7.811 -5.738)
        (xy -7.81 -5.714)
        (xy -7.811 -5.692)
        (xy -7.813 -5.668)
        (xy -7.816 -5.644)
        (xy -7.821 -5.621)
        (xy -7.826 -5.599)
        (xy -7.832 -5.576)
        (xy -7.84 -5.555)
        (xy -7.848 -5.533)
        (xy -7.859 -5.512)
        (xy -7.87 -5.493)
        (xy -7.882 -5.472)
        (xy -7.895 -5.453)
        (xy -7.909 -5.434)
        (xy -7.925 -5.416)
        (xy -7.941 -5.4)
        (xy -7.957 -5.384)
        (xy -7.975 -5.368)
        (xy -7.994 -5.355)
        (xy -8.013 -5.341)
        (xy -8.033 -5.329)
        (xy -8.054 -5.318)
        (xy -8.074 -5.307)
        (xy -8.096 -5.299)
        (xy -8.118 -5.291)
        (xy -8.141 -5.285)
        (xy -8.163 -5.28)
        (xy -8.186 -5.275)
        (xy -8.209 -5.272)
        (xy -8.232 -5.27)
        (xy -8.256 -5.269)
        (xy -8.279 -5.27)
        (xy -8.304 -5.272)
        (xy -8.327 -5.275)
        (xy -8.35 -5.28)
        (xy -8.372 -5.285)
        (xy -8.394 -5.291)
        (xy -8.415 -5.299)
        (xy -8.437 -5.307)
        (xy -8.459 -5.317)
        (xy -8.478 -5.328)
        (xy -8.498 -5.341)
        (xy -8.517 -5.355)
        (xy -8.536 -5.368)
        (xy -8.554 -5.384)
        (xy -8.571 -5.4)
        (xy -8.587 -5.416)
        (xy -8.602 -5.434)
        (xy -8.616 -5.453)
        (xy -8.628 -5.472)
        (xy -8.641 -5.491)
        (xy -8.652 -5.511)
        (xy -8.663 -5.533)
        (xy -8.671 -5.554)
        (xy -8.679 -5.576)
        (xy -8.686 -5.599)
        (xy -8.69 -5.621)
        (xy -8.696 -5.644)
        (xy -8.699 -5.666)
        (xy -8.699 -5.69)
        (xy -8.7 -5.712)
        (xy -8.256 -5.712)
        (xy -8.256 -5.717)
      )

      (stroke (width 0.001) (type solid)) (fill solid) (layer "B.Paste"))
    (fp_poly
      (pts
        (xy -8.256 -3.177)
        (xy -8.7 -3.177)
        (xy -8.699 -3.198)
        (xy -8.699 -3.222)
        (xy -8.696 -3.245)
        (xy -8.69 -3.269)
        (xy -8.686 -3.29)
        (xy -8.679 -3.313)
        (xy -8.671 -3.334)
        (xy -8.663 -3.357)
        (xy -8.652 -3.378)
        (xy -8.641 -3.398)
        (xy -8.628 -3.418)
        (xy -8.616 -3.436)
        (xy -8.602 -3.455)
        (xy -8.587 -3.472)
        (xy -8.571 -3.49)
        (xy -8.554 -3.505)
        (xy -8.536 -3.52)
        (xy -8.517 -3.535)
        (xy -8.498 -3.547)
        (xy -8.478 -3.56)
        (xy -8.459 -3.571)
        (xy -8.437 -3.581)
        (xy -8.415 -3.591)
        (xy -8.394 -3.597)
        (xy -8.372 -3.604)
        (xy -8.35 -3.609)
        (xy -8.327 -3.615)
        (xy -8.304 -3.617)
        (xy -8.279 -3.619)
        (xy -8.256 -3.62)
        (xy -8.232 -3.619)
        (xy -8.209 -3.617)
        (xy -8.186 -3.615)
        (xy -8.163 -3.609)
        (xy -8.141 -3.604)
        (xy -8.118 -3.597)
        (xy -8.096 -3.589)
        (xy -8.074 -3.581)
        (xy -8.054 -3.571)
        (xy -8.033 -3.559)
        (xy -8.013 -3.547)
        (xy -7.994 -3.535)
        (xy -7.975 -3.52)
        (xy -7.957 -3.505)
        (xy -7.941 -3.49)
        (xy -7.925 -3.472)
        (xy -7.909 -3.454)
        (xy -7.895 -3.436)
        (xy -7.882 -3.416)
        (xy -7.87 -3.396)
        (xy -7.859 -3.376)
        (xy -7.848 -3.355)
        (xy -7.84 -3.334)
        (xy -7.832 -3.313)
        (xy -7.826 -3.289)
        (xy -7.821 -3.267)
        (xy -7.816 -3.245)
        (xy -7.813 -3.221)
        (xy -7.811 -3.197)
        (xy -7.81 -3.174)
        (xy -7.811 -3.152)
        (xy -7.813 -3.128)
        (xy -7.816 -3.104)
        (xy -7.821 -3.081)
        (xy -7.826 -3.059)
        (xy -7.832 -3.036)
        (xy -7.84 -3.015)
        (xy -7.848 -2.994)
        (xy -7.859 -2.972)
        (xy -7.87 -2.952)
        (xy -7.882 -2.932)
        (xy -7.895 -2.912)
        (xy -7.909 -2.894)
        (xy -7.925 -2.876)
        (xy -7.941 -2.859)
        (xy -7.957 -2.843)
        (xy -7.975 -2.829)
        (xy -7.994 -2.814)
        (xy -8.013 -2.801)
        (xy -8.033 -2.789)
        (xy -8.054 -2.778)
        (xy -8.074 -2.767)
        (xy -8.096 -2.759)
        (xy -8.118 -2.751)
        (xy -8.141 -2.745)
        (xy -8.163 -2.74)
        (xy -8.186 -2.734)
        (xy -8.209 -2.732)
        (xy -8.232 -2.73)
        (xy -8.256 -2.729)
        (xy -8.279 -2.73)
        (xy -8.304 -2.732)
        (xy -8.327 -2.734)
        (xy -8.35 -2.74)
        (xy -8.372 -2.745)
        (xy -8.394 -2.751)
        (xy -8.415 -2.758)
        (xy -8.437 -2.767)
        (xy -8.459 -2.777)
        (xy -8.478 -2.789)
        (xy -8.498 -2.801)
        (xy -8.517 -2.814)
        (xy -8.536 -2.829)
        (xy -8.554 -2.843)
        (xy -8.571 -2.859)
        (xy -8.587 -2.876)
        (xy -8.602 -2.894)
        (xy -8.616 -2.912)
        (xy -8.628 -2.931)
        (xy -8.641 -2.951)
        (xy -8.652 -2.971)
        (xy -8.663 -2.992)
        (xy -8.671 -3.015)
        (xy -8.679 -3.036)
        (xy -8.686 -3.059)
        (xy -8.69 -3.08)
        (xy -8.696 -3.104)
        (xy -8.699 -3.126)
        (xy -8.699 -3.15)
        (xy -8.7 -3.172)
        (xy -8.256 -3.172)
        (xy -8.256 -3.177)
      )

      (stroke (width 0.001) (type solid)) (fill solid) (layer "B.Paste"))
    (fp_poly
      (pts
        (xy -8.256 1.903)
        (xy -8.7 1.903)
        (xy -8.699 1.881)
        (xy -8.699 1.857)
        (xy -8.696 1.835)
        (xy -8.69 1.811)
        (xy -8.686 1.789)
        (xy -8.679 1.767)
        (xy -8.671 1.746)
        (xy -8.663 1.724)
        (xy -8.652 1.702)
        (xy -8.641 1.682)
        (xy -8.628 1.662)
        (xy -8.616 1.643)
        (xy -8.602 1.625)
        (xy -8.587 1.607)
        (xy -8.571 1.591)
        (xy -8.554 1.575)
        (xy -8.536 1.559)
        (xy -8.517 1.545)
        (xy -8.498 1.532)
        (xy -8.478 1.519)
        (xy -8.459 1.508)
        (xy -8.437 1.498)
        (xy -8.415 1.49)
        (xy -8.394 1.482)
        (xy -8.372 1.476)
        (xy -8.35 1.47)
        (xy -8.327 1.466)
        (xy -8.304 1.462)
        (xy -8.279 1.462)
        (xy -8.256 1.46)
        (xy -8.232 1.462)
        (xy -8.209 1.462)
        (xy -8.186 1.466)
        (xy -8.163 1.47)
        (xy -8.141 1.476)
        (xy -8.118 1.482)
        (xy -8.096 1.49)
        (xy -8.074 1.498)
        (xy -8.054 1.509)
        (xy -8.033 1.52)
        (xy -8.013 1.532)
        (xy -7.994 1.545)
        (xy -7.975 1.559)
        (xy -7.957 1.575)
        (xy -7.941 1.591)
        (xy -7.925 1.607)
        (xy -7.909 1.625)
        (xy -7.895 1.643)
        (xy -7.882 1.663)
        (xy -7.87 1.684)
        (xy -7.859 1.704)
        (xy -7.848 1.724)
        (xy -7.84 1.746)
        (xy -7.832 1.767)
        (xy -7.826 1.79)
        (xy -7.821 1.813)
        (xy -7.816 1.835)
        (xy -7.813 1.859)
        (xy -7.811 1.882)
        (xy -7.81 1.905)
        (xy -7.811 1.928)
        (xy -7.813 1.952)
        (xy -7.816 1.976)
        (xy -7.821 1.998)
        (xy -7.826 2.02)
        (xy -7.832 2.044)
        (xy -7.84 2.065)
        (xy -7.848 2.086)
        (xy -7.859 2.108)
        (xy -7.87 2.127)
        (xy -7.882 2.147)
        (xy -7.895 2.167)
        (xy -7.909 2.186)
        (xy -7.925 2.203)
        (xy -7.941 2.221)
        (xy -7.957 2.237)
        (xy -7.975 2.251)
        (xy -7.994 2.266)
        (xy -8.013 2.278)
        (xy -8.033 2.29)
        (xy -8.054 2.302)
        (xy -8.074 2.312)
        (xy -8.096 2.32)
        (xy -8.118 2.328)
        (xy -8.141 2.335)
        (xy -8.163 2.34)
        (xy -8.186 2.346)
        (xy -8.209 2.348)
        (xy -8.232 2.35)
        (xy -8.256 2.351)
        (xy -8.279 2.35)
        (xy -8.304 2.348)
        (xy -8.327 2.346)
        (xy -8.35 2.34)
        (xy -8.372 2.335)
        (xy -8.394 2.328)
        (xy -8.415 2.322)
        (xy -8.437 2.312)
        (xy -8.459 2.302)
        (xy -8.478 2.291)
        (xy -8.498 2.278)
        (xy -8.517 2.266)
        (xy -8.536 2.251)
        (xy -8.554 2.237)
        (xy -8.571 2.221)
        (xy -8.587 2.203)
        (xy -8.602 2.186)
        (xy -8.616 2.167)
        (xy -8.628 2.149)
        (xy -8.641 2.129)
        (xy -8.652 2.109)
        (xy -8.663 2.088)
        (xy -8.671 2.065)
        (xy -8.679 2.044)
        (xy -8.686 2.021)
        (xy -8.69 2)
        (xy -8.696 1.976)
        (xy -8.699 1.954)
        (xy -8.699 1.93)
        (xy -8.7 1.907)
        (xy -8.256 1.907)
        (xy -8.256 1.903)
      )

      (stroke (width 0.001) (type solid)) (fill solid) (layer "B.Paste"))
    (fp_poly
      (pts
        (xy -8.256 3.173)
        (xy -8.7 3.173)
        (xy -8.699 3.151)
        (xy -8.699 3.127)
        (xy -8.696 3.105)
        (xy -8.69 3.081)
        (xy -8.686 3.06)
        (xy -8.679 3.037)
        (xy -8.671 3.016)
        (xy -8.663 2.993)
        (xy -8.652 2.972)
        (xy -8.641 2.952)
        (xy -8.628 2.932)
        (xy -8.616 2.913)
        (xy -8.602 2.895)
        (xy -8.587 2.877)
        (xy -8.571 2.86)
        (xy -8.554 2.844)
        (xy -8.536 2.83)
        (xy -8.517 2.815)
        (xy -8.498 2.802)
        (xy -8.478 2.79)
        (xy -8.459 2.778)
        (xy -8.437 2.768)
        (xy -8.415 2.759)
        (xy -8.394 2.752)
        (xy -8.372 2.746)
        (xy -8.35 2.741)
        (xy -8.327 2.735)
        (xy -8.304 2.733)
        (xy -8.279 2.731)
        (xy -8.256 2.73)
        (xy -8.232 2.731)
        (xy -8.209 2.733)
        (xy -8.186 2.735)
        (xy -8.163 2.741)
        (xy -8.141 2.746)
        (xy -8.118 2.752)
        (xy -8.096 2.76)
        (xy -8.074 2.768)
        (xy -8.054 2.779)
        (xy -8.033 2.79)
        (xy -8.013 2.802)
        (xy -7.994 2.815)
        (xy -7.975 2.83)
        (xy -7.957 2.844)
        (xy -7.941 2.86)
        (xy -7.925 2.877)
        (xy -7.909 2.895)
        (xy -7.895 2.913)
        (xy -7.882 2.933)
        (xy -7.87 2.953)
        (xy -7.859 2.973)
        (xy -7.848 2.995)
        (xy -7.84 3.016)
        (xy -7.832 3.037)
        (xy -7.826 3.06)
        (xy -7.821 3.082)
        (xy -7.816 3.105)
        (xy -7.813 3.129)
        (xy -7.811 3.153)
        (xy -7.81 3.175)
        (xy -7.811 3.198)
        (xy -7.813 3.222)
        (xy -7.816 3.246)
        (xy -7.821 3.268)
        (xy -7.826 3.29)
        (xy -7.832 3.314)
        (xy -7.84 3.335)
        (xy -7.848 3.356)
        (xy -7.859 3.377)
        (xy -7.87 3.397)
        (xy -7.882 3.417)
        (xy -7.895 3.437)
        (xy -7.909 3.455)
        (xy -7.925 3.473)
        (xy -7.941 3.491)
        (xy -7.957 3.506)
        (xy -7.975 3.521)
        (xy -7.994 3.536)
        (xy -8.013 3.548)
        (xy -8.033 3.56)
        (xy -8.054 3.572)
        (xy -8.074 3.582)
        (xy -8.096 3.59)
        (xy -8.118 3.598)
        (xy -8.141 3.605)
        (xy -8.163 3.61)
        (xy -8.186 3.616)
        (xy -8.209 3.618)
        (xy -8.232 3.62)
        (xy -8.256 3.621)
        (xy -8.279 3.62)
        (xy -8.304 3.618)
        (xy -8.327 3.616)
        (xy -8.35 3.61)
        (xy -8.372 3.605)
        (xy -8.394 3.598)
        (xy -8.415 3.592)
        (xy -8.437 3.582)
        (xy -8.459 3.572)
        (xy -8.478 3.561)
        (xy -8.498 3.548)
        (xy -8.517 3.536)
        (xy -8.536 3.521)
        (xy -8.554 3.506)
        (xy -8.571 3.491)
        (xy -8.587 3.473)
        (xy -8.602 3.456)
        (xy -8.616 3.437)
        (xy -8.628 3.419)
        (xy -8.641 3.399)
        (xy -8.652 3.379)
        (xy -8.663 3.358)
        (xy -8.671 3.335)
        (xy -8.679 3.314)
        (xy -8.686 3.291)
        (xy -8.69 3.27)
        (xy -8.696 3.246)
        (xy -8.699 3.223)
        (xy -8.699 3.199)
        (xy -8.7 3.178)
        (xy -8.256 3.178)
        (xy -8.256 3.173)
      )

      (stroke (width 0.001) (type solid)) (fill solid) (layer "B.Paste"))
    (fp_poly
      (pts
        (xy -8.256 4.443)
        (xy -8.7 4.443)
        (xy -8.699 4.422)
        (xy -8.699 4.398)
        (xy -8.696 4.374)
        (xy -8.69 4.351)
        (xy -8.686 4.329)
        (xy -8.679 4.308)
        (xy -8.671 4.286)
        (xy -8.663 4.263)
        (xy -8.652 4.242)
        (xy -8.641 4.223)
        (xy -8.628 4.202)
        (xy -8.616 4.183)
        (xy -8.602 4.164)
        (xy -8.587 4.148)
        (xy -8.571 4.13)
        (xy -8.554 4.114)
        (xy -8.536 4.1)
        (xy -8.517 4.085)
        (xy -8.498 4.072)
        (xy -8.478 4.06)
        (xy -8.459 4.048)
        (xy -8.437 4.039)
        (xy -8.415 4.029)
        (xy -8.394 4.023)
        (xy -8.372 4.015)
        (xy -8.35 4.01)
        (xy -8.327 4.005)
        (xy -8.304 4.002)
        (xy -8.279 4.002)
        (xy -8.256 4)
        (xy -8.232 4.002)
        (xy -8.209 4.002)
        (xy -8.186 4.005)
        (xy -8.163 4.01)
        (xy -8.141 4.015)
        (xy -8.118 4.023)
        (xy -8.096 4.031)
        (xy -8.074 4.039)
        (xy -8.054 4.05)
        (xy -8.033 4.06)
        (xy -8.013 4.072)
        (xy -7.994 4.085)
        (xy -7.975 4.1)
        (xy -7.957 4.114)
        (xy -7.941 4.13)
        (xy -7.925 4.148)
        (xy -7.909 4.165)
        (xy -7.895 4.183)
        (xy -7.882 4.204)
        (xy -7.87 4.223)
        (xy -7.859 4.244)
        (xy -7.848 4.265)
        (xy -7.84 4.286)
        (xy -7.832 4.308)
        (xy -7.826 4.33)
        (xy -7.821 4.353)
        (xy -7.816 4.375)
        (xy -7.813 4.398)
        (xy -7.811 4.422)
        (xy -7.81 4.446)
        (xy -7.811 4.468)
        (xy -7.813 4.492)
        (xy -7.816 4.515)
        (xy -7.821 4.539)
        (xy -7.826 4.56)
        (xy -7.832 4.584)
        (xy -7.84 4.604)
        (xy -7.848 4.627)
        (xy -7.859 4.648)
        (xy -7.87 4.667)
        (xy -7.882 4.688)
        (xy -7.895 4.707)
        (xy -7.909 4.725)
        (xy -7.925 4.744)
        (xy -7.941 4.76)
        (xy -7.957 4.776)
        (xy -7.975 4.792)
        (xy -7.994 4.805)
        (xy -8.013 4.818)
        (xy -8.033 4.83)
        (xy -8.054 4.842)
        (xy -8.074 4.853)
        (xy -8.096 4.861)
        (xy -8.118 4.869)
        (xy -8.141 4.875)
        (xy -8.163 4.88)
        (xy -8.186 4.885)
        (xy -8.209 4.888)
        (xy -8.232 4.89)
        (xy -8.256 4.89)
        (xy -8.279 4.89)
        (xy -8.304 4.888)
        (xy -8.327 4.885)
        (xy -8.35 4.88)
        (xy -8.372 4.875)
        (xy -8.394 4.869)
        (xy -8.415 4.861)
        (xy -8.437 4.853)
        (xy -8.459 4.842)
        (xy -8.478 4.832)
        (xy -8.498 4.818)
        (xy -8.517 4.805)
        (xy -8.536 4.792)
        (xy -8.554 4.776)
        (xy -8.571 4.76)
        (xy -8.587 4.744)
        (xy -8.602 4.726)
        (xy -8.616 4.707)
        (xy -8.628 4.688)
        (xy -8.641 4.669)
        (xy -8.652 4.648)
        (xy -8.663 4.627)
        (xy -8.671 4.606)
        (xy -8.679 4.584)
        (xy -8.686 4.561)
        (xy -8.69 4.539)
        (xy -8.696 4.516)
        (xy -8.699 4.494)
        (xy -8.699 4.47)
        (xy -8.7 4.447)
        (xy -8.256 4.447)
        (xy -8.256 4.443)
      )

      (stroke (width 0.001) (type solid)) (fill solid) (layer "B.Paste"))
    (fp_poly
      (pts
        (xy -8.256 5.713)
        (xy -8.7 5.713)
        (xy -8.699 5.691)
        (xy -8.699 5.667)
        (xy -8.696 5.645)
        (xy -8.69 5.622)
        (xy -8.686 5.6)
        (xy -8.679 5.577)
        (xy -8.671 5.555)
        (xy -8.663 5.534)
        (xy -8.652 5.512)
        (xy -8.641 5.492)
        (xy -8.628 5.473)
        (xy -8.616 5.454)
        (xy -8.602 5.435)
        (xy -8.587 5.417)
        (xy -8.571 5.401)
        (xy -8.554 5.385)
        (xy -8.536 5.369)
        (xy -8.517 5.356)
        (xy -8.498 5.342)
        (xy -8.478 5.329)
        (xy -8.459 5.318)
        (xy -8.437 5.308)
        (xy -8.415 5.3)
        (xy -8.394 5.292)
        (xy -8.372 5.286)
        (xy -8.35 5.281)
        (xy -8.327 5.276)
        (xy -8.304 5.273)
        (xy -8.279 5.271)
        (xy -8.256 5.27)
        (xy -8.232 5.271)
        (xy -8.209 5.273)
        (xy -8.186 5.276)
        (xy -8.163 5.281)
        (xy -8.141 5.286)
        (xy -8.118 5.292)
        (xy -8.096 5.3)
        (xy -8.074 5.308)
        (xy -8.054 5.319)
        (xy -8.033 5.33)
        (xy -8.013 5.342)
        (xy -7.994 5.356)
        (xy -7.975 5.369)
        (xy -7.957 5.385)
        (xy -7.941 5.401)
        (xy -7.925 5.417)
        (xy -7.909 5.435)
        (xy -7.895 5.454)
        (xy -7.882 5.473)
        (xy -7.87 5.494)
        (xy -7.859 5.513)
        (xy -7.848 5.534)
        (xy -7.84 5.556)
        (xy -7.832 5.577)
        (xy -7.826 5.6)
        (xy -7.821 5.622)
        (xy -7.816 5.645)
        (xy -7.813 5.669)
        (xy -7.811 5.693)
        (xy -7.81 5.715)
        (xy -7.811 5.739)
        (xy -7.813 5.762)
        (xy -7.816 5.786)
        (xy -7.821 5.808)
        (xy -7.826 5.83)
        (xy -7.832 5.853)
        (xy -7.84 5.874)
        (xy -7.848 5.896)
        (xy -7.859 5.917)
        (xy -7.87 5.938)
        (xy -7.882 5.957)
        (xy -7.895 5.978)
        (xy -7.909 5.995)
        (xy -7.925 6.013)
        (xy -7.941 6.031)
        (xy -7.957 6.047)
        (xy -7.975 6.061)
        (xy -7.994 6.076)
        (xy -8.013 6.088)
        (xy -8.033 6.1)
        (xy -8.054 6.111)
        (xy -8.074 6.122)
        (xy -8.096 6.13)
        (xy -8.118 6.138)
        (xy -8.141 6.145)
        (xy -8.163 6.151)
        (xy -8.186 6.156)
        (xy -8.209 6.159)
        (xy -8.232 6.159)
        (xy -8.256 6.161)
        (xy -8.279 6.159)
        (xy -8.304 6.159)
        (xy -8.327 6.156)
        (xy -8.35 6.151)
        (xy -8.372 6.145)
        (xy -8.394 6.138)
        (xy -8.415 6.132)
        (xy -8.437 6.122)
        (xy -8.459 6.112)
        (xy -8.478 6.101)
        (xy -8.498 6.088)
        (xy -8.517 6.076)
        (xy -8.536 6.061)
        (xy -8.554 6.047)
        (xy -8.571 6.031)
        (xy -8.587 6.013)
        (xy -8.602 5.997)
        (xy -8.616 5.978)
        (xy -8.628 5.959)
        (xy -8.641 5.938)
        (xy -8.652 5.919)
        (xy -8.663 5.898)
        (xy -8.671 5.875)
        (xy -8.679 5.853)
        (xy -8.686 5.832)
        (xy -8.69 5.81)
        (xy -8.696 5.786)
        (xy -8.699 5.763)
        (xy -8.699 5.739)
        (xy -8.7 5.718)
        (xy -8.256 5.718)
        (xy -8.256 5.713)
      )

      (stroke (width 0.001) (type solid)) (fill solid) (layer "B.Paste"))
    (fp_poly
      (pts
        (xy -6.986 -5.717)
        (xy -7.43 -5.717)
        (xy -7.43 -5.738)
        (xy -7.428 -5.762)
        (xy -7.425 -5.785)
        (xy -7.42 -5.809)
        (xy -7.415 -5.831)
        (xy -7.409 -5.852)
        (xy -7.401 -5.874)
        (xy -7.393 -5.897)
        (xy -7.382 -5.918)
        (xy -7.372 -5.937)
        (xy -7.358 -5.958)
        (xy -7.345 -5.977)
        (xy -7.332 -5.996)
        (xy -7.316 -6.012)
        (xy -7.3 -6.03)
        (xy -7.284 -6.046)
        (xy -7.266 -6.06)
        (xy -7.247 -6.075)
        (xy -7.228 -6.087)
        (xy -7.209 -6.1)
        (xy -7.188 -6.111)
        (xy -7.167 -6.121)
        (xy -7.145 -6.131)
        (xy -7.124 -6.137)
        (xy -7.101 -6.144)
        (xy -7.079 -6.15)
        (xy -7.056 -6.155)
        (xy -7.034 -6.158)
        (xy -7.01 -6.158)
        (xy -6.986 -6.16)
        (xy -6.962 -6.158)
        (xy -6.938 -6.158)
        (xy -6.915 -6.155)
        (xy -6.893 -6.15)
        (xy -6.87 -6.144)
        (xy -6.848 -6.137)
        (xy -6.826 -6.129)
        (xy -6.805 -6.121)
        (xy -6.784 -6.11)
        (xy -6.763 -6.099)
        (xy -6.744 -6.087)
        (xy -6.723 -6.075)
        (xy -6.705 -6.06)
        (xy -6.688 -6.046)
        (xy -6.67 -6.03)
        (xy -6.654 -6.012)
        (xy -6.64 -5.994)
        (xy -6.625 -5.977)
        (xy -6.612 -5.956)
        (xy -6.6 -5.937)
        (xy -6.59 -5.916)
        (xy -6.579 -5.895)
        (xy -6.571 -5.873)
        (xy -6.563 -5.852)
        (xy -6.555 -5.829)
        (xy -6.55 -5.807)
        (xy -6.545 -5.785)
        (xy -6.542 -5.761)
        (xy -6.542 -5.738)
        (xy -6.54 -5.714)
        (xy -6.542 -5.692)
        (xy -6.542 -5.668)
        (xy -6.545 -5.644)
        (xy -6.55 -5.621)
        (xy -6.555 -5.599)
        (xy -6.563 -5.576)
        (xy -6.571 -5.555)
        (xy -6.579 -5.533)
        (xy -6.59 -5.512)
        (xy -6.6 -5.491)
        (xy -6.612 -5.472)
        (xy -6.625 -5.453)
        (xy -6.64 -5.434)
        (xy -6.654 -5.416)
        (xy -6.67 -5.4)
        (xy -6.688 -5.384)
        (xy -6.705 -5.368)
        (xy -6.723 -5.355)
        (xy -6.744 -5.341)
        (xy -6.763 -5.329)
        (xy -6.784 -5.318)
        (xy -6.805 -5.307)
        (xy -6.826 -5.299)
        (xy -6.848 -5.291)
        (xy -6.87 -5.285)
        (xy -6.893 -5.28)
        (xy -6.915 -5.275)
        (xy -6.938 -5.272)
        (xy -6.962 -5.27)
        (xy -6.986 -5.269)
        (xy -7.01 -5.27)
        (xy -7.034 -5.272)
        (xy -7.056 -5.275)
        (xy -7.079 -5.28)
        (xy -7.101 -5.285)
        (xy -7.124 -5.291)
        (xy -7.145 -5.299)
        (xy -7.167 -5.307)
        (xy -7.188 -5.317)
        (xy -7.209 -5.328)
        (xy -7.228 -5.341)
        (xy -7.247 -5.355)
        (xy -7.266 -5.368)
        (xy -7.284 -5.384)
        (xy -7.3 -5.4)
        (xy -7.316 -5.416)
        (xy -7.332 -5.434)
        (xy -7.345 -5.453)
        (xy -7.358 -5.472)
        (xy -7.372 -5.491)
        (xy -7.382 -5.511)
        (xy -7.393 -5.533)
        (xy -7.401 -5.554)
        (xy -7.409 -5.576)
        (xy -7.415 -5.599)
        (xy -7.42 -5.621)
        (xy -7.425 -5.644)
        (xy -7.428 -5.666)
        (xy -7.43 -5.69)
        (xy -7.43 -5.712)
        (xy -6.986 -5.712)
        (xy -6.986 -5.717)
      )

      (stroke (width 0.001) (type solid)) (fill solid) (layer "B.Paste"))
    (fp_poly
      (pts
        (xy -6.986 -3.177)
        (xy -7.43 -3.177)
        (xy -7.43 -3.198)
        (xy -7.428 -3.222)
        (xy -7.425 -3.245)
        (xy -7.42 -3.269)
        (xy -7.415 -3.29)
        (xy -7.409 -3.313)
        (xy -7.401 -3.334)
        (xy -7.393 -3.357)
        (xy -7.382 -3.378)
        (xy -7.372 -3.398)
        (xy -7.358 -3.418)
        (xy -7.345 -3.436)
        (xy -7.332 -3.455)
        (xy -7.316 -3.472)
        (xy -7.3 -3.49)
        (xy -7.284 -3.505)
        (xy -7.266 -3.52)
        (xy -7.247 -3.535)
        (xy -7.228 -3.547)
        (xy -7.209 -3.56)
        (xy -7.188 -3.571)
        (xy -7.167 -3.581)
        (xy -7.145 -3.591)
        (xy -7.124 -3.597)
        (xy -7.101 -3.604)
        (xy -7.079 -3.609)
        (xy -7.056 -3.615)
        (xy -7.034 -3.617)
        (xy -7.01 -3.619)
        (xy -6.986 -3.62)
        (xy -6.962 -3.619)
        (xy -6.938 -3.617)
        (xy -6.915 -3.615)
        (xy -6.893 -3.609)
        (xy -6.87 -3.604)
        (xy -6.848 -3.597)
        (xy -6.826 -3.589)
        (xy -6.805 -3.581)
        (xy -6.784 -3.571)
        (xy -6.763 -3.559)
        (xy -6.744 -3.547)
        (xy -6.723 -3.535)
        (xy -6.705 -3.52)
        (xy -6.688 -3.505)
        (xy -6.67 -3.49)
        (xy -6.654 -3.472)
        (xy -6.64 -3.454)
        (xy -6.625 -3.436)
        (xy -6.612 -3.416)
        (xy -6.6 -3.396)
        (xy -6.59 -3.376)
        (xy -6.579 -3.355)
        (xy -6.571 -3.334)
        (xy -6.563 -3.313)
        (xy -6.555 -3.289)
        (xy -6.55 -3.267)
        (xy -6.545 -3.245)
        (xy -6.542 -3.221)
        (xy -6.542 -3.197)
        (xy -6.54 -3.174)
        (xy -6.542 -3.152)
        (xy -6.542 -3.128)
        (xy -6.545 -3.104)
        (xy -6.55 -3.081)
        (xy -6.555 -3.059)
        (xy -6.563 -3.036)
        (xy -6.571 -3.015)
        (xy -6.579 -2.994)
        (xy -6.59 -2.972)
        (xy -6.6 -2.951)
        (xy -6.612 -2.932)
        (xy -6.625 -2.912)
        (xy -6.64 -2.894)
        (xy -6.654 -2.876)
        (xy -6.67 -2.859)
        (xy -6.688 -2.843)
        (xy -6.705 -2.829)
        (xy -6.723 -2.814)
        (xy -6.744 -2.801)
        (xy -6.763 -2.789)
        (xy -6.784 -2.778)
        (xy -6.805 -2.767)
        (xy -6.826 -2.759)
        (xy -6.848 -2.751)
        (xy -6.87 -2.745)
        (xy -6.893 -2.74)
        (xy -6.915 -2.734)
        (xy -6.938 -2.732)
        (xy -6.962 -2.73)
        (xy -6.986 -2.729)
        (xy -7.01 -2.73)
        (xy -7.034 -2.732)
        (xy -7.056 -2.734)
        (xy -7.079 -2.74)
        (xy -7.101 -2.745)
        (xy -7.124 -2.751)
        (xy -7.145 -2.758)
        (xy -7.167 -2.767)
        (xy -7.188 -2.777)
        (xy -7.209 -2.789)
        (xy -7.228 -2.801)
        (xy -7.247 -2.814)
        (xy -7.266 -2.829)
        (xy -7.284 -2.843)
        (xy -7.3 -2.859)
        (xy -7.316 -2.876)
        (xy -7.332 -2.894)
        (xy -7.345 -2.912)
        (xy -7.358 -2.931)
        (xy -7.372 -2.951)
        (xy -7.382 -2.971)
        (xy -7.393 -2.992)
        (xy -7.401 -3.015)
        (xy -7.409 -3.036)
        (xy -7.415 -3.059)
        (xy -7.42 -3.08)
        (xy -7.425 -3.104)
        (xy -7.428 -3.126)
        (xy -7.43 -3.15)
        (xy -7.43 -3.172)
        (xy -6.986 -3.172)
        (xy -6.986 -3.177)
      )

      (stroke (width 0.001) (type solid)) (fill solid) (layer "B.Paste"))
    (fp_poly
      (pts
        (xy -6.986 1.903)
        (xy -7.43 1.903)
        (xy -7.43 1.881)
        (xy -7.428 1.857)
        (xy -7.425 1.835)
        (xy -7.42 1.811)
        (xy -7.415 1.789)
        (xy -7.409 1.767)
        (xy -7.401 1.746)
        (xy -7.393 1.724)
        (xy -7.382 1.702)
        (xy -7.372 1.682)
        (xy -7.358 1.662)
        (xy -7.345 1.643)
        (xy -7.332 1.625)
        (xy -7.316 1.607)
        (xy -7.3 1.591)
        (xy -7.284 1.575)
        (xy -7.266 1.559)
        (xy -7.247 1.545)
        (xy -7.228 1.532)
        (xy -7.209 1.519)
        (xy -7.188 1.508)
        (xy -7.167 1.498)
        (xy -7.145 1.49)
        (xy -7.124 1.482)
        (xy -7.101 1.476)
        (xy -7.079 1.47)
        (xy -7.056 1.466)
        (xy -7.034 1.462)
        (xy -7.01 1.462)
        (xy -6.986 1.46)
        (xy -6.962 1.462)
        (xy -6.938 1.462)
        (xy -6.915 1.466)
        (xy -6.893 1.47)
        (xy -6.87 1.476)
        (xy -6.848 1.482)
        (xy -6.826 1.49)
        (xy -6.805 1.498)
        (xy -6.784 1.509)
        (xy -6.763 1.52)
        (xy -6.744 1.532)
        (xy -6.723 1.545)
        (xy -6.705 1.559)
        (xy -6.688 1.575)
        (xy -6.67 1.591)
        (xy -6.654 1.607)
        (xy -6.64 1.625)
        (xy -6.625 1.643)
        (xy -6.612 1.663)
        (xy -6.6 1.684)
        (xy -6.59 1.704)
        (xy -6.579 1.724)
        (xy -6.571 1.746)
        (xy -6.563 1.767)
        (xy -6.555 1.79)
        (xy -6.55 1.813)
        (xy -6.545 1.835)
        (xy -6.542 1.859)
        (xy -6.542 1.882)
        (xy -6.54 1.905)
        (xy -6.542 1.928)
        (xy -6.542 1.952)
        (xy -6.545 1.976)
        (xy -6.55 1.998)
        (xy -6.555 2.02)
        (xy -6.563 2.044)
        (xy -6.571 2.065)
        (xy -6.579 2.086)
        (xy -6.59 2.108)
        (xy -6.6 2.127)
        (xy -6.612 2.147)
        (xy -6.625 2.167)
        (xy -6.64 2.186)
        (xy -6.654 2.203)
        (xy -6.67 2.221)
        (xy -6.688 2.237)
        (xy -6.705 2.251)
        (xy -6.723 2.266)
        (xy -6.744 2.278)
        (xy -6.763 2.29)
        (xy -6.784 2.302)
        (xy -6.805 2.312)
        (xy -6.826 2.32)
        (xy -6.848 2.328)
        (xy -6.87 2.335)
        (xy -6.893 2.34)
        (xy -6.915 2.346)
        (xy -6.938 2.348)
        (xy -6.962 2.35)
        (xy -6.986 2.351)
        (xy -7.01 2.35)
        (xy -7.034 2.348)
        (xy -7.056 2.346)
        (xy -7.079 2.34)
        (xy -7.101 2.335)
        (xy -7.124 2.328)
        (xy -7.145 2.322)
        (xy -7.167 2.312)
        (xy -7.188 2.302)
        (xy -7.209 2.291)
        (xy -7.228 2.278)
        (xy -7.247 2.266)
        (xy -7.266 2.251)
        (xy -7.284 2.237)
        (xy -7.3 2.221)
        (xy -7.316 2.203)
        (xy -7.332 2.186)
        (xy -7.345 2.167)
        (xy -7.358 2.149)
        (xy -7.372 2.129)
        (xy -7.382 2.109)
        (xy -7.393 2.088)
        (xy -7.401 2.065)
        (xy -7.409 2.044)
        (xy -7.415 2.021)
        (xy -7.42 2)
        (xy -7.425 1.976)
        (xy -7.428 1.954)
        (xy -7.43 1.93)
        (xy -7.43 1.907)
        (xy -6.986 1.907)
        (xy -6.986 1.903)
      )

      (stroke (width 0.001) (type solid)) (fill solid) (layer "B.Paste"))
    (fp_poly
      (pts
        (xy -6.986 3.173)
        (xy -7.43 3.173)
        (xy -7.43 3.151)
        (xy -7.428 3.127)
        (xy -7.425 3.105)
        (xy -7.42 3.081)
        (xy -7.415 3.06)
        (xy -7.409 3.037)
        (xy -7.401 3.016)
        (xy -7.393 2.993)
        (xy -7.382 2.972)
        (xy -7.372 2.952)
        (xy -7.358 2.932)
        (xy -7.345 2.913)
        (xy -7.332 2.895)
        (xy -7.316 2.877)
        (xy -7.3 2.86)
        (xy -7.284 2.844)
        (xy -7.266 2.83)
        (xy -7.247 2.815)
        (xy -7.228 2.802)
        (xy -7.209 2.79)
        (xy -7.188 2.778)
        (xy -7.167 2.768)
        (xy -7.145 2.759)
        (xy -7.124 2.752)
        (xy -7.101 2.746)
        (xy -7.079 2.741)
        (xy -7.056 2.735)
        (xy -7.034 2.733)
        (xy -7.01 2.731)
        (xy -6.986 2.73)
        (xy -6.962 2.731)
        (xy -6.938 2.733)
        (xy -6.915 2.735)
        (xy -6.893 2.741)
        (xy -6.87 2.746)
        (xy -6.848 2.752)
        (xy -6.826 2.76)
        (xy -6.805 2.768)
        (xy -6.784 2.779)
        (xy -6.763 2.79)
        (xy -6.744 2.802)
        (xy -6.723 2.815)
        (xy -6.705 2.83)
        (xy -6.688 2.844)
        (xy -6.67 2.86)
        (xy -6.654 2.877)
        (xy -6.64 2.895)
        (xy -6.625 2.913)
        (xy -6.612 2.933)
        (xy -6.6 2.952)
        (xy -6.59 2.973)
        (xy -6.579 2.995)
        (xy -6.571 3.016)
        (xy -6.563 3.037)
        (xy -6.555 3.06)
        (xy -6.55 3.082)
        (xy -6.545 3.105)
        (xy -6.542 3.129)
        (xy -6.542 3.153)
        (xy -6.54 3.175)
        (xy -6.542 3.198)
        (xy -6.542 3.222)
        (xy -6.545 3.246)
        (xy -6.55 3.268)
        (xy -6.555 3.29)
        (xy -6.563 3.314)
        (xy -6.571 3.335)
        (xy -6.579 3.356)
        (xy -6.59 3.377)
        (xy -6.6 3.397)
        (xy -6.612 3.417)
        (xy -6.625 3.437)
        (xy -6.64 3.455)
        (xy -6.654 3.473)
        (xy -6.67 3.491)
        (xy -6.688 3.506)
        (xy -6.705 3.521)
        (xy -6.723 3.536)
        (xy -6.744 3.548)
        (xy -6.763 3.56)
        (xy -6.784 3.572)
        (xy -6.805 3.582)
        (xy -6.826 3.59)
        (xy -6.848 3.598)
        (xy -6.87 3.605)
        (xy -6.893 3.61)
        (xy -6.915 3.616)
        (xy -6.938 3.618)
        (xy -6.962 3.62)
        (xy -6.986 3.621)
        (xy -7.01 3.62)
        (xy -7.034 3.618)
        (xy -7.056 3.616)
        (xy -7.079 3.61)
        (xy -7.101 3.605)
        (xy -7.124 3.598)
        (xy -7.145 3.592)
        (xy -7.167 3.582)
        (xy -7.188 3.572)
        (xy -7.209 3.561)
        (xy -7.228 3.548)
        (xy -7.247 3.536)
        (xy -7.266 3.521)
        (xy -7.284 3.506)
        (xy -7.3 3.491)
        (xy -7.316 3.473)
        (xy -7.332 3.456)
        (xy -7.345 3.437)
        (xy -7.358 3.419)
        (xy -7.372 3.399)
        (xy -7.382 3.379)
        (xy -7.393 3.358)
        (xy -7.401 3.335)
        (xy -7.409 3.314)
        (xy -7.415 3.291)
        (xy -7.42 3.27)
        (xy -7.425 3.246)
        (xy -7.428 3.223)
        (xy -7.43 3.199)
        (xy -7.43 3.178)
        (xy -6.986 3.178)
        (xy -6.986 3.173)
      )

      (stroke (width 0.001) (type solid)) (fill solid) (layer "B.Paste"))
    (fp_poly
      (pts
        (xy -6.986 4.443)
        (xy -7.43 4.443)
        (xy -7.43 4.422)
        (xy -7.428 4.398)
        (xy -7.425 4.374)
        (xy -7.42 4.351)
        (xy -7.415 4.329)
        (xy -7.409 4.308)
        (xy -7.401 4.286)
        (xy -7.393 4.263)
        (xy -7.382 4.242)
        (xy -7.372 4.223)
        (xy -7.358 4.202)
        (xy -7.345 4.183)
        (xy -7.332 4.164)
        (xy -7.316 4.148)
        (xy -7.3 4.13)
        (xy -7.284 4.114)
        (xy -7.266 4.1)
        (xy -7.247 4.085)
        (xy -7.228 4.072)
        (xy -7.209 4.06)
        (xy -7.188 4.048)
        (xy -7.167 4.039)
        (xy -7.145 4.029)
        (xy -7.124 4.023)
        (xy -7.101 4.015)
        (xy -7.079 4.01)
        (xy -7.056 4.005)
        (xy -7.034 4.002)
        (xy -7.01 4.002)
        (xy -6.986 4)
        (xy -6.962 4.002)
        (xy -6.938 4.002)
        (xy -6.915 4.005)
        (xy -6.893 4.01)
        (xy -6.87 4.015)
        (xy -6.848 4.023)
        (xy -6.826 4.031)
        (xy -6.805 4.039)
        (xy -6.784 4.05)
        (xy -6.763 4.06)
        (xy -6.744 4.072)
        (xy -6.723 4.085)
        (xy -6.705 4.1)
        (xy -6.688 4.114)
        (xy -6.67 4.13)
        (xy -6.654 4.148)
        (xy -6.64 4.165)
        (xy -6.625 4.183)
        (xy -6.612 4.204)
        (xy -6.6 4.223)
        (xy -6.59 4.244)
        (xy -6.579 4.265)
        (xy -6.571 4.286)
        (xy -6.563 4.308)
        (xy -6.555 4.33)
        (xy -6.55 4.353)
        (xy -6.545 4.375)
        (xy -6.542 4.398)
        (xy -6.542 4.422)
        (xy -6.54 4.446)
        (xy -6.542 4.468)
        (xy -6.542 4.492)
        (xy -6.545 4.515)
        (xy -6.55 4.539)
        (xy -6.555 4.56)
        (xy -6.563 4.584)
        (xy -6.571 4.604)
        (xy -6.579 4.627)
        (xy -6.59 4.648)
        (xy -6.6 4.669)
        (xy -6.612 4.688)
        (xy -6.625 4.707)
        (xy -6.64 4.725)
        (xy -6.654 4.744)
        (xy -6.67 4.76)
        (xy -6.688 4.776)
        (xy -6.705 4.792)
        (xy -6.723 4.805)
        (xy -6.744 4.818)
        (xy -6.763 4.83)
        (xy -6.784 4.842)
        (xy -6.805 4.853)
        (xy -6.826 4.861)
        (xy -6.848 4.869)
        (xy -6.87 4.875)
        (xy -6.893 4.88)
        (xy -6.915 4.885)
        (xy -6.938 4.888)
        (xy -6.962 4.89)
        (xy -6.986 4.89)
        (xy -7.01 4.89)
        (xy -7.034 4.888)
        (xy -7.056 4.885)
        (xy -7.079 4.88)
        (xy -7.101 4.875)
        (xy -7.124 4.869)
        (xy -7.145 4.861)
        (xy -7.167 4.853)
        (xy -7.188 4.842)
        (xy -7.209 4.832)
        (xy -7.228 4.818)
        (xy -7.247 4.805)
        (xy -7.266 4.792)
        (xy -7.284 4.776)
        (xy -7.3 4.76)
        (xy -7.316 4.744)
        (xy -7.332 4.726)
        (xy -7.345 4.707)
        (xy -7.358 4.688)
        (xy -7.372 4.669)
        (xy -7.382 4.648)
        (xy -7.393 4.627)
        (xy -7.401 4.606)
        (xy -7.409 4.584)
        (xy -7.415 4.561)
        (xy -7.42 4.539)
        (xy -7.425 4.516)
        (xy -7.428 4.494)
        (xy -7.43 4.47)
        (xy -7.43 4.447)
        (xy -6.986 4.447)
        (xy -6.986 4.443)
      )

      (stroke (width 0.001) (type solid)) (fill solid) (layer "B.Paste"))
    (fp_poly
      (pts
        (xy -6.986 5.713)
        (xy -7.43 5.713)
        (xy -7.43 5.691)
        (xy -7.428 5.667)
        (xy -7.425 5.645)
        (xy -7.42 5.622)
        (xy -7.415 5.6)
        (xy -7.409 5.577)
        (xy -7.401 5.555)
        (xy -7.393 5.534)
        (xy -7.382 5.512)
        (xy -7.372 5.492)
        (xy -7.358 5.473)
        (xy -7.345 5.454)
        (xy -7.332 5.435)
        (xy -7.316 5.417)
        (xy -7.3 5.401)
        (xy -7.284 5.385)
        (xy -7.266 5.369)
        (xy -7.247 5.356)
        (xy -7.228 5.342)
        (xy -7.209 5.329)
        (xy -7.188 5.318)
        (xy -7.167 5.308)
        (xy -7.145 5.3)
        (xy -7.124 5.292)
        (xy -7.101 5.286)
        (xy -7.079 5.281)
        (xy -7.056 5.276)
        (xy -7.034 5.273)
        (xy -7.01 5.271)
        (xy -6.986 5.27)
        (xy -6.962 5.271)
        (xy -6.938 5.273)
        (xy -6.915 5.276)
        (xy -6.893 5.281)
        (xy -6.87 5.286)
        (xy -6.848 5.292)
        (xy -6.826 5.3)
        (xy -6.805 5.308)
        (xy -6.784 5.319)
        (xy -6.763 5.33)
        (xy -6.744 5.342)
        (xy -6.723 5.356)
        (xy -6.705 5.369)
        (xy -6.688 5.385)
        (xy -6.67 5.401)
        (xy -6.654 5.417)
        (xy -6.64 5.435)
        (xy -6.625 5.454)
        (xy -6.612 5.473)
        (xy -6.6 5.492)
        (xy -6.59 5.513)
        (xy -6.579 5.534)
        (xy -6.571 5.556)
        (xy -6.563 5.577)
        (xy -6.555 5.6)
        (xy -6.55 5.622)
        (xy -6.545 5.645)
        (xy -6.542 5.669)
        (xy -6.542 5.693)
        (xy -6.54 5.715)
        (xy -6.542 5.739)
        (xy -6.542 5.762)
        (xy -6.545 5.786)
        (xy -6.55 5.808)
        (xy -6.555 5.83)
        (xy -6.563 5.853)
        (xy -6.571 5.874)
        (xy -6.579 5.896)
        (xy -6.59 5.917)
        (xy -6.6 5.938)
        (xy -6.612 5.957)
        (xy -6.625 5.978)
        (xy -6.64 5.995)
        (xy -6.654 6.013)
        (xy -6.67 6.031)
        (xy -6.688 6.047)
        (xy -6.705 6.061)
        (xy -6.723 6.076)
        (xy -6.744 6.088)
        (xy -6.763 6.1)
        (xy -6.784 6.111)
        (xy -6.805 6.122)
        (xy -6.826 6.13)
        (xy -6.848 6.138)
        (xy -6.87 6.145)
        (xy -6.893 6.151)
        (xy -6.915 6.156)
        (xy -6.938 6.159)
        (xy -6.962 6.159)
        (xy -6.986 6.161)
        (xy -7.01 6.159)
        (xy -7.034 6.159)
        (xy -7.056 6.156)
        (xy -7.079 6.151)
        (xy -7.101 6.145)
        (xy -7.124 6.138)
        (xy -7.145 6.132)
        (xy -7.167 6.122)
        (xy -7.188 6.112)
        (xy -7.209 6.101)
        (xy -7.228 6.088)
        (xy -7.247 6.076)
        (xy -7.266 6.061)
        (xy -7.284 6.047)
        (xy -7.3 6.031)
        (xy -7.316 6.013)
        (xy -7.332 5.997)
        (xy -7.345 5.978)
        (xy -7.358 5.959)
        (xy -7.372 5.938)
        (xy -7.382 5.919)
        (xy -7.393 5.898)
        (xy -7.401 5.875)
        (xy -7.409 5.853)
        (xy -7.415 5.832)
        (xy -7.42 5.81)
        (xy -7.425 5.786)
        (xy -7.428 5.763)
        (xy -7.43 5.739)
        (xy -7.43 5.718)
        (xy -6.986 5.718)
        (xy -6.986 5.713)
      )

      (stroke (width 0.001) (type solid)) (fill solid) (layer "B.Paste"))
    (fp_poly
      (pts
        (xy -5.715 -5.717)
        (xy -6.161 -5.717)
        (xy -6.159 -5.738)
        (xy -6.159 -5.762)
        (xy -6.156 -5.785)
        (xy -6.151 -5.809)
        (xy -6.145 -5.831)
        (xy -6.138 -5.852)
        (xy -6.132 -5.874)
        (xy -6.122 -5.897)
        (xy -6.112 -5.918)
        (xy -6.101 -5.937)
        (xy -6.088 -5.958)
        (xy -6.076 -5.977)
        (xy -6.061 -5.996)
        (xy -6.047 -6.012)
        (xy -6.031 -6.03)
        (xy -6.013 -6.046)
        (xy -5.997 -6.06)
        (xy -5.978 -6.075)
        (xy -5.959 -6.087)
        (xy -5.938 -6.1)
        (xy -5.919 -6.111)
        (xy -5.898 -6.121)
        (xy -5.875 -6.131)
        (xy -5.853 -6.137)
        (xy -5.832 -6.144)
        (xy -5.81 -6.15)
        (xy -5.786 -6.155)
        (xy -5.763 -6.158)
        (xy -5.739 -6.158)
        (xy -5.715 -6.16)
        (xy -5.693 -6.158)
        (xy -5.669 -6.158)
        (xy -5.645 -6.155)
        (xy -5.622 -6.15)
        (xy -5.6 -6.144)
        (xy -5.577 -6.137)
        (xy -5.556 -6.129)
        (xy -5.534 -6.121)
        (xy -5.513 -6.11)
        (xy -5.492 -6.099)
        (xy -5.473 -6.087)
        (xy -5.454 -6.075)
        (xy -5.435 -6.06)
        (xy -5.417 -6.046)
        (xy -5.401 -6.03)
        (xy -5.385 -6.012)
        (xy -5.369 -5.994)
        (xy -5.356 -5.977)
        (xy -5.342 -5.956)
        (xy -5.33 -5.937)
        (xy -5.319 -5.916)
        (xy -5.308 -5.895)
        (xy -5.3 -5.873)
        (xy -5.292 -5.852)
        (xy -5.286 -5.829)
        (xy -5.281 -5.807)
        (xy -5.276 -5.785)
        (xy -5.273 -5.761)
        (xy -5.271 -5.738)
        (xy -5.27 -5.714)
        (xy -5.271 -5.692)
        (xy -5.273 -5.668)
        (xy -5.276 -5.644)
        (xy -5.281 -5.621)
        (xy -5.286 -5.599)
        (xy -5.292 -5.576)
        (xy -5.3 -5.555)
        (xy -5.308 -5.533)
        (xy -5.319 -5.512)
        (xy -5.33 -5.491)
        (xy -5.342 -5.472)
        (xy -5.356 -5.453)
        (xy -5.369 -5.434)
        (xy -5.385 -5.416)
        (xy -5.401 -5.4)
        (xy -5.417 -5.384)
        (xy -5.435 -5.368)
        (xy -5.454 -5.355)
        (xy -5.473 -5.341)
        (xy -5.492 -5.329)
        (xy -5.513 -5.318)
        (xy -5.534 -5.307)
        (xy -5.556 -5.299)
        (xy -5.577 -5.291)
        (xy -5.6 -5.285)
        (xy -5.622 -5.28)
        (xy -5.645 -5.275)
        (xy -5.669 -5.272)
        (xy -5.693 -5.27)
        (xy -5.715 -5.269)
        (xy -5.739 -5.27)
        (xy -5.763 -5.272)
        (xy -5.786 -5.275)
        (xy -5.81 -5.28)
        (xy -5.832 -5.285)
        (xy -5.853 -5.291)
        (xy -5.875 -5.299)
        (xy -5.898 -5.307)
        (xy -5.919 -5.317)
        (xy -5.938 -5.328)
        (xy -5.959 -5.341)
        (xy -5.978 -5.355)
        (xy -5.997 -5.368)
        (xy -6.013 -5.384)
        (xy -6.031 -5.4)
        (xy -6.047 -5.416)
        (xy -6.061 -5.434)
        (xy -6.076 -5.453)
        (xy -6.088 -5.472)
        (xy -6.101 -5.491)
        (xy -6.112 -5.511)
        (xy -6.122 -5.533)
        (xy -6.132 -5.554)
        (xy -6.138 -5.576)
        (xy -6.145 -5.599)
        (xy -6.151 -5.621)
        (xy -6.156 -5.644)
        (xy -6.159 -5.666)
        (xy -6.159 -5.69)
        (xy -6.161 -5.712)
        (xy -5.715 -5.712)
        (xy -5.715 -5.717)
      )

      (stroke (width 0.001) (type solid)) (fill solid) (layer "B.Paste"))
    (fp_poly
      (pts
        (xy -5.715 -3.177)
        (xy -6.161 -3.177)
        (xy -6.159 -3.198)
        (xy -6.159 -3.222)
        (xy -6.156 -3.245)
        (xy -6.151 -3.269)
        (xy -6.145 -3.29)
        (xy -6.138 -3.313)
        (xy -6.132 -3.334)
        (xy -6.122 -3.357)
        (xy -6.112 -3.378)
        (xy -6.101 -3.398)
        (xy -6.088 -3.418)
        (xy -6.076 -3.436)
        (xy -6.061 -3.455)
        (xy -6.047 -3.472)
        (xy -6.031 -3.49)
        (xy -6.013 -3.505)
        (xy -5.997 -3.52)
        (xy -5.978 -3.535)
        (xy -5.959 -3.547)
        (xy -5.938 -3.56)
        (xy -5.919 -3.571)
        (xy -5.898 -3.581)
        (xy -5.875 -3.591)
        (xy -5.853 -3.597)
        (xy -5.832 -3.604)
        (xy -5.81 -3.609)
        (xy -5.786 -3.615)
        (xy -5.763 -3.617)
        (xy -5.739 -3.619)
        (xy -5.715 -3.62)
        (xy -5.693 -3.619)
        (xy -5.669 -3.617)
        (xy -5.645 -3.615)
        (xy -5.622 -3.609)
        (xy -5.6 -3.604)
        (xy -5.577 -3.597)
        (xy -5.556 -3.589)
        (xy -5.534 -3.581)
        (xy -5.513 -3.571)
        (xy -5.492 -3.559)
        (xy -5.473 -3.547)
        (xy -5.454 -3.535)
        (xy -5.435 -3.52)
        (xy -5.417 -3.505)
        (xy -5.401 -3.49)
        (xy -5.385 -3.472)
        (xy -5.369 -3.454)
        (xy -5.356 -3.436)
        (xy -5.342 -3.416)
        (xy -5.33 -3.396)
        (xy -5.319 -3.376)
        (xy -5.308 -3.355)
        (xy -5.3 -3.334)
        (xy -5.292 -3.313)
        (xy -5.286 -3.289)
        (xy -5.281 -3.267)
        (xy -5.276 -3.245)
        (xy -5.273 -3.221)
        (xy -5.271 -3.197)
        (xy -5.27 -3.174)
        (xy -5.271 -3.152)
        (xy -5.273 -3.128)
        (xy -5.276 -3.104)
        (xy -5.281 -3.081)
        (xy -5.286 -3.059)
        (xy -5.292 -3.036)
        (xy -5.3 -3.015)
        (xy -5.308 -2.994)
        (xy -5.319 -2.972)
        (xy -5.33 -2.951)
        (xy -5.342 -2.932)
        (xy -5.356 -2.912)
        (xy -5.369 -2.894)
        (xy -5.385 -2.876)
        (xy -5.401 -2.859)
        (xy -5.417 -2.843)
        (xy -5.435 -2.829)
        (xy -5.454 -2.814)
        (xy -5.473 -2.801)
        (xy -5.492 -2.789)
        (xy -5.513 -2.778)
        (xy -5.534 -2.767)
        (xy -5.556 -2.759)
        (xy -5.577 -2.751)
        (xy -5.6 -2.745)
        (xy -5.622 -2.74)
        (xy -5.645 -2.734)
        (xy -5.669 -2.732)
        (xy -5.693 -2.73)
        (xy -5.715 -2.729)
        (xy -5.739 -2.73)
        (xy -5.763 -2.732)
        (xy -5.786 -2.734)
        (xy -5.81 -2.74)
        (xy -5.832 -2.745)
        (xy -5.853 -2.751)
        (xy -5.875 -2.758)
        (xy -5.898 -2.767)
        (xy -5.919 -2.777)
        (xy -5.938 -2.789)
        (xy -5.959 -2.801)
        (xy -5.978 -2.814)
        (xy -5.997 -2.829)
        (xy -6.013 -2.843)
        (xy -6.031 -2.859)
        (xy -6.047 -2.876)
        (xy -6.061 -2.894)
        (xy -6.076 -2.912)
        (xy -6.088 -2.931)
        (xy -6.101 -2.951)
        (xy -6.112 -2.971)
        (xy -6.122 -2.992)
        (xy -6.132 -3.015)
        (xy -6.138 -3.036)
        (xy -6.145 -3.059)
        (xy -6.151 -3.08)
        (xy -6.156 -3.104)
        (xy -6.159 -3.126)
        (xy -6.159 -3.15)
        (xy -6.161 -3.172)
        (xy -5.715 -3.172)
        (xy -5.715 -3.177)
      )

      (stroke (width 0.001) (type solid)) (fill solid) (layer "B.Paste"))
    (fp_poly
      (pts
        (xy -5.715 1.903)
        (xy -6.161 1.903)
        (xy -6.159 1.881)
        (xy -6.159 1.857)
        (xy -6.156 1.835)
        (xy -6.151 1.811)
        (xy -6.145 1.789)
        (xy -6.138 1.767)
        (xy -6.132 1.746)
        (xy -6.122 1.724)
        (xy -6.112 1.702)
        (xy -6.101 1.682)
        (xy -6.088 1.662)
        (xy -6.076 1.643)
        (xy -6.061 1.625)
        (xy -6.047 1.607)
        (xy -6.031 1.591)
        (xy -6.013 1.575)
        (xy -5.997 1.559)
        (xy -5.978 1.545)
        (xy -5.959 1.532)
        (xy -5.938 1.519)
        (xy -5.919 1.508)
        (xy -5.898 1.498)
        (xy -5.875 1.49)
        (xy -5.853 1.482)
        (xy -5.832 1.476)
        (xy -5.81 1.47)
        (xy -5.786 1.466)
        (xy -5.763 1.462)
        (xy -5.739 1.462)
        (xy -5.715 1.46)
        (xy -5.693 1.462)
        (xy -5.669 1.462)
        (xy -5.645 1.466)
        (xy -5.622 1.47)
        (xy -5.6 1.476)
        (xy -5.577 1.482)
        (xy -5.556 1.49)
        (xy -5.534 1.498)
        (xy -5.513 1.509)
        (xy -5.492 1.52)
        (xy -5.473 1.532)
        (xy -5.454 1.545)
        (xy -5.435 1.559)
        (xy -5.417 1.575)
        (xy -5.401 1.591)
        (xy -5.385 1.607)
        (xy -5.369 1.625)
        (xy -5.356 1.643)
        (xy -5.342 1.663)
        (xy -5.33 1.684)
        (xy -5.319 1.704)
        (xy -5.308 1.724)
        (xy -5.3 1.746)
        (xy -5.292 1.767)
        (xy -5.286 1.79)
        (xy -5.281 1.813)
        (xy -5.276 1.835)
        (xy -5.273 1.859)
        (xy -5.271 1.882)
        (xy -5.27 1.905)
        (xy -5.271 1.928)
        (xy -5.273 1.952)
        (xy -5.276 1.976)
        (xy -5.281 1.998)
        (xy -5.286 2.02)
        (xy -5.292 2.044)
        (xy -5.3 2.065)
        (xy -5.308 2.086)
        (xy -5.319 2.108)
        (xy -5.33 2.127)
        (xy -5.342 2.147)
        (xy -5.356 2.167)
        (xy -5.369 2.186)
        (xy -5.385 2.203)
        (xy -5.401 2.221)
        (xy -5.417 2.237)
        (xy -5.435 2.251)
        (xy -5.454 2.266)
        (xy -5.473 2.278)
        (xy -5.492 2.29)
        (xy -5.513 2.302)
        (xy -5.534 2.312)
        (xy -5.556 2.32)
        (xy -5.577 2.328)
        (xy -5.6 2.335)
        (xy -5.622 2.34)
        (xy -5.645 2.346)
        (xy -5.669 2.348)
        (xy -5.693 2.35)
        (xy -5.715 2.351)
        (xy -5.739 2.35)
        (xy -5.763 2.348)
        (xy -5.786 2.346)
        (xy -5.81 2.34)
        (xy -5.832 2.335)
        (xy -5.853 2.328)
        (xy -5.875 2.322)
        (xy -5.898 2.312)
        (xy -5.919 2.302)
        (xy -5.938 2.291)
        (xy -5.959 2.278)
        (xy -5.978 2.266)
        (xy -5.997 2.251)
        (xy -6.013 2.237)
        (xy -6.031 2.221)
        (xy -6.047 2.203)
        (xy -6.061 2.186)
        (xy -6.076 2.167)
        (xy -6.088 2.149)
        (xy -6.101 2.129)
        (xy -6.112 2.109)
        (xy -6.122 2.088)
        (xy -6.132 2.065)
        (xy -6.138 2.044)
        (xy -6.145 2.021)
        (xy -6.151 2)
        (xy -6.156 1.976)
        (xy -6.159 1.954)
        (xy -6.159 1.93)
        (xy -6.161 1.907)
        (xy -5.715 1.907)
        (xy -5.715 1.903)
      )

      (stroke (width 0.001) (type solid)) (fill solid) (layer "B.Paste"))
    (fp_poly
      (pts
        (xy -5.715 3.173)
        (xy -6.161 3.173)
        (xy -6.159 3.151)
        (xy -6.159 3.127)
        (xy -6.156 3.105)
        (xy -6.151 3.081)
        (xy -6.145 3.06)
        (xy -6.138 3.037)
        (xy -6.132 3.016)
        (xy -6.122 2.993)
        (xy -6.112 2.972)
        (xy -6.101 2.952)
        (xy -6.088 2.932)
        (xy -6.076 2.913)
        (xy -6.061 2.895)
        (xy -6.047 2.877)
        (xy -6.031 2.86)
        (xy -6.013 2.844)
        (xy -5.997 2.83)
        (xy -5.978 2.815)
        (xy -5.959 2.802)
        (xy -5.938 2.79)
        (xy -5.919 2.778)
        (xy -5.898 2.768)
        (xy -5.875 2.759)
        (xy -5.853 2.752)
        (xy -5.832 2.746)
        (xy -5.81 2.741)
        (xy -5.786 2.735)
        (xy -5.763 2.733)
        (xy -5.739 2.731)
        (xy -5.715 2.73)
        (xy -5.693 2.731)
        (xy -5.669 2.733)
        (xy -5.645 2.735)
        (xy -5.622 2.741)
        (xy -5.6 2.746)
        (xy -5.577 2.752)
        (xy -5.556 2.76)
        (xy -5.534 2.768)
        (xy -5.513 2.779)
        (xy -5.492 2.79)
        (xy -5.473 2.802)
        (xy -5.454 2.815)
        (xy -5.435 2.83)
        (xy -5.417 2.844)
        (xy -5.401 2.86)
        (xy -5.385 2.877)
        (xy -5.369 2.895)
        (xy -5.356 2.913)
        (xy -5.342 2.933)
        (xy -5.33 2.952)
        (xy -5.319 2.973)
        (xy -5.308 2.995)
        (xy -5.3 3.016)
        (xy -5.292 3.037)
        (xy -5.286 3.06)
        (xy -5.281 3.082)
        (xy -5.276 3.105)
        (xy -5.273 3.129)
        (xy -5.271 3.153)
        (xy -5.27 3.175)
        (xy -5.271 3.198)
        (xy -5.273 3.222)
        (xy -5.276 3.246)
        (xy -5.281 3.268)
        (xy -5.286 3.29)
        (xy -5.292 3.314)
        (xy -5.3 3.335)
        (xy -5.308 3.356)
        (xy -5.319 3.377)
        (xy -5.33 3.397)
        (xy -5.342 3.417)
        (xy -5.356 3.437)
        (xy -5.369 3.455)
        (xy -5.385 3.473)
        (xy -5.401 3.491)
        (xy -5.417 3.506)
        (xy -5.435 3.521)
        (xy -5.454 3.536)
        (xy -5.473 3.548)
        (xy -5.492 3.56)
        (xy -5.513 3.572)
        (xy -5.534 3.582)
        (xy -5.556 3.59)
        (xy -5.577 3.598)
        (xy -5.6 3.605)
        (xy -5.622 3.61)
        (xy -5.645 3.616)
        (xy -5.669 3.618)
        (xy -5.693 3.62)
        (xy -5.715 3.621)
        (xy -5.739 3.62)
        (xy -5.763 3.618)
        (xy -5.786 3.616)
        (xy -5.81 3.61)
        (xy -5.832 3.605)
        (xy -5.853 3.598)
        (xy -5.875 3.592)
        (xy -5.898 3.582)
        (xy -5.919 3.572)
        (xy -5.938 3.561)
        (xy -5.959 3.548)
        (xy -5.978 3.536)
        (xy -5.997 3.521)
        (xy -6.013 3.506)
        (xy -6.031 3.491)
        (xy -6.047 3.473)
        (xy -6.061 3.456)
        (xy -6.076 3.437)
        (xy -6.088 3.419)
        (xy -6.101 3.399)
        (xy -6.112 3.379)
        (xy -6.122 3.358)
        (xy -6.132 3.335)
        (xy -6.138 3.314)
        (xy -6.145 3.291)
        (xy -6.151 3.27)
        (xy -6.156 3.246)
        (xy -6.159 3.223)
        (xy -6.159 3.199)
        (xy -6.161 3.178)
        (xy -5.715 3.178)
        (xy -5.715 3.173)
      )

      (stroke (width 0.001) (type solid)) (fill solid) (layer "B.Paste"))
    (fp_poly
      (pts
        (xy -5.715 4.443)
        (xy -6.161 4.443)
        (xy -6.159 4.422)
        (xy -6.159 4.398)
        (xy -6.156 4.374)
        (xy -6.151 4.351)
        (xy -6.145 4.329)
        (xy -6.138 4.308)
        (xy -6.132 4.286)
        (xy -6.122 4.263)
        (xy -6.112 4.242)
        (xy -6.101 4.223)
        (xy -6.088 4.202)
        (xy -6.076 4.183)
        (xy -6.061 4.164)
        (xy -6.047 4.148)
        (xy -6.031 4.13)
        (xy -6.013 4.114)
        (xy -5.997 4.1)
        (xy -5.978 4.085)
        (xy -5.959 4.072)
        (xy -5.938 4.06)
        (xy -5.919 4.048)
        (xy -5.898 4.039)
        (xy -5.875 4.029)
        (xy -5.853 4.023)
        (xy -5.832 4.015)
        (xy -5.81 4.01)
        (xy -5.786 4.005)
        (xy -5.763 4.002)
        (xy -5.739 4.002)
        (xy -5.715 4)
        (xy -5.693 4.002)
        (xy -5.669 4.002)
        (xy -5.645 4.005)
        (xy -5.622 4.01)
        (xy -5.6 4.015)
        (xy -5.577 4.023)
        (xy -5.556 4.031)
        (xy -5.534 4.039)
        (xy -5.513 4.05)
        (xy -5.492 4.06)
        (xy -5.473 4.072)
        (xy -5.454 4.085)
        (xy -5.435 4.1)
        (xy -5.417 4.114)
        (xy -5.401 4.13)
        (xy -5.385 4.148)
        (xy -5.369 4.165)
        (xy -5.356 4.183)
        (xy -5.342 4.204)
        (xy -5.33 4.223)
        (xy -5.319 4.244)
        (xy -5.308 4.265)
        (xy -5.3 4.286)
        (xy -5.292 4.308)
        (xy -5.286 4.33)
        (xy -5.281 4.353)
        (xy -5.276 4.375)
        (xy -5.273 4.398)
        (xy -5.271 4.422)
        (xy -5.27 4.446)
        (xy -5.271 4.468)
        (xy -5.273 4.492)
        (xy -5.276 4.515)
        (xy -5.281 4.539)
        (xy -5.286 4.56)
        (xy -5.292 4.584)
        (xy -5.3 4.604)
        (xy -5.308 4.627)
        (xy -5.319 4.648)
        (xy -5.33 4.669)
        (xy -5.342 4.688)
        (xy -5.356 4.707)
        (xy -5.369 4.725)
        (xy -5.385 4.744)
        (xy -5.401 4.76)
        (xy -5.417 4.776)
        (xy -5.435 4.792)
        (xy -5.454 4.805)
        (xy -5.473 4.818)
        (xy -5.492 4.83)
        (xy -5.513 4.842)
        (xy -5.534 4.853)
        (xy -5.556 4.861)
        (xy -5.577 4.869)
        (xy -5.6 4.875)
        (xy -5.622 4.88)
        (xy -5.645 4.885)
        (xy -5.669 4.888)
        (xy -5.693 4.89)
        (xy -5.715 4.89)
        (xy -5.739 4.89)
        (xy -5.763 4.888)
        (xy -5.786 4.885)
        (xy -5.81 4.88)
        (xy -5.832 4.875)
        (xy -5.853 4.869)
        (xy -5.875 4.861)
        (xy -5.898 4.853)
        (xy -5.919 4.842)
        (xy -5.938 4.832)
        (xy -5.959 4.818)
        (xy -5.978 4.805)
        (xy -5.997 4.792)
        (xy -6.013 4.776)
        (xy -6.031 4.76)
        (xy -6.047 4.744)
        (xy -6.061 4.726)
        (xy -6.076 4.707)
        (xy -6.088 4.688)
        (xy -6.101 4.669)
        (xy -6.112 4.648)
        (xy -6.122 4.627)
        (xy -6.132 4.606)
        (xy -6.138 4.584)
        (xy -6.145 4.561)
        (xy -6.151 4.539)
        (xy -6.156 4.516)
        (xy -6.159 4.494)
        (xy -6.159 4.47)
        (xy -6.161 4.447)
        (xy -5.715 4.447)
        (xy -5.715 4.443)
      )

      (stroke (width 0.001) (type solid)) (fill solid) (layer "B.Paste"))
    (fp_poly
      (pts
        (xy -5.715 5.713)
        (xy -6.161 5.713)
        (xy -6.159 5.691)
        (xy -6.159 5.667)
        (xy -6.156 5.645)
        (xy -6.151 5.622)
        (xy -6.145 5.6)
        (xy -6.138 5.577)
        (xy -6.132 5.555)
        (xy -6.122 5.534)
        (xy -6.112 5.512)
        (xy -6.101 5.492)
        (xy -6.088 5.473)
        (xy -6.076 5.454)
        (xy -6.061 5.435)
        (xy -6.047 5.417)
        (xy -6.031 5.401)
        (xy -6.013 5.385)
        (xy -5.997 5.369)
        (xy -5.978 5.356)
        (xy -5.959 5.342)
        (xy -5.938 5.329)
        (xy -5.919 5.318)
        (xy -5.898 5.308)
        (xy -5.875 5.3)
        (xy -5.853 5.292)
        (xy -5.832 5.286)
        (xy -5.81 5.281)
        (xy -5.786 5.276)
        (xy -5.763 5.273)
        (xy -5.739 5.271)
        (xy -5.715 5.27)
        (xy -5.693 5.271)
        (xy -5.669 5.273)
        (xy -5.645 5.276)
        (xy -5.622 5.281)
        (xy -5.6 5.286)
        (xy -5.577 5.292)
        (xy -5.556 5.3)
        (xy -5.534 5.308)
        (xy -5.513 5.319)
        (xy -5.492 5.33)
        (xy -5.473 5.342)
        (xy -5.454 5.356)
        (xy -5.435 5.369)
        (xy -5.417 5.385)
        (xy -5.401 5.401)
        (xy -5.385 5.417)
        (xy -5.369 5.435)
        (xy -5.356 5.454)
        (xy -5.342 5.473)
        (xy -5.33 5.492)
        (xy -5.319 5.513)
        (xy -5.308 5.534)
        (xy -5.3 5.556)
        (xy -5.292 5.577)
        (xy -5.286 5.6)
        (xy -5.281 5.622)
        (xy -5.276 5.645)
        (xy -5.273 5.669)
        (xy -5.271 5.693)
        (xy -5.27 5.715)
        (xy -5.271 5.739)
        (xy -5.273 5.762)
        (xy -5.276 5.786)
        (xy -5.281 5.808)
        (xy -5.286 5.83)
        (xy -5.292 5.853)
        (xy -5.3 5.874)
        (xy -5.308 5.896)
        (xy -5.319 5.917)
        (xy -5.33 5.938)
        (xy -5.342 5.957)
        (xy -5.356 5.978)
        (xy -5.369 5.995)
        (xy -5.385 6.013)
        (xy -5.401 6.031)
        (xy -5.417 6.047)
        (xy -5.435 6.061)
        (xy -5.454 6.076)
        (xy -5.473 6.088)
        (xy -5.492 6.1)
        (xy -5.513 6.111)
        (xy -5.534 6.122)
        (xy -5.556 6.13)
        (xy -5.577 6.138)
        (xy -5.6 6.145)
        (xy -5.622 6.151)
        (xy -5.645 6.156)
        (xy -5.669 6.159)
        (xy -5.693 6.159)
        (xy -5.715 6.161)
        (xy -5.739 6.159)
        (xy -5.763 6.159)
        (xy -5.786 6.156)
        (xy -5.81 6.151)
        (xy -5.832 6.145)
        (xy -5.853 6.138)
        (xy -5.875 6.132)
        (xy -5.898 6.122)
        (xy -5.919 6.112)
        (xy -5.938 6.101)
        (xy -5.959 6.088)
        (xy -5.978 6.076)
        (xy -5.997 6.061)
        (xy -6.013 6.047)
        (xy -6.031 6.031)
        (xy -6.047 6.013)
        (xy -6.061 5.997)
        (xy -6.076 5.978)
        (xy -6.088 5.959)
        (xy -6.101 5.938)
        (xy -6.112 5.919)
        (xy -6.122 5.898)
        (xy -6.132 5.875)
        (xy -6.138 5.853)
        (xy -6.145 5.832)
        (xy -6.151 5.81)
        (xy -6.156 5.786)
        (xy -6.159 5.763)
        (xy -6.159 5.739)
        (xy -6.161 5.718)
        (xy -5.715 5.718)
        (xy -5.715 5.713)
      )

      (stroke (width 0.001) (type solid)) (fill solid) (layer "B.Paste"))
    (fp_poly
      (pts
        (xy -4.446 -5.717)
        (xy -4.89 -5.717)
        (xy -4.89 -5.738)
        (xy -4.888 -5.762)
        (xy -4.885 -5.785)
        (xy -4.88 -5.809)
        (xy -4.875 -5.831)
        (xy -4.869 -5.852)
        (xy -4.861 -5.874)
        (xy -4.853 -5.897)
        (xy -4.842 -5.918)
        (xy -4.832 -5.937)
        (xy -4.818 -5.958)
        (xy -4.805 -5.977)
        (xy -4.792 -5.996)
        (xy -4.776 -6.012)
        (xy -4.76 -6.03)
        (xy -4.744 -6.046)
        (xy -4.726 -6.06)
        (xy -4.707 -6.075)
        (xy -4.688 -6.087)
        (xy -4.669 -6.1)
        (xy -4.648 -6.111)
        (xy -4.627 -6.121)
        (xy -4.606 -6.131)
        (xy -4.584 -6.137)
        (xy -4.561 -6.144)
        (xy -4.539 -6.15)
        (xy -4.516 -6.155)
        (xy -4.494 -6.158)
        (xy -4.47 -6.158)
        (xy -4.446 -6.16)
        (xy -4.422 -6.158)
        (xy -4.398 -6.158)
        (xy -4.375 -6.155)
        (xy -4.353 -6.15)
        (xy -4.33 -6.144)
        (xy -4.308 -6.137)
        (xy -4.286 -6.129)
        (xy -4.265 -6.121)
        (xy -4.244 -6.11)
        (xy -4.223 -6.099)
        (xy -4.204 -6.087)
        (xy -4.183 -6.075)
        (xy -4.165 -6.06)
        (xy -4.148 -6.046)
        (xy -4.13 -6.03)
        (xy -4.114 -6.012)
        (xy -4.1 -5.994)
        (xy -4.085 -5.977)
        (xy -4.072 -5.956)
        (xy -4.06 -5.937)
        (xy -4.05 -5.916)
        (xy -4.039 -5.895)
        (xy -4.031 -5.873)
        (xy -4.023 -5.852)
        (xy -4.015 -5.829)
        (xy -4.01 -5.807)
        (xy -4.005 -5.785)
        (xy -4.002 -5.761)
        (xy -4.002 -5.738)
        (xy -4 -5.714)
        (xy -4.002 -5.692)
        (xy -4.002 -5.668)
        (xy -4.005 -5.644)
        (xy -4.01 -5.621)
        (xy -4.015 -5.599)
        (xy -4.023 -5.576)
        (xy -4.031 -5.555)
        (xy -4.039 -5.533)
        (xy -4.05 -5.512)
        (xy -4.06 -5.491)
        (xy -4.072 -5.472)
        (xy -4.085 -5.453)
        (xy -4.1 -5.434)
        (xy -4.114 -5.416)
        (xy -4.13 -5.4)
        (xy -4.148 -5.384)
        (xy -4.165 -5.368)
        (xy -4.183 -5.355)
        (xy -4.204 -5.341)
        (xy -4.223 -5.329)
        (xy -4.244 -5.318)
        (xy -4.265 -5.307)
        (xy -4.286 -5.299)
        (xy -4.308 -5.291)
        (xy -4.33 -5.285)
        (xy -4.353 -5.28)
        (xy -4.375 -5.275)
        (xy -4.398 -5.272)
        (xy -4.422 -5.27)
        (xy -4.446 -5.269)
        (xy -4.47 -5.27)
        (xy -4.494 -5.272)
        (xy -4.516 -5.275)
        (xy -4.539 -5.28)
        (xy -4.561 -5.285)
        (xy -4.584 -5.291)
        (xy -4.606 -5.299)
        (xy -4.627 -5.307)
        (xy -4.648 -5.317)
        (xy -4.669 -5.328)
        (xy -4.688 -5.341)
        (xy -4.707 -5.355)
        (xy -4.726 -5.368)
        (xy -4.744 -5.384)
        (xy -4.76 -5.4)
        (xy -4.776 -5.416)
        (xy -4.792 -5.434)
        (xy -4.805 -5.453)
        (xy -4.818 -5.472)
        (xy -4.832 -5.491)
        (xy -4.842 -5.511)
        (xy -4.853 -5.533)
        (xy -4.861 -5.554)
        (xy -4.869 -5.576)
        (xy -4.875 -5.599)
        (xy -4.88 -5.621)
        (xy -4.885 -5.644)
        (xy -4.888 -5.666)
        (xy -4.89 -5.69)
        (xy -4.89 -5.712)
        (xy -4.446 -5.712)
        (xy -4.446 -5.717)
      )

      (stroke (width 0.001) (type solid)) (fill solid) (layer "B.Paste"))
    (fp_poly
      (pts
        (xy -4.446 -3.177)
        (xy -4.89 -3.177)
        (xy -4.89 -3.198)
        (xy -4.888 -3.222)
        (xy -4.885 -3.245)
        (xy -4.88 -3.269)
        (xy -4.875 -3.29)
        (xy -4.869 -3.313)
        (xy -4.861 -3.334)
        (xy -4.853 -3.357)
        (xy -4.842 -3.378)
        (xy -4.832 -3.398)
        (xy -4.818 -3.418)
        (xy -4.805 -3.436)
        (xy -4.792 -3.455)
        (xy -4.776 -3.472)
        (xy -4.76 -3.49)
        (xy -4.744 -3.505)
        (xy -4.726 -3.52)
        (xy -4.707 -3.535)
        (xy -4.688 -3.547)
        (xy -4.669 -3.56)
        (xy -4.648 -3.571)
        (xy -4.627 -3.581)
        (xy -4.606 -3.591)
        (xy -4.584 -3.597)
        (xy -4.561 -3.604)
        (xy -4.539 -3.609)
        (xy -4.516 -3.615)
        (xy -4.494 -3.617)
        (xy -4.47 -3.619)
        (xy -4.446 -3.62)
        (xy -4.422 -3.619)
        (xy -4.398 -3.617)
        (xy -4.375 -3.615)
        (xy -4.353 -3.609)
        (xy -4.33 -3.604)
        (xy -4.308 -3.597)
        (xy -4.286 -3.589)
        (xy -4.265 -3.581)
        (xy -4.244 -3.571)
        (xy -4.223 -3.559)
        (xy -4.204 -3.547)
        (xy -4.183 -3.535)
        (xy -4.165 -3.52)
        (xy -4.148 -3.505)
        (xy -4.13 -3.49)
        (xy -4.114 -3.472)
        (xy -4.1 -3.454)
        (xy -4.085 -3.436)
        (xy -4.072 -3.416)
        (xy -4.06 -3.396)
        (xy -4.05 -3.376)
        (xy -4.039 -3.355)
        (xy -4.031 -3.334)
        (xy -4.023 -3.313)
        (xy -4.015 -3.289)
        (xy -4.01 -3.267)
        (xy -4.005 -3.245)
        (xy -4.002 -3.221)
        (xy -4.002 -3.197)
        (xy -4 -3.174)
        (xy -4.002 -3.152)
        (xy -4.002 -3.128)
        (xy -4.005 -3.104)
        (xy -4.01 -3.081)
        (xy -4.015 -3.059)
        (xy -4.023 -3.036)
        (xy -4.031 -3.015)
        (xy -4.039 -2.994)
        (xy -4.05 -2.972)
        (xy -4.06 -2.951)
        (xy -4.072 -2.932)
        (xy -4.085 -2.912)
        (xy -4.1 -2.894)
        (xy -4.114 -2.876)
        (xy -4.13 -2.859)
        (xy -4.148 -2.843)
        (xy -4.165 -2.829)
        (xy -4.183 -2.814)
        (xy -4.204 -2.801)
        (xy -4.223 -2.789)
        (xy -4.244 -2.778)
        (xy -4.265 -2.767)
        (xy -4.286 -2.759)
        (xy -4.308 -2.751)
        (xy -4.33 -2.745)
        (xy -4.353 -2.74)
        (xy -4.375 -2.734)
        (xy -4.398 -2.732)
        (xy -4.422 -2.73)
        (xy -4.446 -2.729)
        (xy -4.47 -2.73)
        (xy -4.494 -2.732)
        (xy -4.516 -2.734)
        (xy -4.539 -2.74)
        (xy -4.561 -2.745)
        (xy -4.584 -2.751)
        (xy -4.606 -2.758)
        (xy -4.627 -2.767)
        (xy -4.648 -2.777)
        (xy -4.669 -2.789)
        (xy -4.688 -2.801)
        (xy -4.707 -2.814)
        (xy -4.726 -2.829)
        (xy -4.744 -2.843)
        (xy -4.76 -2.859)
        (xy -4.776 -2.876)
        (xy -4.792 -2.894)
        (xy -4.805 -2.912)
        (xy -4.818 -2.931)
        (xy -4.832 -2.951)
        (xy -4.842 -2.971)
        (xy -4.853 -2.992)
        (xy -4.861 -3.015)
        (xy -4.869 -3.036)
        (xy -4.875 -3.059)
        (xy -4.88 -3.08)
        (xy -4.885 -3.104)
        (xy -4.888 -3.126)
        (xy -4.89 -3.15)
        (xy -4.89 -3.172)
        (xy -4.446 -3.172)
        (xy -4.446 -3.177)
      )

      (stroke (width 0.001) (type solid)) (fill solid) (layer "B.Paste"))
    (fp_poly
      (pts
        (xy -4.446 1.903)
        (xy -4.89 1.903)
        (xy -4.89 1.881)
        (xy -4.888 1.857)
        (xy -4.885 1.835)
        (xy -4.88 1.811)
        (xy -4.875 1.789)
        (xy -4.869 1.767)
        (xy -4.861 1.746)
        (xy -4.853 1.724)
        (xy -4.842 1.702)
        (xy -4.832 1.682)
        (xy -4.818 1.662)
        (xy -4.805 1.643)
        (xy -4.792 1.625)
        (xy -4.776 1.607)
        (xy -4.76 1.591)
        (xy -4.744 1.575)
        (xy -4.726 1.559)
        (xy -4.707 1.545)
        (xy -4.688 1.532)
        (xy -4.669 1.519)
        (xy -4.648 1.508)
        (xy -4.627 1.498)
        (xy -4.606 1.49)
        (xy -4.584 1.482)
        (xy -4.561 1.476)
        (xy -4.539 1.47)
        (xy -4.516 1.466)
        (xy -4.494 1.462)
        (xy -4.47 1.462)
        (xy -4.446 1.46)
        (xy -4.422 1.462)
        (xy -4.398 1.462)
        (xy -4.375 1.466)
        (xy -4.353 1.47)
        (xy -4.33 1.476)
        (xy -4.308 1.482)
        (xy -4.286 1.49)
        (xy -4.265 1.498)
        (xy -4.244 1.509)
        (xy -4.223 1.52)
        (xy -4.204 1.532)
        (xy -4.183 1.545)
        (xy -4.165 1.559)
        (xy -4.148 1.575)
        (xy -4.13 1.591)
        (xy -4.114 1.607)
        (xy -4.1 1.625)
        (xy -4.085 1.643)
        (xy -4.072 1.663)
        (xy -4.06 1.684)
        (xy -4.05 1.704)
        (xy -4.039 1.724)
        (xy -4.031 1.746)
        (xy -4.023 1.767)
        (xy -4.015 1.79)
        (xy -4.01 1.813)
        (xy -4.005 1.835)
        (xy -4.002 1.859)
        (xy -4.002 1.882)
        (xy -4 1.905)
        (xy -4.002 1.928)
        (xy -4.002 1.952)
        (xy -4.005 1.976)
        (xy -4.01 1.998)
        (xy -4.015 2.02)
        (xy -4.023 2.044)
        (xy -4.031 2.065)
        (xy -4.039 2.086)
        (xy -4.05 2.108)
        (xy -4.06 2.127)
        (xy -4.072 2.147)
        (xy -4.085 2.167)
        (xy -4.1 2.186)
        (xy -4.114 2.203)
        (xy -4.13 2.221)
        (xy -4.148 2.237)
        (xy -4.165 2.251)
        (xy -4.183 2.266)
        (xy -4.204 2.278)
        (xy -4.223 2.29)
        (xy -4.244 2.302)
        (xy -4.265 2.312)
        (xy -4.286 2.32)
        (xy -4.308 2.328)
        (xy -4.33 2.335)
        (xy -4.353 2.34)
        (xy -4.375 2.346)
        (xy -4.398 2.348)
        (xy -4.422 2.35)
        (xy -4.446 2.351)
        (xy -4.47 2.35)
        (xy -4.494 2.348)
        (xy -4.516 2.346)
        (xy -4.539 2.34)
        (xy -4.561 2.335)
        (xy -4.584 2.328)
        (xy -4.606 2.322)
        (xy -4.627 2.312)
        (xy -4.648 2.302)
        (xy -4.669 2.291)
        (xy -4.688 2.278)
        (xy -4.707 2.266)
        (xy -4.726 2.251)
        (xy -4.744 2.237)
        (xy -4.76 2.221)
        (xy -4.776 2.203)
        (xy -4.792 2.186)
        (xy -4.805 2.167)
        (xy -4.818 2.149)
        (xy -4.832 2.129)
        (xy -4.842 2.109)
        (xy -4.853 2.088)
        (xy -4.861 2.065)
        (xy -4.869 2.044)
        (xy -4.875 2.021)
        (xy -4.88 2)
        (xy -4.885 1.976)
        (xy -4.888 1.954)
        (xy -4.89 1.93)
        (xy -4.89 1.907)
        (xy -4.446 1.907)
        (xy -4.446 1.903)
      )

      (stroke (width 0.001) (type solid)) (fill solid) (layer "B.Paste"))
    (fp_poly
      (pts
        (xy -4.446 3.173)
        (xy -4.89 3.173)
        (xy -4.89 3.151)
        (xy -4.888 3.127)
        (xy -4.885 3.105)
        (xy -4.88 3.081)
        (xy -4.875 3.06)
        (xy -4.869 3.037)
        (xy -4.861 3.016)
        (xy -4.853 2.993)
        (xy -4.842 2.972)
        (xy -4.832 2.952)
        (xy -4.818 2.932)
        (xy -4.805 2.913)
        (xy -4.792 2.895)
        (xy -4.776 2.877)
        (xy -4.76 2.86)
        (xy -4.744 2.844)
        (xy -4.726 2.83)
        (xy -4.707 2.815)
        (xy -4.688 2.802)
        (xy -4.669 2.79)
        (xy -4.648 2.778)
        (xy -4.627 2.768)
        (xy -4.606 2.759)
        (xy -4.584 2.752)
        (xy -4.561 2.746)
        (xy -4.539 2.741)
        (xy -4.516 2.735)
        (xy -4.494 2.733)
        (xy -4.47 2.731)
        (xy -4.446 2.73)
        (xy -4.422 2.731)
        (xy -4.398 2.733)
        (xy -4.375 2.735)
        (xy -4.353 2.741)
        (xy -4.33 2.746)
        (xy -4.308 2.752)
        (xy -4.286 2.76)
        (xy -4.265 2.768)
        (xy -4.244 2.779)
        (xy -4.223 2.79)
        (xy -4.204 2.802)
        (xy -4.183 2.815)
        (xy -4.165 2.83)
        (xy -4.148 2.844)
        (xy -4.13 2.86)
        (xy -4.114 2.877)
        (xy -4.1 2.895)
        (xy -4.085 2.913)
        (xy -4.072 2.933)
        (xy -4.06 2.952)
        (xy -4.05 2.973)
        (xy -4.039 2.995)
        (xy -4.031 3.016)
        (xy -4.023 3.037)
        (xy -4.015 3.06)
        (xy -4.01 3.082)
        (xy -4.005 3.105)
        (xy -4.002 3.129)
        (xy -4.002 3.153)
        (xy -4 3.175)
        (xy -4.002 3.198)
        (xy -4.002 3.222)
        (xy -4.005 3.246)
        (xy -4.01 3.268)
        (xy -4.015 3.29)
        (xy -4.023 3.314)
        (xy -4.031 3.335)
        (xy -4.039 3.356)
        (xy -4.05 3.377)
        (xy -4.06 3.397)
        (xy -4.072 3.417)
        (xy -4.085 3.437)
        (xy -4.1 3.455)
        (xy -4.114 3.473)
        (xy -4.13 3.491)
        (xy -4.148 3.506)
        (xy -4.165 3.521)
        (xy -4.183 3.536)
        (xy -4.204 3.548)
        (xy -4.223 3.56)
        (xy -4.244 3.572)
        (xy -4.265 3.582)
        (xy -4.286 3.59)
        (xy -4.308 3.598)
        (xy -4.33 3.605)
        (xy -4.353 3.61)
        (xy -4.375 3.616)
        (xy -4.398 3.618)
        (xy -4.422 3.62)
        (xy -4.446 3.621)
        (xy -4.47 3.62)
        (xy -4.494 3.618)
        (xy -4.516 3.616)
        (xy -4.539 3.61)
        (xy -4.561 3.605)
        (xy -4.584 3.598)
        (xy -4.606 3.592)
        (xy -4.627 3.582)
        (xy -4.648 3.572)
        (xy -4.669 3.561)
        (xy -4.688 3.548)
        (xy -4.707 3.536)
        (xy -4.726 3.521)
        (xy -4.744 3.506)
        (xy -4.76 3.491)
        (xy -4.776 3.473)
        (xy -4.792 3.456)
        (xy -4.805 3.437)
        (xy -4.818 3.419)
        (xy -4.832 3.399)
        (xy -4.842 3.379)
        (xy -4.853 3.358)
        (xy -4.861 3.335)
        (xy -4.869 3.314)
        (xy -4.875 3.291)
        (xy -4.88 3.27)
        (xy -4.885 3.246)
        (xy -4.888 3.223)
        (xy -4.89 3.199)
        (xy -4.89 3.178)
        (xy -4.446 3.178)
        (xy -4.446 3.173)
      )

      (stroke (width 0.001) (type solid)) (fill solid) (layer "B.Paste"))
    (fp_poly
      (pts
        (xy -4.446 4.443)
        (xy -4.89 4.443)
        (xy -4.89 4.422)
        (xy -4.888 4.398)
        (xy -4.885 4.374)
        (xy -4.88 4.351)
        (xy -4.875 4.329)
        (xy -4.869 4.308)
        (xy -4.861 4.286)
        (xy -4.853 4.263)
        (xy -4.842 4.242)
        (xy -4.832 4.223)
        (xy -4.818 4.202)
        (xy -4.805 4.183)
        (xy -4.792 4.164)
        (xy -4.776 4.148)
        (xy -4.76 4.13)
        (xy -4.744 4.114)
        (xy -4.726 4.1)
        (xy -4.707 4.085)
        (xy -4.688 4.072)
        (xy -4.669 4.06)
        (xy -4.648 4.048)
        (xy -4.627 4.039)
        (xy -4.606 4.029)
        (xy -4.584 4.023)
        (xy -4.561 4.015)
        (xy -4.539 4.01)
        (xy -4.516 4.005)
        (xy -4.494 4.002)
        (xy -4.47 4.002)
        (xy -4.446 4)
        (xy -4.422 4.002)
        (xy -4.398 4.002)
        (xy -4.375 4.005)
        (xy -4.353 4.01)
        (xy -4.33 4.015)
        (xy -4.308 4.023)
        (xy -4.286 4.031)
        (xy -4.265 4.039)
        (xy -4.244 4.05)
        (xy -4.223 4.06)
        (xy -4.204 4.072)
        (xy -4.183 4.085)
        (xy -4.165 4.1)
        (xy -4.148 4.114)
        (xy -4.13 4.13)
        (xy -4.114 4.148)
        (xy -4.1 4.165)
        (xy -4.085 4.183)
        (xy -4.072 4.204)
        (xy -4.06 4.223)
        (xy -4.05 4.244)
        (xy -4.039 4.265)
        (xy -4.031 4.286)
        (xy -4.023 4.308)
        (xy -4.015 4.33)
        (xy -4.01 4.353)
        (xy -4.005 4.375)
        (xy -4.002 4.398)
        (xy -4.002 4.422)
        (xy -4 4.446)
        (xy -4.002 4.468)
        (xy -4.002 4.492)
        (xy -4.005 4.515)
        (xy -4.01 4.539)
        (xy -4.015 4.56)
        (xy -4.023 4.584)
        (xy -4.031 4.604)
        (xy -4.039 4.627)
        (xy -4.05 4.648)
        (xy -4.06 4.669)
        (xy -4.072 4.688)
        (xy -4.085 4.707)
        (xy -4.1 4.725)
        (xy -4.114 4.744)
        (xy -4.13 4.76)
        (xy -4.148 4.776)
        (xy -4.165 4.792)
        (xy -4.183 4.805)
        (xy -4.204 4.818)
        (xy -4.223 4.83)
        (xy -4.244 4.842)
        (xy -4.265 4.853)
        (xy -4.286 4.861)
        (xy -4.308 4.869)
        (xy -4.33 4.875)
        (xy -4.353 4.88)
        (xy -4.375 4.885)
        (xy -4.398 4.888)
        (xy -4.422 4.89)
        (xy -4.446 4.89)
        (xy -4.47 4.89)
        (xy -4.494 4.888)
        (xy -4.516 4.885)
        (xy -4.539 4.88)
        (xy -4.561 4.875)
        (xy -4.584 4.869)
        (xy -4.606 4.861)
        (xy -4.627 4.853)
        (xy -4.648 4.842)
        (xy -4.669 4.832)
        (xy -4.688 4.818)
        (xy -4.707 4.805)
        (xy -4.726 4.792)
        (xy -4.744 4.776)
        (xy -4.76 4.76)
        (xy -4.776 4.744)
        (xy -4.792 4.726)
        (xy -4.805 4.707)
        (xy -4.818 4.688)
        (xy -4.832 4.669)
        (xy -4.842 4.648)
        (xy -4.853 4.627)
        (xy -4.861 4.606)
        (xy -4.869 4.584)
        (xy -4.875 4.561)
        (xy -4.88 4.539)
        (xy -4.885 4.516)
        (xy -4.888 4.494)
        (xy -4.89 4.47)
        (xy -4.89 4.447)
        (xy -4.446 4.447)
        (xy -4.446 4.443)
      )

      (stroke (width 0.001) (type solid)) (fill solid) (layer "B.Paste"))
    (fp_poly
      (pts
        (xy -4.446 5.713)
        (xy -4.89 5.713)
        (xy -4.89 5.691)
        (xy -4.888 5.667)
        (xy -4.885 5.645)
        (xy -4.88 5.622)
        (xy -4.875 5.6)
        (xy -4.869 5.577)
        (xy -4.861 5.555)
        (xy -4.853 5.534)
        (xy -4.842 5.512)
        (xy -4.832 5.492)
        (xy -4.818 5.473)
        (xy -4.805 5.454)
        (xy -4.792 5.435)
        (xy -4.776 5.417)
        (xy -4.76 5.401)
        (xy -4.744 5.385)
        (xy -4.726 5.369)
        (xy -4.707 5.356)
        (xy -4.688 5.342)
        (xy -4.669 5.329)
        (xy -4.648 5.318)
        (xy -4.627 5.308)
        (xy -4.606 5.3)
        (xy -4.584 5.292)
        (xy -4.561 5.286)
        (xy -4.539 5.281)
        (xy -4.516 5.276)
        (xy -4.494 5.273)
        (xy -4.47 5.271)
        (xy -4.446 5.27)
        (xy -4.422 5.271)
        (xy -4.398 5.273)
        (xy -4.375 5.276)
        (xy -4.353 5.281)
        (xy -4.33 5.286)
        (xy -4.308 5.292)
        (xy -4.286 5.3)
        (xy -4.265 5.308)
        (xy -4.244 5.319)
        (xy -4.223 5.33)
        (xy -4.204 5.342)
        (xy -4.183 5.356)
        (xy -4.165 5.369)
        (xy -4.148 5.385)
        (xy -4.13 5.401)
        (xy -4.114 5.417)
        (xy -4.1 5.435)
        (xy -4.085 5.454)
        (xy -4.072 5.473)
        (xy -4.06 5.492)
        (xy -4.05 5.513)
        (xy -4.039 5.534)
        (xy -4.031 5.556)
        (xy -4.023 5.577)
        (xy -4.015 5.6)
        (xy -4.01 5.622)
        (xy -4.005 5.645)
        (xy -4.002 5.669)
        (xy -4.002 5.693)
        (xy -4 5.715)
        (xy -4.002 5.739)
        (xy -4.002 5.762)
        (xy -4.005 5.786)
        (xy -4.01 5.808)
        (xy -4.015 5.83)
        (xy -4.023 5.853)
        (xy -4.031 5.874)
        (xy -4.039 5.896)
        (xy -4.05 5.917)
        (xy -4.06 5.938)
        (xy -4.072 5.957)
        (xy -4.085 5.978)
        (xy -4.1 5.995)
        (xy -4.114 6.013)
        (xy -4.13 6.031)
        (xy -4.148 6.047)
        (xy -4.165 6.061)
        (xy -4.183 6.076)
        (xy -4.204 6.088)
        (xy -4.223 6.1)
        (xy -4.244 6.111)
        (xy -4.265 6.122)
        (xy -4.286 6.13)
        (xy -4.308 6.138)
        (xy -4.33 6.145)
        (xy -4.353 6.151)
        (xy -4.375 6.156)
        (xy -4.398 6.159)
        (xy -4.422 6.159)
        (xy -4.446 6.161)
        (xy -4.47 6.159)
        (xy -4.494 6.159)
        (xy -4.516 6.156)
        (xy -4.539 6.151)
        (xy -4.561 6.145)
        (xy -4.584 6.138)
        (xy -4.606 6.132)
        (xy -4.627 6.122)
        (xy -4.648 6.112)
        (xy -4.669 6.101)
        (xy -4.688 6.088)
        (xy -4.707 6.076)
        (xy -4.726 6.061)
        (xy -4.744 6.047)
        (xy -4.76 6.031)
        (xy -4.776 6.013)
        (xy -4.792 5.997)
        (xy -4.805 5.978)
        (xy -4.818 5.959)
        (xy -4.832 5.938)
        (xy -4.842 5.919)
        (xy -4.853 5.898)
        (xy -4.861 5.875)
        (xy -4.869 5.853)
        (xy -4.875 5.832)
        (xy -4.88 5.81)
        (xy -4.885 5.786)
        (xy -4.888 5.763)
        (xy -4.89 5.739)
        (xy -4.89 5.718)
        (xy -4.446 5.718)
        (xy -4.446 5.713)
      )

      (stroke (width 0.001) (type solid)) (fill solid) (layer "B.Paste"))
    (fp_poly
      (pts
        (xy -3.175 -5.717)
        (xy -3.621 -5.717)
        (xy -3.62 -5.738)
        (xy -3.618 -5.762)
        (xy -3.616 -5.785)
        (xy -3.61 -5.809)
        (xy -3.605 -5.831)
        (xy -3.598 -5.852)
        (xy -3.592 -5.874)
        (xy -3.582 -5.897)
        (xy -3.572 -5.918)
        (xy -3.561 -5.937)
        (xy -3.548 -5.958)
        (xy -3.536 -5.977)
        (xy -3.521 -5.996)
        (xy -3.506 -6.012)
        (xy -3.491 -6.03)
        (xy -3.473 -6.046)
        (xy -3.456 -6.06)
        (xy -3.437 -6.075)
        (xy -3.419 -6.087)
        (xy -3.399 -6.1)
        (xy -3.379 -6.111)
        (xy -3.358 -6.121)
        (xy -3.335 -6.131)
        (xy -3.314 -6.137)
        (xy -3.291 -6.144)
        (xy -3.27 -6.15)
        (xy -3.246 -6.155)
        (xy -3.223 -6.158)
        (xy -3.199 -6.158)
        (xy -3.175 -6.16)
        (xy -3.153 -6.158)
        (xy -3.129 -6.158)
        (xy -3.105 -6.155)
        (xy -3.082 -6.15)
        (xy -3.06 -6.144)
        (xy -3.037 -6.137)
        (xy -3.016 -6.129)
        (xy -2.995 -6.121)
        (xy -2.973 -6.11)
        (xy -2.952 -6.099)
        (xy -2.933 -6.087)
        (xy -2.913 -6.075)
        (xy -2.895 -6.06)
        (xy -2.877 -6.046)
        (xy -2.86 -6.03)
        (xy -2.844 -6.012)
        (xy -2.83 -5.994)
        (xy -2.815 -5.977)
        (xy -2.802 -5.956)
        (xy -2.79 -5.937)
        (xy -2.779 -5.916)
        (xy -2.768 -5.895)
        (xy -2.76 -5.873)
        (xy -2.752 -5.852)
        (xy -2.746 -5.829)
        (xy -2.741 -5.807)
        (xy -2.735 -5.785)
        (xy -2.733 -5.761)
        (xy -2.731 -5.738)
        (xy -2.73 -5.714)
        (xy -2.731 -5.692)
        (xy -2.733 -5.668)
        (xy -2.735 -5.644)
        (xy -2.741 -5.621)
        (xy -2.746 -5.599)
        (xy -2.752 -5.576)
        (xy -2.76 -5.555)
        (xy -2.768 -5.533)
        (xy -2.779 -5.512)
        (xy -2.79 -5.491)
        (xy -2.802 -5.472)
        (xy -2.815 -5.453)
        (xy -2.83 -5.434)
        (xy -2.844 -5.416)
        (xy -2.86 -5.4)
        (xy -2.877 -5.384)
        (xy -2.895 -5.368)
        (xy -2.913 -5.355)
        (xy -2.933 -5.341)
        (xy -2.952 -5.329)
        (xy -2.973 -5.318)
        (xy -2.995 -5.307)
        (xy -3.016 -5.299)
        (xy -3.037 -5.291)
        (xy -3.06 -5.285)
        (xy -3.082 -5.28)
        (xy -3.105 -5.275)
        (xy -3.129 -5.272)
        (xy -3.153 -5.27)
        (xy -3.175 -5.269)
        (xy -3.199 -5.27)
        (xy -3.223 -5.272)
        (xy -3.246 -5.275)
        (xy -3.27 -5.28)
        (xy -3.291 -5.285)
        (xy -3.314 -5.291)
        (xy -3.335 -5.299)
        (xy -3.358 -5.307)
        (xy -3.379 -5.317)
        (xy -3.399 -5.328)
        (xy -3.419 -5.341)
        (xy -3.437 -5.355)
        (xy -3.456 -5.368)
        (xy -3.473 -5.384)
        (xy -3.491 -5.4)
        (xy -3.506 -5.416)
        (xy -3.521 -5.434)
        (xy -3.536 -5.453)
        (xy -3.548 -5.472)
        (xy -3.561 -5.491)
        (xy -3.572 -5.511)
        (xy -3.582 -5.533)
        (xy -3.592 -5.554)
        (xy -3.598 -5.576)
        (xy -3.605 -5.599)
        (xy -3.61 -5.621)
        (xy -3.616 -5.644)
        (xy -3.618 -5.666)
        (xy -3.62 -5.69)
        (xy -3.621 -5.712)
        (xy -3.175 -5.712)
        (xy -3.175 -5.717)
      )

      (stroke (width 0.001) (type solid)) (fill solid) (layer "B.Paste"))
    (fp_poly
      (pts
        (xy -3.175 -3.177)
        (xy -3.621 -3.177)
        (xy -3.62 -3.198)
        (xy -3.618 -3.222)
        (xy -3.616 -3.245)
        (xy -3.61 -3.269)
        (xy -3.605 -3.29)
        (xy -3.598 -3.313)
        (xy -3.592 -3.334)
        (xy -3.582 -3.357)
        (xy -3.572 -3.378)
        (xy -3.561 -3.398)
        (xy -3.548 -3.418)
        (xy -3.536 -3.436)
        (xy -3.521 -3.455)
        (xy -3.506 -3.472)
        (xy -3.491 -3.49)
        (xy -3.473 -3.505)
        (xy -3.456 -3.52)
        (xy -3.437 -3.535)
        (xy -3.419 -3.547)
        (xy -3.399 -3.56)
        (xy -3.379 -3.571)
        (xy -3.358 -3.581)
        (xy -3.335 -3.591)
        (xy -3.314 -3.597)
        (xy -3.291 -3.604)
        (xy -3.27 -3.609)
        (xy -3.246 -3.615)
        (xy -3.223 -3.617)
        (xy -3.199 -3.619)
        (xy -3.175 -3.62)
        (xy -3.153 -3.619)
        (xy -3.129 -3.617)
        (xy -3.105 -3.615)
        (xy -3.082 -3.609)
        (xy -3.06 -3.604)
        (xy -3.037 -3.597)
        (xy -3.016 -3.589)
        (xy -2.995 -3.581)
        (xy -2.973 -3.571)
        (xy -2.952 -3.559)
        (xy -2.933 -3.547)
        (xy -2.913 -3.535)
        (xy -2.895 -3.52)
        (xy -2.877 -3.505)
        (xy -2.86 -3.49)
        (xy -2.844 -3.472)
        (xy -2.83 -3.454)
        (xy -2.815 -3.436)
        (xy -2.802 -3.416)
        (xy -2.79 -3.396)
        (xy -2.779 -3.376)
        (xy -2.768 -3.355)
        (xy -2.76 -3.334)
        (xy -2.752 -3.313)
        (xy -2.746 -3.289)
        (xy -2.741 -3.267)
        (xy -2.735 -3.245)
        (xy -2.733 -3.221)
        (xy -2.731 -3.197)
        (xy -2.73 -3.174)
        (xy -2.731 -3.152)
        (xy -2.733 -3.128)
        (xy -2.735 -3.104)
        (xy -2.741 -3.081)
        (xy -2.746 -3.059)
        (xy -2.752 -3.036)
        (xy -2.76 -3.015)
        (xy -2.768 -2.994)
        (xy -2.779 -2.972)
        (xy -2.79 -2.951)
        (xy -2.802 -2.932)
        (xy -2.815 -2.912)
        (xy -2.83 -2.894)
        (xy -2.844 -2.876)
        (xy -2.86 -2.859)
        (xy -2.877 -2.843)
        (xy -2.895 -2.829)
        (xy -2.913 -2.814)
        (xy -2.933 -2.801)
        (xy -2.952 -2.789)
        (xy -2.973 -2.778)
        (xy -2.995 -2.767)
        (xy -3.016 -2.759)
        (xy -3.037 -2.751)
        (xy -3.06 -2.745)
        (xy -3.082 -2.74)
        (xy -3.105 -2.734)
        (xy -3.129 -2.732)
        (xy -3.153 -2.73)
        (xy -3.175 -2.729)
        (xy -3.199 -2.73)
        (xy -3.223 -2.732)
        (xy -3.246 -2.734)
        (xy -3.27 -2.74)
        (xy -3.291 -2.745)
        (xy -3.314 -2.751)
        (xy -3.335 -2.758)
        (xy -3.358 -2.767)
        (xy -3.379 -2.777)
        (xy -3.399 -2.789)
        (xy -3.419 -2.801)
        (xy -3.437 -2.814)
        (xy -3.456 -2.829)
        (xy -3.473 -2.843)
        (xy -3.491 -2.859)
        (xy -3.506 -2.876)
        (xy -3.521 -2.894)
        (xy -3.536 -2.912)
        (xy -3.548 -2.931)
        (xy -3.561 -2.951)
        (xy -3.572 -2.971)
        (xy -3.582 -2.992)
        (xy -3.592 -3.015)
        (xy -3.598 -3.036)
        (xy -3.605 -3.059)
        (xy -3.61 -3.08)
        (xy -3.616 -3.104)
        (xy -3.618 -3.126)
        (xy -3.62 -3.15)
        (xy -3.621 -3.172)
        (xy -3.175 -3.172)
        (xy -3.175 -3.177)
      )

      (stroke (width 0.001) (type solid)) (fill solid) (layer "B.Paste"))
    (fp_poly
      (pts
        (xy -3.175 1.903)
        (xy -3.621 1.903)
        (xy -3.62 1.881)
        (xy -3.618 1.857)
        (xy -3.616 1.835)
        (xy -3.61 1.811)
        (xy -3.605 1.789)
        (xy -3.598 1.767)
        (xy -3.592 1.746)
        (xy -3.582 1.724)
        (xy -3.572 1.702)
        (xy -3.561 1.682)
        (xy -3.548 1.662)
        (xy -3.536 1.643)
        (xy -3.521 1.625)
        (xy -3.506 1.607)
        (xy -3.491 1.591)
        (xy -3.473 1.575)
        (xy -3.456 1.559)
        (xy -3.437 1.545)
        (xy -3.419 1.532)
        (xy -3.399 1.519)
        (xy -3.379 1.508)
        (xy -3.358 1.498)
        (xy -3.335 1.49)
        (xy -3.314 1.482)
        (xy -3.291 1.476)
        (xy -3.27 1.47)
        (xy -3.246 1.466)
        (xy -3.223 1.462)
        (xy -3.199 1.462)
        (xy -3.175 1.46)
        (xy -3.153 1.462)
        (xy -3.129 1.462)
        (xy -3.105 1.466)
        (xy -3.082 1.47)
        (xy -3.06 1.476)
        (xy -3.037 1.482)
        (xy -3.016 1.49)
        (xy -2.995 1.498)
        (xy -2.973 1.509)
        (xy -2.952 1.52)
        (xy -2.933 1.532)
        (xy -2.913 1.545)
        (xy -2.895 1.559)
        (xy -2.877 1.575)
        (xy -2.86 1.591)
        (xy -2.844 1.607)
        (xy -2.83 1.625)
        (xy -2.815 1.643)
        (xy -2.802 1.663)
        (xy -2.79 1.684)
        (xy -2.779 1.704)
        (xy -2.768 1.724)
        (xy -2.76 1.746)
        (xy -2.752 1.767)
        (xy -2.746 1.79)
        (xy -2.741 1.813)
        (xy -2.735 1.835)
        (xy -2.733 1.859)
        (xy -2.731 1.882)
        (xy -2.73 1.905)
        (xy -2.731 1.928)
        (xy -2.733 1.952)
        (xy -2.735 1.976)
        (xy -2.741 1.998)
        (xy -2.746 2.02)
        (xy -2.752 2.044)
        (xy -2.76 2.065)
        (xy -2.768 2.086)
        (xy -2.779 2.108)
        (xy -2.79 2.127)
        (xy -2.802 2.147)
        (xy -2.815 2.167)
        (xy -2.83 2.186)
        (xy -2.844 2.203)
        (xy -2.86 2.221)
        (xy -2.877 2.237)
        (xy -2.895 2.251)
        (xy -2.913 2.266)
        (xy -2.933 2.278)
        (xy -2.952 2.29)
        (xy -2.973 2.302)
        (xy -2.995 2.312)
        (xy -3.016 2.32)
        (xy -3.037 2.328)
        (xy -3.06 2.335)
        (xy -3.082 2.34)
        (xy -3.105 2.346)
        (xy -3.129 2.348)
        (xy -3.153 2.35)
        (xy -3.175 2.351)
        (xy -3.199 2.35)
        (xy -3.223 2.348)
        (xy -3.246 2.346)
        (xy -3.27 2.34)
        (xy -3.291 2.335)
        (xy -3.314 2.328)
        (xy -3.335 2.322)
        (xy -3.358 2.312)
        (xy -3.379 2.302)
        (xy -3.399 2.291)
        (xy -3.419 2.278)
        (xy -3.437 2.266)
        (xy -3.456 2.251)
        (xy -3.473 2.237)
        (xy -3.491 2.221)
        (xy -3.506 2.203)
        (xy -3.521 2.186)
        (xy -3.536 2.167)
        (xy -3.548 2.149)
        (xy -3.561 2.129)
        (xy -3.572 2.109)
        (xy -3.582 2.088)
        (xy -3.592 2.065)
        (xy -3.598 2.044)
        (xy -3.605 2.021)
        (xy -3.61 2)
        (xy -3.616 1.976)
        (xy -3.618 1.954)
        (xy -3.62 1.93)
        (xy -3.621 1.907)
        (xy -3.175 1.907)
        (xy -3.175 1.903)
      )

      (stroke (width 0.001) (type solid)) (fill solid) (layer "B.Paste"))
    (fp_poly
      (pts
        (xy -3.175 3.173)
        (xy -3.621 3.173)
        (xy -3.62 3.151)
        (xy -3.618 3.127)
        (xy -3.616 3.105)
        (xy -3.61 3.081)
        (xy -3.605 3.06)
        (xy -3.598 3.037)
        (xy -3.592 3.016)
        (xy -3.582 2.993)
        (xy -3.572 2.972)
        (xy -3.561 2.952)
        (xy -3.548 2.932)
        (xy -3.536 2.913)
        (xy -3.521 2.895)
        (xy -3.506 2.877)
        (xy -3.491 2.86)
        (xy -3.473 2.844)
        (xy -3.456 2.83)
        (xy -3.437 2.815)
        (xy -3.419 2.802)
        (xy -3.399 2.79)
        (xy -3.379 2.778)
        (xy -3.358 2.768)
        (xy -3.335 2.759)
        (xy -3.314 2.752)
        (xy -3.291 2.746)
        (xy -3.27 2.741)
        (xy -3.246 2.735)
        (xy -3.223 2.733)
        (xy -3.199 2.731)
        (xy -3.175 2.73)
        (xy -3.153 2.731)
        (xy -3.129 2.733)
        (xy -3.105 2.735)
        (xy -3.082 2.741)
        (xy -3.06 2.746)
        (xy -3.037 2.752)
        (xy -3.016 2.76)
        (xy -2.995 2.768)
        (xy -2.973 2.779)
        (xy -2.952 2.79)
        (xy -2.933 2.802)
        (xy -2.913 2.815)
        (xy -2.895 2.83)
        (xy -2.877 2.844)
        (xy -2.86 2.86)
        (xy -2.844 2.877)
        (xy -2.83 2.895)
        (xy -2.815 2.913)
        (xy -2.802 2.933)
        (xy -2.79 2.952)
        (xy -2.779 2.973)
        (xy -2.768 2.995)
        (xy -2.76 3.016)
        (xy -2.752 3.037)
        (xy -2.746 3.06)
        (xy -2.741 3.082)
        (xy -2.735 3.105)
        (xy -2.733 3.129)
        (xy -2.731 3.153)
        (xy -2.73 3.175)
        (xy -2.731 3.198)
        (xy -2.733 3.222)
        (xy -2.735 3.246)
        (xy -2.741 3.268)
        (xy -2.746 3.29)
        (xy -2.752 3.314)
        (xy -2.76 3.335)
        (xy -2.768 3.356)
        (xy -2.779 3.377)
        (xy -2.79 3.397)
        (xy -2.802 3.417)
        (xy -2.815 3.437)
        (xy -2.83 3.455)
        (xy -2.844 3.473)
        (xy -2.86 3.491)
        (xy -2.877 3.506)
        (xy -2.895 3.521)
        (xy -2.913 3.536)
        (xy -2.933 3.548)
        (xy -2.952 3.56)
        (xy -2.973 3.572)
        (xy -2.995 3.582)
        (xy -3.016 3.59)
        (xy -3.037 3.598)
        (xy -3.06 3.605)
        (xy -3.082 3.61)
        (xy -3.105 3.616)
        (xy -3.129 3.618)
        (xy -3.153 3.62)
        (xy -3.175 3.621)
        (xy -3.199 3.62)
        (xy -3.223 3.618)
        (xy -3.246 3.616)
        (xy -3.27 3.61)
        (xy -3.291 3.605)
        (xy -3.314 3.598)
        (xy -3.335 3.592)
        (xy -3.358 3.582)
        (xy -3.379 3.572)
        (xy -3.399 3.561)
        (xy -3.419 3.548)
        (xy -3.437 3.536)
        (xy -3.456 3.521)
        (xy -3.473 3.506)
        (xy -3.491 3.491)
        (xy -3.506 3.473)
        (xy -3.521 3.456)
        (xy -3.536 3.437)
        (xy -3.548 3.419)
        (xy -3.561 3.399)
        (xy -3.572 3.379)
        (xy -3.582 3.358)
        (xy -3.592 3.335)
        (xy -3.598 3.314)
        (xy -3.605 3.291)
        (xy -3.61 3.27)
        (xy -3.616 3.246)
        (xy -3.618 3.223)
        (xy -3.62 3.199)
        (xy -3.621 3.178)
        (xy -3.175 3.178)
        (xy -3.175 3.173)
      )

      (stroke (width 0.001) (type solid)) (fill solid) (layer "B.Paste"))
    (fp_poly
      (pts
        (xy -3.175 4.443)
        (xy -3.621 4.443)
        (xy -3.62 4.422)
        (xy -3.618 4.398)
        (xy -3.616 4.374)
        (xy -3.61 4.351)
        (xy -3.605 4.329)
        (xy -3.598 4.308)
        (xy -3.592 4.286)
        (xy -3.582 4.263)
        (xy -3.572 4.242)
        (xy -3.561 4.223)
        (xy -3.548 4.202)
        (xy -3.536 4.183)
        (xy -3.521 4.164)
        (xy -3.506 4.148)
        (xy -3.491 4.13)
        (xy -3.473 4.114)
        (xy -3.456 4.1)
        (xy -3.437 4.085)
        (xy -3.419 4.072)
        (xy -3.399 4.06)
        (xy -3.379 4.048)
        (xy -3.358 4.039)
        (xy -3.335 4.029)
        (xy -3.314 4.023)
        (xy -3.291 4.015)
        (xy -3.27 4.01)
        (xy -3.246 4.005)
        (xy -3.223 4.002)
        (xy -3.199 4.002)
        (xy -3.175 4)
        (xy -3.153 4.002)
        (xy -3.129 4.002)
        (xy -3.105 4.005)
        (xy -3.082 4.01)
        (xy -3.06 4.015)
        (xy -3.037 4.023)
        (xy -3.016 4.031)
        (xy -2.995 4.039)
        (xy -2.973 4.05)
        (xy -2.952 4.06)
        (xy -2.933 4.072)
        (xy -2.913 4.085)
        (xy -2.895 4.1)
        (xy -2.877 4.114)
        (xy -2.86 4.13)
        (xy -2.844 4.148)
        (xy -2.83 4.165)
        (xy -2.815 4.183)
        (xy -2.802 4.204)
        (xy -2.79 4.223)
        (xy -2.779 4.244)
        (xy -2.768 4.265)
        (xy -2.76 4.286)
        (xy -2.752 4.308)
        (xy -2.746 4.33)
        (xy -2.741 4.353)
        (xy -2.735 4.375)
        (xy -2.733 4.398)
        (xy -2.731 4.422)
        (xy -2.73 4.446)
        (xy -2.731 4.468)
        (xy -2.733 4.492)
        (xy -2.735 4.515)
        (xy -2.741 4.539)
        (xy -2.746 4.56)
        (xy -2.752 4.584)
        (xy -2.76 4.604)
        (xy -2.768 4.627)
        (xy -2.779 4.648)
        (xy -2.79 4.669)
        (xy -2.802 4.688)
        (xy -2.815 4.707)
        (xy -2.83 4.725)
        (xy -2.844 4.744)
        (xy -2.86 4.76)
        (xy -2.877 4.776)
        (xy -2.895 4.792)
        (xy -2.913 4.805)
        (xy -2.933 4.818)
        (xy -2.952 4.83)
        (xy -2.973 4.842)
        (xy -2.995 4.853)
        (xy -3.016 4.861)
        (xy -3.037 4.869)
        (xy -3.06 4.875)
        (xy -3.082 4.88)
        (xy -3.105 4.885)
        (xy -3.129 4.888)
        (xy -3.153 4.89)
        (xy -3.175 4.89)
        (xy -3.199 4.89)
        (xy -3.223 4.888)
        (xy -3.246 4.885)
        (xy -3.27 4.88)
        (xy -3.291 4.875)
        (xy -3.314 4.869)
        (xy -3.335 4.861)
        (xy -3.358 4.853)
        (xy -3.379 4.842)
        (xy -3.399 4.832)
        (xy -3.419 4.818)
        (xy -3.437 4.805)
        (xy -3.456 4.792)
        (xy -3.473 4.776)
        (xy -3.491 4.76)
        (xy -3.506 4.744)
        (xy -3.521 4.726)
        (xy -3.536 4.707)
        (xy -3.548 4.688)
        (xy -3.561 4.669)
        (xy -3.572 4.648)
        (xy -3.582 4.627)
        (xy -3.592 4.606)
        (xy -3.598 4.584)
        (xy -3.605 4.561)
        (xy -3.61 4.539)
        (xy -3.616 4.516)
        (xy -3.618 4.494)
        (xy -3.62 4.47)
        (xy -3.621 4.447)
        (xy -3.175 4.447)
        (xy -3.175 4.443)
      )

      (stroke (width 0.001) (type solid)) (fill solid) (layer "B.Paste"))
    (fp_poly
      (pts
        (xy -3.175 5.713)
        (xy -3.621 5.713)
        (xy -3.62 5.691)
        (xy -3.618 5.667)
        (xy -3.616 5.645)
        (xy -3.61 5.622)
        (xy -3.605 5.6)
        (xy -3.598 5.577)
        (xy -3.592 5.555)
        (xy -3.582 5.534)
        (xy -3.572 5.512)
        (xy -3.561 5.492)
        (xy -3.548 5.473)
        (xy -3.536 5.454)
        (xy -3.521 5.435)
        (xy -3.506 5.417)
        (xy -3.491 5.401)
        (xy -3.473 5.385)
        (xy -3.456 5.369)
        (xy -3.437 5.356)
        (xy -3.419 5.342)
        (xy -3.399 5.329)
        (xy -3.379 5.318)
        (xy -3.358 5.308)
        (xy -3.335 5.3)
        (xy -3.314 5.292)
        (xy -3.291 5.286)
        (xy -3.27 5.281)
        (xy -3.246 5.276)
        (xy -3.223 5.273)
        (xy -3.199 5.271)
        (xy -3.175 5.27)
        (xy -3.153 5.271)
        (xy -3.129 5.273)
        (xy -3.105 5.276)
        (xy -3.082 5.281)
        (xy -3.06 5.286)
        (xy -3.037 5.292)
        (xy -3.016 5.3)
        (xy -2.995 5.308)
        (xy -2.973 5.319)
        (xy -2.952 5.33)
        (xy -2.933 5.342)
        (xy -2.913 5.356)
        (xy -2.895 5.369)
        (xy -2.877 5.385)
        (xy -2.86 5.401)
        (xy -2.844 5.417)
        (xy -2.83 5.435)
        (xy -2.815 5.454)
        (xy -2.802 5.473)
        (xy -2.79 5.492)
        (xy -2.779 5.513)
        (xy -2.768 5.534)
        (xy -2.76 5.556)
        (xy -2.752 5.577)
        (xy -2.746 5.6)
        (xy -2.741 5.622)
        (xy -2.735 5.645)
        (xy -2.733 5.669)
        (xy -2.731 5.693)
        (xy -2.73 5.715)
        (xy -2.731 5.739)
        (xy -2.733 5.762)
        (xy -2.735 5.786)
        (xy -2.741 5.808)
        (xy -2.746 5.83)
        (xy -2.752 5.853)
        (xy -2.76 5.874)
        (xy -2.768 5.896)
        (xy -2.779 5.917)
        (xy -2.79 5.938)
        (xy -2.802 5.957)
        (xy -2.815 5.978)
        (xy -2.83 5.995)
        (xy -2.844 6.013)
        (xy -2.86 6.031)
        (xy -2.877 6.047)
        (xy -2.895 6.061)
        (xy -2.913 6.076)
        (xy -2.933 6.088)
        (xy -2.952 6.1)
        (xy -2.973 6.111)
        (xy -2.995 6.122)
        (xy -3.016 6.13)
        (xy -3.037 6.138)
        (xy -3.06 6.145)
        (xy -3.082 6.151)
        (xy -3.105 6.156)
        (xy -3.129 6.159)
        (xy -3.153 6.159)
        (xy -3.175 6.161)
        (xy -3.199 6.159)
        (xy -3.223 6.159)
        (xy -3.246 6.156)
        (xy -3.27 6.151)
        (xy -3.291 6.145)
        (xy -3.314 6.138)
        (xy -3.335 6.132)
        (xy -3.358 6.122)
        (xy -3.379 6.112)
        (xy -3.399 6.101)
        (xy -3.419 6.088)
        (xy -3.437 6.076)
        (xy -3.456 6.061)
        (xy -3.473 6.047)
        (xy -3.491 6.031)
        (xy -3.506 6.013)
        (xy -3.521 5.997)
        (xy -3.536 5.978)
        (xy -3.548 5.959)
        (xy -3.561 5.938)
        (xy -3.572 5.919)
        (xy -3.582 5.898)
        (xy -3.592 5.875)
        (xy -3.598 5.853)
        (xy -3.605 5.832)
        (xy -3.61 5.81)
        (xy -3.616 5.786)
        (xy -3.618 5.763)
        (xy -3.62 5.739)
        (xy -3.621 5.718)
        (xy -3.175 5.718)
        (xy -3.175 5.713)
      )

      (stroke (width 0.001) (type solid)) (fill solid) (layer "B.Paste"))
    (fp_poly
      (pts
        (xy -1.905 -5.717)
        (xy -2.351 -5.717)
        (xy -2.35 -5.738)
        (xy -2.348 -5.762)
        (xy -2.346 -5.785)
        (xy -2.34 -5.809)
        (xy -2.335 -5.831)
        (xy -2.328 -5.852)
        (xy -2.322 -5.874)
        (xy -2.312 -5.897)
        (xy -2.302 -5.918)
        (xy -2.291 -5.937)
        (xy -2.278 -5.958)
        (xy -2.266 -5.977)
        (xy -2.251 -5.996)
        (xy -2.237 -6.012)
        (xy -2.221 -6.03)
        (xy -2.203 -6.046)
        (xy -2.186 -6.06)
        (xy -2.167 -6.075)
        (xy -2.149 -6.087)
        (xy -2.129 -6.1)
        (xy -2.109 -6.111)
        (xy -2.088 -6.121)
        (xy -2.065 -6.131)
        (xy -2.044 -6.137)
        (xy -2.021 -6.144)
        (xy -2 -6.15)
        (xy -1.976 -6.155)
        (xy -1.954 -6.158)
        (xy -1.93 -6.158)
        (xy -1.905 -6.16)
        (xy -1.882 -6.158)
        (xy -1.859 -6.158)
        (xy -1.835 -6.155)
        (xy -1.813 -6.15)
        (xy -1.79 -6.144)
        (xy -1.767 -6.137)
        (xy -1.746 -6.129)
        (xy -1.724 -6.121)
        (xy -1.704 -6.11)
        (xy -1.684 -6.099)
        (xy -1.663 -6.087)
        (xy -1.643 -6.075)
        (xy -1.625 -6.06)
        (xy -1.607 -6.046)
        (xy -1.591 -6.03)
        (xy -1.575 -6.012)
        (xy -1.559 -5.994)
        (xy -1.545 -5.977)
        (xy -1.532 -5.956)
        (xy -1.52 -5.937)
        (xy -1.509 -5.916)
        (xy -1.498 -5.895)
        (xy -1.49 -5.873)
        (xy -1.482 -5.852)
        (xy -1.476 -5.829)
        (xy -1.47 -5.807)
        (xy -1.466 -5.785)
        (xy -1.462 -5.761)
        (xy -1.462 -5.738)
        (xy -1.46 -5.714)
        (xy -1.462 -5.692)
        (xy -1.462 -5.668)
        (xy -1.466 -5.644)
        (xy -1.47 -5.621)
        (xy -1.476 -5.599)
        (xy -1.482 -5.576)
        (xy -1.49 -5.555)
        (xy -1.498 -5.533)
        (xy -1.509 -5.512)
        (xy -1.52 -5.491)
        (xy -1.532 -5.472)
        (xy -1.545 -5.453)
        (xy -1.559 -5.434)
        (xy -1.575 -5.416)
        (xy -1.591 -5.4)
        (xy -1.607 -5.384)
        (xy -1.625 -5.368)
        (xy -1.643 -5.355)
        (xy -1.663 -5.341)
        (xy -1.684 -5.329)
        (xy -1.704 -5.318)
        (xy -1.724 -5.307)
        (xy -1.746 -5.299)
        (xy -1.767 -5.291)
        (xy -1.79 -5.285)
        (xy -1.813 -5.28)
        (xy -1.835 -5.275)
        (xy -1.859 -5.272)
        (xy -1.882 -5.27)
        (xy -1.905 -5.269)
        (xy -1.93 -5.27)
        (xy -1.954 -5.272)
        (xy -1.976 -5.275)
        (xy -2 -5.28)
        (xy -2.021 -5.285)
        (xy -2.044 -5.291)
        (xy -2.065 -5.299)
        (xy -2.088 -5.307)
        (xy -2.109 -5.317)
        (xy -2.129 -5.328)
        (xy -2.149 -5.341)
        (xy -2.167 -5.355)
        (xy -2.186 -5.368)
        (xy -2.203 -5.384)
        (xy -2.221 -5.4)
        (xy -2.237 -5.416)
        (xy -2.251 -5.434)
        (xy -2.266 -5.453)
        (xy -2.278 -5.472)
        (xy -2.291 -5.491)
        (xy -2.302 -5.511)
        (xy -2.312 -5.533)
        (xy -2.322 -5.554)
        (xy -2.328 -5.576)
        (xy -2.335 -5.599)
        (xy -2.34 -5.621)
        (xy -2.346 -5.644)
        (xy -2.348 -5.666)
        (xy -2.35 -5.69)
        (xy -2.351 -5.712)
        (xy -1.905 -5.712)
        (xy -1.905 -5.717)
      )

      (stroke (width 0.001) (type solid)) (fill solid) (layer "B.Paste"))
    (fp_poly
      (pts
        (xy -1.905 -3.177)
        (xy -2.351 -3.177)
        (xy -2.35 -3.198)
        (xy -2.348 -3.222)
        (xy -2.346 -3.245)
        (xy -2.34 -3.269)
        (xy -2.335 -3.29)
        (xy -2.328 -3.313)
        (xy -2.322 -3.334)
        (xy -2.312 -3.357)
        (xy -2.302 -3.378)
        (xy -2.291 -3.398)
        (xy -2.278 -3.418)
        (xy -2.266 -3.436)
        (xy -2.251 -3.455)
        (xy -2.237 -3.472)
        (xy -2.221 -3.49)
        (xy -2.203 -3.505)
        (xy -2.186 -3.52)
        (xy -2.167 -3.535)
        (xy -2.149 -3.547)
        (xy -2.129 -3.56)
        (xy -2.109 -3.571)
        (xy -2.088 -3.581)
        (xy -2.065 -3.591)
        (xy -2.044 -3.597)
        (xy -2.021 -3.604)
        (xy -2 -3.609)
        (xy -1.976 -3.615)
        (xy -1.954 -3.617)
        (xy -1.93 -3.619)
        (xy -1.905 -3.62)
        (xy -1.882 -3.619)
        (xy -1.859 -3.617)
        (xy -1.835 -3.615)
        (xy -1.813 -3.609)
        (xy -1.79 -3.604)
        (xy -1.767 -3.597)
        (xy -1.746 -3.589)
        (xy -1.724 -3.581)
        (xy -1.704 -3.571)
        (xy -1.684 -3.559)
        (xy -1.663 -3.547)
        (xy -1.643 -3.535)
        (xy -1.625 -3.52)
        (xy -1.607 -3.505)
        (xy -1.591 -3.49)
        (xy -1.575 -3.472)
        (xy -1.559 -3.454)
        (xy -1.545 -3.436)
        (xy -1.532 -3.416)
        (xy -1.52 -3.396)
        (xy -1.509 -3.376)
        (xy -1.498 -3.355)
        (xy -1.49 -3.334)
        (xy -1.482 -3.313)
        (xy -1.476 -3.289)
        (xy -1.47 -3.267)
        (xy -1.466 -3.245)
        (xy -1.462 -3.221)
        (xy -1.462 -3.197)
        (xy -1.46 -3.174)
        (xy -1.462 -3.152)
        (xy -1.462 -3.128)
        (xy -1.466 -3.104)
        (xy -1.47 -3.081)
        (xy -1.476 -3.059)
        (xy -1.482 -3.036)
        (xy -1.49 -3.015)
        (xy -1.498 -2.994)
        (xy -1.509 -2.972)
        (xy -1.52 -2.951)
        (xy -1.532 -2.932)
        (xy -1.545 -2.912)
        (xy -1.559 -2.894)
        (xy -1.575 -2.876)
        (xy -1.591 -2.859)
        (xy -1.607 -2.843)
        (xy -1.625 -2.829)
        (xy -1.643 -2.814)
        (xy -1.663 -2.801)
        (xy -1.682 -2.789)
        (xy -1.704 -2.778)
        (xy -1.724 -2.767)
        (xy -1.746 -2.759)
        (xy -1.767 -2.751)
        (xy -1.79 -2.745)
        (xy -1.813 -2.74)
        (xy -1.835 -2.734)
        (xy -1.859 -2.732)
        (xy -1.882 -2.73)
        (xy -1.905 -2.729)
        (xy -1.93 -2.73)
        (xy -1.954 -2.732)
        (xy -1.976 -2.734)
        (xy -2 -2.74)
        (xy -2.021 -2.745)
        (xy -2.044 -2.751)
        (xy -2.065 -2.758)
        (xy -2.088 -2.767)
        (xy -2.109 -2.777)
        (xy -2.129 -2.789)
        (xy -2.149 -2.801)
        (xy -2.167 -2.814)
        (xy -2.186 -2.829)
        (xy -2.203 -2.843)
        (xy -2.221 -2.859)
        (xy -2.237 -2.876)
        (xy -2.251 -2.894)
        (xy -2.266 -2.912)
        (xy -2.278 -2.931)
        (xy -2.291 -2.951)
        (xy -2.302 -2.971)
        (xy -2.312 -2.992)
        (xy -2.322 -3.015)
        (xy -2.328 -3.036)
        (xy -2.335 -3.059)
        (xy -2.34 -3.08)
        (xy -2.346 -3.104)
        (xy -2.348 -3.126)
        (xy -2.35 -3.15)
        (xy -2.351 -3.172)
        (xy -1.905 -3.172)
        (xy -1.905 -3.177)
      )

      (stroke (width 0.001) (type solid)) (fill solid) (layer "B.Paste"))
    (fp_poly
      (pts
        (xy -1.905 1.903)
        (xy -2.351 1.903)
        (xy -2.35 1.881)
        (xy -2.348 1.857)
        (xy -2.346 1.835)
        (xy -2.34 1.811)
        (xy -2.335 1.789)
        (xy -2.328 1.767)
        (xy -2.322 1.746)
        (xy -2.312 1.724)
        (xy -2.302 1.702)
        (xy -2.291 1.682)
        (xy -2.278 1.662)
        (xy -2.266 1.643)
        (xy -2.251 1.625)
        (xy -2.237 1.607)
        (xy -2.221 1.591)
        (xy -2.203 1.575)
        (xy -2.186 1.559)
        (xy -2.167 1.545)
        (xy -2.149 1.532)
        (xy -2.129 1.519)
        (xy -2.109 1.508)
        (xy -2.088 1.498)
        (xy -2.065 1.49)
        (xy -2.044 1.482)
        (xy -2.021 1.476)
        (xy -2 1.47)
        (xy -1.976 1.466)
        (xy -1.954 1.462)
        (xy -1.93 1.462)
        (xy -1.905 1.46)
        (xy -1.882 1.462)
        (xy -1.859 1.462)
        (xy -1.835 1.466)
        (xy -1.813 1.47)
        (xy -1.79 1.476)
        (xy -1.767 1.482)
        (xy -1.746 1.49)
        (xy -1.724 1.498)
        (xy -1.704 1.509)
        (xy -1.684 1.52)
        (xy -1.663 1.532)
        (xy -1.643 1.545)
        (xy -1.625 1.559)
        (xy -1.607 1.575)
        (xy -1.591 1.591)
        (xy -1.575 1.607)
        (xy -1.559 1.625)
        (xy -1.545 1.643)
        (xy -1.532 1.663)
        (xy -1.52 1.684)
        (xy -1.509 1.704)
        (xy -1.498 1.724)
        (xy -1.49 1.746)
        (xy -1.482 1.767)
        (xy -1.476 1.79)
        (xy -1.47 1.813)
        (xy -1.466 1.835)
        (xy -1.462 1.859)
        (xy -1.462 1.882)
        (xy -1.46 1.905)
        (xy -1.462 1.928)
        (xy -1.462 1.952)
        (xy -1.466 1.976)
        (xy -1.47 1.998)
        (xy -1.476 2.02)
        (xy -1.482 2.044)
        (xy -1.49 2.065)
        (xy -1.498 2.086)
        (xy -1.509 2.108)
        (xy -1.52 2.127)
        (xy -1.532 2.147)
        (xy -1.545 2.167)
        (xy -1.559 2.186)
        (xy -1.575 2.203)
        (xy -1.591 2.221)
        (xy -1.607 2.237)
        (xy -1.625 2.251)
        (xy -1.643 2.266)
        (xy -1.663 2.278)
        (xy -1.684 2.29)
        (xy -1.704 2.302)
        (xy -1.724 2.312)
        (xy -1.746 2.32)
        (xy -1.767 2.328)
        (xy -1.79 2.335)
        (xy -1.813 2.34)
        (xy -1.835 2.346)
        (xy -1.859 2.348)
        (xy -1.882 2.35)
        (xy -1.905 2.351)
        (xy -1.93 2.35)
        (xy -1.954 2.348)
        (xy -1.976 2.346)
        (xy -2 2.34)
        (xy -2.021 2.335)
        (xy -2.044 2.328)
        (xy -2.065 2.322)
        (xy -2.088 2.312)
        (xy -2.109 2.302)
        (xy -2.129 2.291)
        (xy -2.149 2.278)
        (xy -2.167 2.266)
        (xy -2.186 2.251)
        (xy -2.203 2.237)
        (xy -2.221 2.221)
        (xy -2.237 2.203)
        (xy -2.251 2.186)
        (xy -2.266 2.167)
        (xy -2.278 2.149)
        (xy -2.291 2.129)
        (xy -2.302 2.109)
        (xy -2.312 2.088)
        (xy -2.322 2.065)
        (xy -2.328 2.044)
        (xy -2.335 2.021)
        (xy -2.34 2)
        (xy -2.346 1.976)
        (xy -2.348 1.954)
        (xy -2.35 1.93)
        (xy -2.351 1.907)
        (xy -1.905 1.907)
        (xy -1.905 1.903)
      )

      (stroke (width 0.001) (type solid)) (fill solid) (layer "B.Paste"))
    (fp_poly
      (pts
        (xy -1.905 3.173)
        (xy -2.351 3.173)
        (xy -2.35 3.151)
        (xy -2.348 3.127)
        (xy -2.346 3.105)
        (xy -2.34 3.081)
        (xy -2.335 3.06)
        (xy -2.328 3.037)
        (xy -2.322 3.016)
        (xy -2.312 2.993)
        (xy -2.302 2.972)
        (xy -2.291 2.952)
        (xy -2.278 2.932)
        (xy -2.266 2.913)
        (xy -2.251 2.895)
        (xy -2.237 2.877)
        (xy -2.221 2.86)
        (xy -2.203 2.844)
        (xy -2.186 2.83)
        (xy -2.167 2.815)
        (xy -2.149 2.802)
        (xy -2.129 2.79)
        (xy -2.109 2.778)
        (xy -2.088 2.768)
        (xy -2.065 2.759)
        (xy -2.044 2.752)
        (xy -2.021 2.746)
        (xy -2 2.741)
        (xy -1.976 2.735)
        (xy -1.954 2.733)
        (xy -1.93 2.731)
        (xy -1.905 2.73)
        (xy -1.882 2.731)
        (xy -1.859 2.733)
        (xy -1.835 2.735)
        (xy -1.813 2.741)
        (xy -1.79 2.746)
        (xy -1.767 2.752)
        (xy -1.746 2.76)
        (xy -1.724 2.768)
        (xy -1.704 2.779)
        (xy -1.682 2.79)
        (xy -1.663 2.802)
        (xy -1.643 2.815)
        (xy -1.625 2.83)
        (xy -1.607 2.844)
        (xy -1.591 2.86)
        (xy -1.575 2.877)
        (xy -1.559 2.895)
        (xy -1.545 2.913)
        (xy -1.532 2.933)
        (xy -1.52 2.952)
        (xy -1.509 2.973)
        (xy -1.498 2.995)
        (xy -1.49 3.016)
        (xy -1.482 3.037)
        (xy -1.476 3.06)
        (xy -1.47 3.082)
        (xy -1.466 3.105)
        (xy -1.462 3.129)
        (xy -1.462 3.153)
        (xy -1.46 3.175)
        (xy -1.462 3.198)
        (xy -1.462 3.222)
        (xy -1.466 3.246)
        (xy -1.47 3.268)
        (xy -1.476 3.29)
        (xy -1.482 3.314)
        (xy -1.49 3.335)
        (xy -1.498 3.356)
        (xy -1.509 3.377)
        (xy -1.52 3.397)
        (xy -1.532 3.417)
        (xy -1.545 3.437)
        (xy -1.559 3.455)
        (xy -1.575 3.473)
        (xy -1.591 3.491)
        (xy -1.607 3.506)
        (xy -1.625 3.521)
        (xy -1.643 3.536)
        (xy -1.663 3.548)
        (xy -1.684 3.56)
        (xy -1.704 3.572)
        (xy -1.724 3.582)
        (xy -1.746 3.59)
        (xy -1.767 3.598)
        (xy -1.79 3.605)
        (xy -1.813 3.61)
        (xy -1.835 3.616)
        (xy -1.859 3.618)
        (xy -1.882 3.62)
        (xy -1.905 3.621)
        (xy -1.93 3.62)
        (xy -1.954 3.618)
        (xy -1.976 3.616)
        (xy -2 3.61)
        (xy -2.021 3.605)
        (xy -2.044 3.598)
        (xy -2.065 3.592)
        (xy -2.088 3.582)
        (xy -2.109 3.572)
        (xy -2.129 3.561)
        (xy -2.149 3.548)
        (xy -2.167 3.536)
        (xy -2.186 3.521)
        (xy -2.203 3.506)
        (xy -2.221 3.491)
        (xy -2.237 3.473)
        (xy -2.251 3.456)
        (xy -2.266 3.437)
        (xy -2.278 3.419)
        (xy -2.291 3.399)
        (xy -2.302 3.379)
        (xy -2.312 3.358)
        (xy -2.322 3.335)
        (xy -2.328 3.314)
        (xy -2.335 3.291)
        (xy -2.34 3.27)
        (xy -2.346 3.246)
        (xy -2.348 3.223)
        (xy -2.35 3.199)
        (xy -2.351 3.178)
        (xy -1.905 3.178)
        (xy -1.905 3.173)
      )

      (stroke (width 0.001) (type solid)) (fill solid) (layer "B.Paste"))
    (fp_poly
      (pts
        (xy -1.905 4.443)
        (xy -2.351 4.443)
        (xy -2.35 4.422)
        (xy -2.348 4.398)
        (xy -2.346 4.374)
        (xy -2.34 4.351)
        (xy -2.335 4.329)
        (xy -2.328 4.308)
        (xy -2.322 4.286)
        (xy -2.312 4.263)
        (xy -2.302 4.242)
        (xy -2.291 4.223)
        (xy -2.278 4.202)
        (xy -2.266 4.183)
        (xy -2.251 4.164)
        (xy -2.237 4.148)
        (xy -2.221 4.13)
        (xy -2.203 4.114)
        (xy -2.186 4.1)
        (xy -2.167 4.085)
        (xy -2.149 4.072)
        (xy -2.129 4.06)
        (xy -2.109 4.048)
        (xy -2.088 4.039)
        (xy -2.065 4.029)
        (xy -2.044 4.023)
        (xy -2.021 4.015)
        (xy -2 4.01)
        (xy -1.976 4.005)
        (xy -1.954 4.002)
        (xy -1.93 4.002)
        (xy -1.905 4)
        (xy -1.882 4.002)
        (xy -1.859 4.002)
        (xy -1.835 4.005)
        (xy -1.813 4.01)
        (xy -1.79 4.015)
        (xy -1.767 4.023)
        (xy -1.746 4.031)
        (xy -1.724 4.039)
        (xy -1.704 4.05)
        (xy -1.684 4.06)
        (xy -1.663 4.072)
        (xy -1.643 4.085)
        (xy -1.625 4.1)
        (xy -1.607 4.114)
        (xy -1.591 4.13)
        (xy -1.575 4.148)
        (xy -1.559 4.165)
        (xy -1.545 4.183)
        (xy -1.532 4.204)
        (xy -1.52 4.223)
        (xy -1.509 4.244)
        (xy -1.498 4.265)
        (xy -1.49 4.286)
        (xy -1.482 4.308)
        (xy -1.476 4.33)
        (xy -1.47 4.353)
        (xy -1.466 4.375)
        (xy -1.462 4.398)
        (xy -1.462 4.422)
        (xy -1.46 4.446)
        (xy -1.462 4.468)
        (xy -1.462 4.492)
        (xy -1.466 4.515)
        (xy -1.47 4.539)
        (xy -1.476 4.56)
        (xy -1.482 4.584)
        (xy -1.49 4.604)
        (xy -1.498 4.627)
        (xy -1.509 4.648)
        (xy -1.52 4.669)
        (xy -1.532 4.688)
        (xy -1.545 4.707)
        (xy -1.559 4.725)
        (xy -1.575 4.744)
        (xy -1.591 4.76)
        (xy -1.607 4.776)
        (xy -1.625 4.792)
        (xy -1.643 4.805)
        (xy -1.663 4.818)
        (xy -1.682 4.83)
        (xy -1.704 4.842)
        (xy -1.724 4.853)
        (xy -1.746 4.861)
        (xy -1.767 4.869)
        (xy -1.79 4.875)
        (xy -1.813 4.88)
        (xy -1.835 4.885)
        (xy -1.859 4.888)
        (xy -1.882 4.89)
        (xy -1.905 4.89)
        (xy -1.93 4.89)
        (xy -1.954 4.888)
        (xy -1.976 4.885)
        (xy -2 4.88)
        (xy -2.021 4.875)
        (xy -2.044 4.869)
        (xy -2.065 4.861)
        (xy -2.088 4.853)
        (xy -2.109 4.842)
        (xy -2.129 4.832)
        (xy -2.149 4.818)
        (xy -2.167 4.805)
        (xy -2.186 4.792)
        (xy -2.203 4.776)
        (xy -2.221 4.76)
        (xy -2.237 4.744)
        (xy -2.251 4.726)
        (xy -2.266 4.707)
        (xy -2.278 4.688)
        (xy -2.291 4.669)
        (xy -2.302 4.648)
        (xy -2.312 4.627)
        (xy -2.322 4.606)
        (xy -2.328 4.584)
        (xy -2.335 4.561)
        (xy -2.34 4.539)
        (xy -2.346 4.516)
        (xy -2.348 4.494)
        (xy -2.35 4.47)
        (xy -2.351 4.447)
        (xy -1.905 4.447)
        (xy -1.905 4.443)
      )

      (stroke (width 0.001) (type solid)) (fill solid) (layer "B.Paste"))
    (fp_poly
      (pts
        (xy -1.905 5.713)
        (xy -2.351 5.713)
        (xy -2.35 5.691)
        (xy -2.348 5.667)
        (xy -2.346 5.645)
        (xy -2.34 5.622)
        (xy -2.335 5.6)
        (xy -2.328 5.577)
        (xy -2.322 5.555)
        (xy -2.312 5.534)
        (xy -2.302 5.512)
        (xy -2.291 5.492)
        (xy -2.278 5.473)
        (xy -2.266 5.454)
        (xy -2.251 5.435)
        (xy -2.237 5.417)
        (xy -2.221 5.401)
        (xy -2.203 5.385)
        (xy -2.186 5.369)
        (xy -2.167 5.356)
        (xy -2.149 5.342)
        (xy -2.129 5.329)
        (xy -2.109 5.318)
        (xy -2.088 5.308)
        (xy -2.065 5.3)
        (xy -2.044 5.292)
        (xy -2.021 5.286)
        (xy -2 5.281)
        (xy -1.976 5.276)
        (xy -1.954 5.273)
        (xy -1.93 5.271)
        (xy -1.905 5.27)
        (xy -1.882 5.271)
        (xy -1.859 5.273)
        (xy -1.835 5.276)
        (xy -1.813 5.281)
        (xy -1.79 5.286)
        (xy -1.767 5.292)
        (xy -1.746 5.3)
        (xy -1.724 5.308)
        (xy -1.704 5.319)
        (xy -1.684 5.33)
        (xy -1.663 5.342)
        (xy -1.643 5.356)
        (xy -1.625 5.369)
        (xy -1.607 5.385)
        (xy -1.591 5.401)
        (xy -1.575 5.417)
        (xy -1.559 5.435)
        (xy -1.545 5.454)
        (xy -1.532 5.473)
        (xy -1.52 5.492)
        (xy -1.509 5.513)
        (xy -1.498 5.534)
        (xy -1.49 5.556)
        (xy -1.482 5.577)
        (xy -1.476 5.6)
        (xy -1.47 5.622)
        (xy -1.466 5.645)
        (xy -1.462 5.669)
        (xy -1.462 5.693)
        (xy -1.46 5.715)
        (xy -1.462 5.739)
        (xy -1.462 5.762)
        (xy -1.466 5.786)
        (xy -1.47 5.808)
        (xy -1.476 5.83)
        (xy -1.482 5.853)
        (xy -1.49 5.874)
        (xy -1.498 5.896)
        (xy -1.509 5.917)
        (xy -1.52 5.938)
        (xy -1.532 5.957)
        (xy -1.545 5.978)
        (xy -1.559 5.995)
        (xy -1.575 6.013)
        (xy -1.591 6.031)
        (xy -1.607 6.047)
        (xy -1.625 6.061)
        (xy -1.643 6.076)
        (xy -1.663 6.088)
        (xy -1.684 6.1)
        (xy -1.704 6.111)
        (xy -1.724 6.122)
        (xy -1.746 6.13)
        (xy -1.767 6.138)
        (xy -1.79 6.145)
        (xy -1.813 6.151)
        (xy -1.835 6.156)
        (xy -1.859 6.159)
        (xy -1.882 6.159)
        (xy -1.905 6.161)
        (xy -1.93 6.159)
        (xy -1.954 6.159)
        (xy -1.976 6.156)
        (xy -2 6.151)
        (xy -2.021 6.145)
        (xy -2.044 6.138)
        (xy -2.065 6.132)
        (xy -2.088 6.122)
        (xy -2.109 6.112)
        (xy -2.129 6.101)
        (xy -2.149 6.088)
        (xy -2.167 6.076)
        (xy -2.186 6.061)
        (xy -2.203 6.047)
        (xy -2.221 6.031)
        (xy -2.237 6.013)
        (xy -2.251 5.997)
        (xy -2.266 5.978)
        (xy -2.278 5.959)
        (xy -2.291 5.938)
        (xy -2.302 5.919)
        (xy -2.312 5.898)
        (xy -2.322 5.875)
        (xy -2.328 5.853)
        (xy -2.335 5.832)
        (xy -2.34 5.81)
        (xy -2.346 5.786)
        (xy -2.348 5.763)
        (xy -2.35 5.739)
        (xy -2.351 5.718)
        (xy -1.905 5.718)
        (xy -1.905 5.713)
      )

      (stroke (width 0.001) (type solid)) (fill solid) (layer "B.Paste"))
    (fp_poly
      (pts
        (xy -0.635 -5.717)
        (xy -1.081 -5.717)
        (xy -1.079 -5.738)
        (xy -1.079 -5.762)
        (xy -1.075 -5.785)
        (xy -1.071 -5.809)
        (xy -1.065 -5.831)
        (xy -1.059 -5.852)
        (xy -1.051 -5.874)
        (xy -1.043 -5.897)
        (xy -1.033 -5.918)
        (xy -1.021 -5.937)
        (xy -1.008 -5.958)
        (xy -0.995 -5.977)
        (xy -0.981 -5.996)
        (xy -0.966 -6.012)
        (xy -0.95 -6.03)
        (xy -0.934 -6.046)
        (xy -0.917 -6.06)
        (xy -0.898 -6.075)
        (xy -0.878 -6.087)
        (xy -0.858 -6.1)
        (xy -0.838 -6.111)
        (xy -0.817 -6.121)
        (xy -0.796 -6.131)
        (xy -0.774 -6.137)
        (xy -0.751 -6.144)
        (xy -0.729 -6.15)
        (xy -0.706 -6.155)
        (xy -0.684 -6.158)
        (xy -0.66 -6.158)
        (xy -0.635 -6.16)
        (xy -0.612 -6.158)
        (xy -0.588 -6.158)
        (xy -0.565 -6.155)
        (xy -0.543 -6.15)
        (xy -0.521 -6.144)
        (xy -0.497 -6.137)
        (xy -0.476 -6.129)
        (xy -0.455 -6.121)
        (xy -0.433 -6.11)
        (xy -0.413 -6.099)
        (xy -0.394 -6.087)
        (xy -0.373 -6.075)
        (xy -0.355 -6.06)
        (xy -0.338 -6.046)
        (xy -0.32 -6.03)
        (xy -0.304 -6.012)
        (xy -0.289 -5.994)
        (xy -0.276 -5.977)
        (xy -0.263 -5.956)
        (xy -0.25 -5.937)
        (xy -0.239 -5.916)
        (xy -0.229 -5.895)
        (xy -0.22 -5.873)
        (xy -0.212 -5.852)
        (xy -0.205 -5.829)
        (xy -0.201 -5.807)
        (xy -0.196 -5.785)
        (xy -0.192 -5.761)
        (xy -0.191 -5.738)
        (xy -0.19 -5.714)
        (xy -0.191 -5.692)
        (xy -0.192 -5.668)
        (xy -0.196 -5.644)
        (xy -0.201 -5.621)
        (xy -0.205 -5.599)
        (xy -0.212 -5.576)
        (xy -0.22 -5.555)
        (xy -0.229 -5.533)
        (xy -0.239 -5.512)
        (xy -0.25 -5.491)
        (xy -0.263 -5.472)
        (xy -0.276 -5.453)
        (xy -0.289 -5.434)
        (xy -0.304 -5.416)
        (xy -0.32 -5.4)
        (xy -0.338 -5.384)
        (xy -0.355 -5.368)
        (xy -0.373 -5.355)
        (xy -0.394 -5.341)
        (xy -0.413 -5.329)
        (xy -0.433 -5.318)
        (xy -0.455 -5.307)
        (xy -0.476 -5.299)
        (xy -0.497 -5.291)
        (xy -0.521 -5.285)
        (xy -0.543 -5.28)
        (xy -0.565 -5.275)
        (xy -0.588 -5.272)
        (xy -0.612 -5.27)
        (xy -0.635 -5.269)
        (xy -0.66 -5.27)
        (xy -0.684 -5.272)
        (xy -0.706 -5.275)
        (xy -0.729 -5.28)
        (xy -0.751 -5.285)
        (xy -0.774 -5.291)
        (xy -0.796 -5.299)
        (xy -0.817 -5.307)
        (xy -0.838 -5.317)
        (xy -0.858 -5.328)
        (xy -0.878 -5.341)
        (xy -0.898 -5.355)
        (xy -0.917 -5.368)
        (xy -0.934 -5.384)
        (xy -0.95 -5.4)
        (xy -0.966 -5.416)
        (xy -0.981 -5.434)
        (xy -0.995 -5.453)
        (xy -1.008 -5.472)
        (xy -1.021 -5.491)
        (xy -1.033 -5.511)
        (xy -1.043 -5.533)
        (xy -1.051 -5.554)
        (xy -1.059 -5.576)
        (xy -1.065 -5.599)
        (xy -1.071 -5.621)
        (xy -1.075 -5.644)
        (xy -1.079 -5.666)
        (xy -1.079 -5.69)
        (xy -1.081 -5.712)
        (xy -0.635 -5.712)
        (xy -0.635 -5.717)
      )

      (stroke (width 0.001) (type solid)) (fill solid) (layer "B.Paste"))
    (fp_poly
      (pts
        (xy -0.635 -3.177)
        (xy -1.081 -3.177)
        (xy -1.079 -3.198)
        (xy -1.079 -3.222)
        (xy -1.075 -3.245)
        (xy -1.071 -3.269)
        (xy -1.065 -3.29)
        (xy -1.059 -3.313)
        (xy -1.051 -3.334)
        (xy -1.043 -3.357)
        (xy -1.033 -3.378)
        (xy -1.021 -3.398)
        (xy -1.008 -3.418)
        (xy -0.995 -3.436)
        (xy -0.981 -3.455)
        (xy -0.966 -3.472)
        (xy -0.95 -3.49)
        (xy -0.934 -3.505)
        (xy -0.917 -3.52)
        (xy -0.898 -3.535)
        (xy -0.878 -3.547)
        (xy -0.858 -3.56)
        (xy -0.838 -3.571)
        (xy -0.817 -3.581)
        (xy -0.796 -3.591)
        (xy -0.774 -3.597)
        (xy -0.751 -3.604)
        (xy -0.729 -3.609)
        (xy -0.706 -3.615)
        (xy -0.684 -3.617)
        (xy -0.66 -3.619)
        (xy -0.635 -3.62)
        (xy -0.612 -3.619)
        (xy -0.588 -3.617)
        (xy -0.565 -3.615)
        (xy -0.543 -3.609)
        (xy -0.521 -3.604)
        (xy -0.497 -3.597)
        (xy -0.476 -3.589)
        (xy -0.455 -3.581)
        (xy -0.433 -3.571)
        (xy -0.413 -3.559)
        (xy -0.394 -3.547)
        (xy -0.373 -3.535)
        (xy -0.355 -3.52)
        (xy -0.338 -3.505)
        (xy -0.32 -3.49)
        (xy -0.304 -3.472)
        (xy -0.289 -3.454)
        (xy -0.276 -3.436)
        (xy -0.263 -3.416)
        (xy -0.25 -3.396)
        (xy -0.239 -3.376)
        (xy -0.229 -3.355)
        (xy -0.22 -3.334)
        (xy -0.212 -3.313)
        (xy -0.205 -3.289)
        (xy -0.201 -3.267)
        (xy -0.196 -3.245)
        (xy -0.192 -3.221)
        (xy -0.191 -3.197)
        (xy -0.19 -3.174)
        (xy -0.191 -3.152)
        (xy -0.192 -3.128)
        (xy -0.196 -3.104)
        (xy -0.201 -3.081)
        (xy -0.205 -3.059)
        (xy -0.212 -3.036)
        (xy -0.22 -3.015)
        (xy -0.229 -2.994)
        (xy -0.239 -2.972)
        (xy -0.25 -2.951)
        (xy -0.263 -2.932)
        (xy -0.276 -2.912)
        (xy -0.289 -2.894)
        (xy -0.304 -2.876)
        (xy -0.32 -2.859)
        (xy -0.338 -2.843)
        (xy -0.355 -2.829)
        (xy -0.373 -2.814)
        (xy -0.394 -2.801)
        (xy -0.412 -2.789)
        (xy -0.433 -2.778)
        (xy -0.455 -2.767)
        (xy -0.476 -2.759)
        (xy -0.497 -2.751)
        (xy -0.521 -2.745)
        (xy -0.543 -2.74)
        (xy -0.565 -2.734)
        (xy -0.588 -2.732)
        (xy -0.612 -2.73)
        (xy -0.635 -2.729)
        (xy -0.66 -2.73)
        (xy -0.684 -2.732)
        (xy -0.706 -2.734)
        (xy -0.729 -2.74)
        (xy -0.751 -2.745)
        (xy -0.774 -2.751)
        (xy -0.796 -2.758)
        (xy -0.817 -2.767)
        (xy -0.838 -2.777)
        (xy -0.858 -2.789)
        (xy -0.878 -2.801)
        (xy -0.898 -2.814)
        (xy -0.917 -2.829)
        (xy -0.934 -2.843)
        (xy -0.95 -2.859)
        (xy -0.966 -2.876)
        (xy -0.981 -2.894)
        (xy -0.995 -2.912)
        (xy -1.008 -2.931)
        (xy -1.021 -2.951)
        (xy -1.033 -2.971)
        (xy -1.043 -2.992)
        (xy -1.051 -3.015)
        (xy -1.059 -3.036)
        (xy -1.065 -3.059)
        (xy -1.071 -3.08)
        (xy -1.075 -3.104)
        (xy -1.079 -3.126)
        (xy -1.079 -3.15)
        (xy -1.081 -3.172)
        (xy -0.635 -3.172)
        (xy -0.635 -3.177)
      )

      (stroke (width 0.001) (type solid)) (fill solid) (layer "B.Paste"))
    (fp_poly
      (pts
        (xy -0.635 1.903)
        (xy -1.081 1.903)
        (xy -1.079 1.881)
        (xy -1.079 1.857)
        (xy -1.075 1.835)
        (xy -1.071 1.811)
        (xy -1.065 1.789)
        (xy -1.059 1.767)
        (xy -1.051 1.746)
        (xy -1.043 1.724)
        (xy -1.033 1.702)
        (xy -1.021 1.682)
        (xy -1.008 1.662)
        (xy -0.995 1.643)
        (xy -0.981 1.625)
        (xy -0.966 1.607)
        (xy -0.95 1.591)
        (xy -0.934 1.575)
        (xy -0.917 1.559)
        (xy -0.898 1.545)
        (xy -0.878 1.532)
        (xy -0.858 1.519)
        (xy -0.838 1.508)
        (xy -0.817 1.498)
        (xy -0.796 1.49)
        (xy -0.774 1.482)
        (xy -0.751 1.476)
        (xy -0.729 1.47)
        (xy -0.706 1.466)
        (xy -0.684 1.462)
        (xy -0.66 1.462)
        (xy -0.635 1.46)
        (xy -0.612 1.462)
        (xy -0.588 1.462)
        (xy -0.565 1.466)
        (xy -0.543 1.47)
        (xy -0.521 1.476)
        (xy -0.497 1.482)
        (xy -0.476 1.49)
        (xy -0.455 1.498)
        (xy -0.433 1.509)
        (xy -0.412 1.52)
        (xy -0.394 1.532)
        (xy -0.373 1.545)
        (xy -0.355 1.559)
        (xy -0.338 1.575)
        (xy -0.32 1.591)
        (xy -0.304 1.607)
        (xy -0.289 1.625)
        (xy -0.276 1.643)
        (xy -0.263 1.663)
        (xy -0.25 1.684)
        (xy -0.239 1.704)
        (xy -0.229 1.724)
        (xy -0.22 1.746)
        (xy -0.212 1.767)
        (xy -0.205 1.79)
        (xy -0.201 1.813)
        (xy -0.196 1.835)
        (xy -0.192 1.859)
        (xy -0.191 1.882)
        (xy -0.19 1.905)
        (xy -0.191 1.928)
        (xy -0.192 1.952)
        (xy -0.196 1.976)
        (xy -0.201 1.998)
        (xy -0.205 2.02)
        (xy -0.212 2.044)
        (xy -0.22 2.065)
        (xy -0.229 2.086)
        (xy -0.239 2.108)
        (xy -0.25 2.127)
        (xy -0.263 2.147)
        (xy -0.276 2.167)
        (xy -0.289 2.186)
        (xy -0.304 2.203)
        (xy -0.32 2.221)
        (xy -0.338 2.237)
        (xy -0.355 2.251)
        (xy -0.373 2.266)
        (xy -0.394 2.278)
        (xy -0.412 2.29)
        (xy -0.433 2.302)
        (xy -0.455 2.312)
        (xy -0.476 2.32)
        (xy -0.497 2.328)
        (xy -0.521 2.335)
        (xy -0.543 2.34)
        (xy -0.565 2.346)
        (xy -0.588 2.348)
        (xy -0.612 2.35)
        (xy -0.635 2.351)
        (xy -0.66 2.35)
        (xy -0.684 2.348)
        (xy -0.706 2.346)
        (xy -0.729 2.34)
        (xy -0.751 2.335)
        (xy -0.774 2.328)
        (xy -0.796 2.322)
        (xy -0.817 2.312)
        (xy -0.838 2.302)
        (xy -0.858 2.291)
        (xy -0.878 2.278)
        (xy -0.898 2.266)
        (xy -0.917 2.251)
        (xy -0.934 2.237)
        (xy -0.95 2.221)
        (xy -0.966 2.203)
        (xy -0.981 2.186)
        (xy -0.995 2.167)
        (xy -1.008 2.149)
        (xy -1.021 2.129)
        (xy -1.033 2.109)
        (xy -1.043 2.088)
        (xy -1.051 2.065)
        (xy -1.059 2.044)
        (xy -1.065 2.021)
        (xy -1.071 2)
        (xy -1.075 1.976)
        (xy -1.079 1.954)
        (xy -1.079 1.93)
        (xy -1.081 1.907)
        (xy -0.635 1.907)
        (xy -0.635 1.903)
      )

      (stroke (width 0.001) (type solid)) (fill solid) (layer "B.Paste"))
    (fp_poly
      (pts
        (xy -0.635 3.173)
        (xy -1.081 3.173)
        (xy -1.079 3.151)
        (xy -1.079 3.127)
        (xy -1.075 3.105)
        (xy -1.071 3.081)
        (xy -1.065 3.06)
        (xy -1.059 3.037)
        (xy -1.051 3.016)
        (xy -1.043 2.993)
        (xy -1.033 2.972)
        (xy -1.021 2.952)
        (xy -1.008 2.932)
        (xy -0.995 2.913)
        (xy -0.981 2.895)
        (xy -0.966 2.877)
        (xy -0.95 2.86)
        (xy -0.934 2.844)
        (xy -0.917 2.83)
        (xy -0.898 2.815)
        (xy -0.878 2.802)
        (xy -0.858 2.79)
        (xy -0.838 2.778)
        (xy -0.817 2.768)
        (xy -0.796 2.759)
        (xy -0.774 2.752)
        (xy -0.751 2.746)
        (xy -0.729 2.741)
        (xy -0.706 2.735)
        (xy -0.684 2.733)
        (xy -0.66 2.731)
        (xy -0.635 2.73)
        (xy -0.612 2.731)
        (xy -0.588 2.733)
        (xy -0.565 2.735)
        (xy -0.543 2.741)
        (xy -0.521 2.746)
        (xy -0.497 2.752)
        (xy -0.476 2.76)
        (xy -0.455 2.768)
        (xy -0.433 2.779)
        (xy -0.412 2.79)
        (xy -0.394 2.802)
        (xy -0.373 2.815)
        (xy -0.355 2.83)
        (xy -0.338 2.844)
        (xy -0.32 2.86)
        (xy -0.304 2.877)
        (xy -0.289 2.895)
        (xy -0.276 2.913)
        (xy -0.263 2.933)
        (xy -0.25 2.952)
        (xy -0.239 2.973)
        (xy -0.229 2.995)
        (xy -0.22 3.016)
        (xy -0.212 3.037)
        (xy -0.205 3.06)
        (xy -0.201 3.082)
        (xy -0.196 3.105)
        (xy -0.192 3.129)
        (xy -0.191 3.153)
        (xy -0.19 3.175)
        (xy -0.191 3.198)
        (xy -0.192 3.222)
        (xy -0.196 3.246)
        (xy -0.201 3.268)
        (xy -0.205 3.29)
        (xy -0.212 3.314)
        (xy -0.22 3.335)
        (xy -0.229 3.356)
        (xy -0.239 3.377)
        (xy -0.25 3.397)
        (xy -0.263 3.417)
        (xy -0.276 3.437)
        (xy -0.289 3.455)
        (xy -0.304 3.473)
        (xy -0.32 3.491)
        (xy -0.338 3.506)
        (xy -0.355 3.521)
        (xy -0.373 3.536)
        (xy -0.394 3.548)
        (xy -0.413 3.56)
        (xy -0.433 3.572)
        (xy -0.455 3.582)
        (xy -0.476 3.59)
        (xy -0.497 3.598)
        (xy -0.521 3.605)
        (xy -0.543 3.61)
        (xy -0.565 3.616)
        (xy -0.588 3.618)
        (xy -0.612 3.62)
        (xy -0.635 3.621)
        (xy -0.66 3.62)
        (xy -0.684 3.618)
        (xy -0.706 3.616)
        (xy -0.729 3.61)
        (xy -0.751 3.605)
        (xy -0.774 3.598)
        (xy -0.796 3.592)
        (xy -0.817 3.582)
        (xy -0.838 3.572)
        (xy -0.858 3.561)
        (xy -0.878 3.548)
        (xy -0.898 3.536)
        (xy -0.917 3.521)
        (xy -0.934 3.506)
        (xy -0.95 3.491)
        (xy -0.966 3.473)
        (xy -0.981 3.456)
        (xy -0.995 3.437)
        (xy -1.008 3.419)
        (xy -1.021 3.399)
        (xy -1.033 3.379)
        (xy -1.043 3.358)
        (xy -1.051 3.335)
        (xy -1.059 3.314)
        (xy -1.065 3.291)
        (xy -1.071 3.27)
        (xy -1.075 3.246)
        (xy -1.079 3.223)
        (xy -1.079 3.199)
        (xy -1.081 3.178)
        (xy -0.635 3.178)
        (xy -0.635 3.173)
      )

      (stroke (width 0.001) (type solid)) (fill solid) (layer "B.Paste"))
    (fp_poly
      (pts
        (xy -0.635 4.443)
        (xy -1.081 4.443)
        (xy -1.079 4.422)
        (xy -1.079 4.398)
        (xy -1.075 4.374)
        (xy -1.071 4.351)
        (xy -1.065 4.329)
        (xy -1.059 4.308)
        (xy -1.051 4.286)
        (xy -1.043 4.263)
        (xy -1.033 4.242)
        (xy -1.021 4.223)
        (xy -1.008 4.202)
        (xy -0.995 4.183)
        (xy -0.981 4.164)
        (xy -0.966 4.148)
        (xy -0.95 4.13)
        (xy -0.934 4.114)
        (xy -0.917 4.1)
        (xy -0.898 4.085)
        (xy -0.878 4.072)
        (xy -0.858 4.06)
        (xy -0.838 4.048)
        (xy -0.817 4.039)
        (xy -0.796 4.029)
        (xy -0.774 4.023)
        (xy -0.751 4.015)
        (xy -0.729 4.01)
        (xy -0.706 4.005)
        (xy -0.684 4.002)
        (xy -0.66 4.002)
        (xy -0.635 4)
        (xy -0.612 4.002)
        (xy -0.588 4.002)
        (xy -0.565 4.005)
        (xy -0.543 4.01)
        (xy -0.521 4.015)
        (xy -0.497 4.023)
        (xy -0.476 4.031)
        (xy -0.455 4.039)
        (xy -0.433 4.05)
        (xy -0.413 4.06)
        (xy -0.394 4.072)
        (xy -0.373 4.085)
        (xy -0.355 4.1)
        (xy -0.338 4.114)
        (xy -0.32 4.13)
        (xy -0.304 4.148)
        (xy -0.289 4.165)
        (xy -0.276 4.183)
        (xy -0.263 4.204)
        (xy -0.25 4.223)
        (xy -0.239 4.244)
        (xy -0.229 4.265)
        (xy -0.22 4.286)
        (xy -0.212 4.308)
        (xy -0.205 4.33)
        (xy -0.201 4.353)
        (xy -0.196 4.375)
        (xy -0.192 4.398)
        (xy -0.191 4.422)
        (xy -0.19 4.446)
        (xy -0.191 4.468)
        (xy -0.192 4.492)
        (xy -0.196 4.515)
        (xy -0.201 4.539)
        (xy -0.205 4.56)
        (xy -0.212 4.584)
        (xy -0.22 4.604)
        (xy -0.229 4.627)
        (xy -0.239 4.648)
        (xy -0.25 4.669)
        (xy -0.263 4.688)
        (xy -0.276 4.707)
        (xy -0.289 4.725)
        (xy -0.304 4.744)
        (xy -0.32 4.76)
        (xy -0.338 4.776)
        (xy -0.355 4.792)
        (xy -0.373 4.805)
        (xy -0.394 4.818)
        (xy -0.412 4.83)
        (xy -0.433 4.842)
        (xy -0.455 4.853)
        (xy -0.476 4.861)
        (xy -0.497 4.869)
        (xy -0.521 4.875)
        (xy -0.543 4.88)
        (xy -0.565 4.885)
        (xy -0.588 4.888)
        (xy -0.612 4.89)
        (xy -0.635 4.89)
        (xy -0.66 4.89)
        (xy -0.684 4.888)
        (xy -0.706 4.885)
        (xy -0.729 4.88)
        (xy -0.751 4.875)
        (xy -0.774 4.869)
        (xy -0.796 4.861)
        (xy -0.817 4.853)
        (xy -0.838 4.842)
        (xy -0.858 4.832)
        (xy -0.878 4.818)
        (xy -0.898 4.805)
        (xy -0.917 4.792)
        (xy -0.934 4.776)
        (xy -0.95 4.76)
        (xy -0.966 4.744)
        (xy -0.981 4.726)
        (xy -0.995 4.707)
        (xy -1.008 4.688)
        (xy -1.021 4.669)
        (xy -1.033 4.648)
        (xy -1.043 4.627)
        (xy -1.051 4.606)
        (xy -1.059 4.584)
        (xy -1.065 4.561)
        (xy -1.071 4.539)
        (xy -1.075 4.516)
        (xy -1.079 4.494)
        (xy -1.079 4.47)
        (xy -1.081 4.447)
        (xy -0.635 4.447)
        (xy -0.635 4.443)
      )

      (stroke (width 0.001) (type solid)) (fill solid) (layer "B.Paste"))
    (fp_poly
      (pts
        (xy -0.635 5.713)
        (xy -1.081 5.713)
        (xy -1.079 5.691)
        (xy -1.079 5.667)
        (xy -1.075 5.645)
        (xy -1.071 5.622)
        (xy -1.065 5.6)
        (xy -1.059 5.577)
        (xy -1.051 5.555)
        (xy -1.043 5.534)
        (xy -1.033 5.512)
        (xy -1.021 5.492)
        (xy -1.008 5.473)
        (xy -0.995 5.454)
        (xy -0.981 5.435)
        (xy -0.966 5.417)
        (xy -0.95 5.401)
        (xy -0.934 5.385)
        (xy -0.917 5.369)
        (xy -0.898 5.356)
        (xy -0.878 5.342)
        (xy -0.858 5.329)
        (xy -0.838 5.318)
        (xy -0.817 5.308)
        (xy -0.796 5.3)
        (xy -0.774 5.292)
        (xy -0.751 5.286)
        (xy -0.729 5.281)
        (xy -0.706 5.276)
        (xy -0.684 5.273)
        (xy -0.66 5.271)
        (xy -0.635 5.27)
        (xy -0.612 5.271)
        (xy -0.588 5.273)
        (xy -0.565 5.276)
        (xy -0.543 5.281)
        (xy -0.521 5.286)
        (xy -0.497 5.292)
        (xy -0.476 5.3)
        (xy -0.455 5.308)
        (xy -0.433 5.319)
        (xy -0.413 5.33)
        (xy -0.394 5.342)
        (xy -0.373 5.356)
        (xy -0.355 5.369)
        (xy -0.338 5.385)
        (xy -0.32 5.401)
        (xy -0.304 5.417)
        (xy -0.289 5.435)
        (xy -0.276 5.454)
        (xy -0.263 5.473)
        (xy -0.25 5.492)
        (xy -0.239 5.513)
        (xy -0.229 5.534)
        (xy -0.22 5.556)
        (xy -0.212 5.577)
        (xy -0.205 5.6)
        (xy -0.201 5.622)
        (xy -0.196 5.645)
        (xy -0.192 5.669)
        (xy -0.191 5.693)
        (xy -0.19 5.715)
        (xy -0.191 5.739)
        (xy -0.192 5.762)
        (xy -0.196 5.786)
        (xy -0.201 5.808)
        (xy -0.205 5.83)
        (xy -0.212 5.853)
        (xy -0.22 5.874)
        (xy -0.229 5.896)
        (xy -0.239 5.917)
        (xy -0.25 5.938)
        (xy -0.263 5.957)
        (xy -0.276 5.978)
        (xy -0.289 5.995)
        (xy -0.304 6.013)
        (xy -0.32 6.031)
        (xy -0.338 6.047)
        (xy -0.355 6.061)
        (xy -0.373 6.076)
        (xy -0.394 6.088)
        (xy -0.413 6.1)
        (xy -0.433 6.111)
        (xy -0.455 6.122)
        (xy -0.476 6.13)
        (xy -0.497 6.138)
        (xy -0.521 6.145)
        (xy -0.543 6.151)
        (xy -0.565 6.156)
        (xy -0.588 6.159)
        (xy -0.612 6.159)
        (xy -0.635 6.161)
        (xy -0.66 6.159)
        (xy -0.684 6.159)
        (xy -0.706 6.156)
        (xy -0.729 6.151)
        (xy -0.751 6.145)
        (xy -0.774 6.138)
        (xy -0.796 6.132)
        (xy -0.817 6.122)
        (xy -0.838 6.112)
        (xy -0.858 6.101)
        (xy -0.878 6.088)
        (xy -0.898 6.076)
        (xy -0.917 6.061)
        (xy -0.934 6.047)
        (xy -0.95 6.031)
        (xy -0.966 6.013)
        (xy -0.981 5.997)
        (xy -0.995 5.978)
        (xy -1.008 5.959)
        (xy -1.021 5.938)
        (xy -1.033 5.919)
        (xy -1.043 5.898)
        (xy -1.051 5.875)
        (xy -1.059 5.853)
        (xy -1.065 5.832)
        (xy -1.071 5.81)
        (xy -1.075 5.786)
        (xy -1.079 5.763)
        (xy -1.079 5.739)
        (xy -1.081 5.718)
        (xy -0.635 5.718)
        (xy -0.635 5.713)
      )

      (stroke (width 0.001) (type solid)) (fill solid) (layer "B.Paste"))
    (fp_poly
      (pts
        (xy 0.634 -5.717)
        (xy 0.189 -5.717)
        (xy 0.19 -5.738)
        (xy 0.192 -5.762)
        (xy 0.195 -5.785)
        (xy 0.2 -5.809)
        (xy 0.204 -5.831)
        (xy 0.211 -5.852)
        (xy 0.218 -5.874)
        (xy 0.228 -5.897)
        (xy 0.237 -5.918)
        (xy 0.248 -5.937)
        (xy 0.262 -5.958)
        (xy 0.275 -5.977)
        (xy 0.288 -5.996)
        (xy 0.303 -6.012)
        (xy 0.32 -6.03)
        (xy 0.337 -6.046)
        (xy 0.353 -6.06)
        (xy 0.372 -6.075)
        (xy 0.392 -6.087)
        (xy 0.411 -6.1)
        (xy 0.431 -6.111)
        (xy 0.453 -6.121)
        (xy 0.474 -6.131)
        (xy 0.496 -6.137)
        (xy 0.519 -6.144)
        (xy 0.541 -6.15)
        (xy 0.563 -6.155)
        (xy 0.586 -6.158)
        (xy 0.61 -6.158)
        (xy 0.634 -6.16)
        (xy 0.658 -6.158)
        (xy 0.682 -6.158)
        (xy 0.704 -6.155)
        (xy 0.727 -6.15)
        (xy 0.749 -6.144)
        (xy 0.773 -6.137)
        (xy 0.794 -6.129)
        (xy 0.815 -6.121)
        (xy 0.836 -6.11)
        (xy 0.856 -6.099)
        (xy 0.876 -6.087)
        (xy 0.897 -6.075)
        (xy 0.915 -6.06)
        (xy 0.933 -6.046)
        (xy 0.949 -6.03)
        (xy 0.965 -6.012)
        (xy 0.98 -5.994)
        (xy 0.994 -5.977)
        (xy 1.007 -5.956)
        (xy 1.019 -5.937)
        (xy 1.03 -5.916)
        (xy 1.042 -5.895)
        (xy 1.05 -5.873)
        (xy 1.058 -5.852)
        (xy 1.064 -5.829)
        (xy 1.07 -5.807)
        (xy 1.074 -5.785)
        (xy 1.078 -5.761)
        (xy 1.078 -5.738)
        (xy 1.08 -5.714)
        (xy 1.078 -5.692)
        (xy 1.078 -5.668)
        (xy 1.074 -5.644)
        (xy 1.07 -5.621)
        (xy 1.064 -5.599)
        (xy 1.058 -5.576)
        (xy 1.05 -5.555)
        (xy 1.042 -5.533)
        (xy 1.03 -5.512)
        (xy 1.019 -5.491)
        (xy 1.007 -5.472)
        (xy 0.994 -5.453)
        (xy 0.98 -5.434)
        (xy 0.965 -5.416)
        (xy 0.949 -5.4)
        (xy 0.933 -5.384)
        (xy 0.915 -5.368)
        (xy 0.897 -5.355)
        (xy 0.876 -5.341)
        (xy 0.856 -5.329)
        (xy 0.836 -5.318)
        (xy 0.815 -5.307)
        (xy 0.794 -5.299)
        (xy 0.773 -5.291)
        (xy 0.749 -5.285)
        (xy 0.727 -5.28)
        (xy 0.704 -5.275)
        (xy 0.682 -5.272)
        (xy 0.658 -5.27)
        (xy 0.634 -5.269)
        (xy 0.61 -5.27)
        (xy 0.586 -5.272)
        (xy 0.563 -5.275)
        (xy 0.541 -5.28)
        (xy 0.519 -5.285)
        (xy 0.496 -5.291)
        (xy 0.474 -5.299)
        (xy 0.453 -5.307)
        (xy 0.431 -5.317)
        (xy 0.411 -5.328)
        (xy 0.392 -5.341)
        (xy 0.372 -5.355)
        (xy 0.353 -5.368)
        (xy 0.337 -5.384)
        (xy 0.32 -5.4)
        (xy 0.303 -5.416)
        (xy 0.288 -5.434)
        (xy 0.275 -5.453)
        (xy 0.262 -5.472)
        (xy 0.248 -5.491)
        (xy 0.237 -5.511)
        (xy 0.228 -5.533)
        (xy 0.218 -5.554)
        (xy 0.211 -5.576)
        (xy 0.204 -5.599)
        (xy 0.2 -5.621)
        (xy 0.195 -5.644)
        (xy 0.192 -5.666)
        (xy 0.19 -5.69)
        (xy 0.189 -5.712)
        (xy 0.634 -5.712)
        (xy 0.634 -5.717)
      )

      (stroke (width 0.001) (type solid)) (fill solid) (layer "B.Paste"))
    (fp_poly
      (pts
        (xy 0.634 -3.177)
        (xy 0.189 -3.177)
        (xy 0.19 -3.198)
        (xy 0.192 -3.222)
        (xy 0.195 -3.245)
        (xy 0.2 -3.269)
        (xy 0.204 -3.29)
        (xy 0.211 -3.313)
        (xy 0.218 -3.334)
        (xy 0.228 -3.357)
        (xy 0.237 -3.378)
        (xy 0.248 -3.398)
        (xy 0.262 -3.418)
        (xy 0.275 -3.436)
        (xy 0.288 -3.455)
        (xy 0.303 -3.472)
        (xy 0.32 -3.49)
        (xy 0.337 -3.505)
        (xy 0.353 -3.52)
        (xy 0.372 -3.535)
        (xy 0.392 -3.547)
        (xy 0.411 -3.56)
        (xy 0.431 -3.571)
        (xy 0.453 -3.581)
        (xy 0.474 -3.591)
        (xy 0.496 -3.597)
        (xy 0.519 -3.604)
        (xy 0.541 -3.609)
        (xy 0.563 -3.615)
        (xy 0.586 -3.617)
        (xy 0.61 -3.619)
        (xy 0.634 -3.62)
        (xy 0.658 -3.619)
        (xy 0.682 -3.617)
        (xy 0.704 -3.615)
        (xy 0.727 -3.609)
        (xy 0.749 -3.604)
        (xy 0.773 -3.597)
        (xy 0.794 -3.589)
        (xy 0.815 -3.581)
        (xy 0.836 -3.571)
        (xy 0.856 -3.559)
        (xy 0.876 -3.547)
        (xy 0.897 -3.535)
        (xy 0.915 -3.52)
        (xy 0.933 -3.505)
        (xy 0.949 -3.49)
        (xy 0.965 -3.472)
        (xy 0.98 -3.454)
        (xy 0.994 -3.436)
        (xy 1.007 -3.416)
        (xy 1.019 -3.396)
        (xy 1.03 -3.376)
        (xy 1.042 -3.355)
        (xy 1.05 -3.334)
        (xy 1.058 -3.313)
        (xy 1.064 -3.289)
        (xy 1.07 -3.267)
        (xy 1.074 -3.245)
        (xy 1.078 -3.221)
        (xy 1.078 -3.197)
        (xy 1.08 -3.174)
        (xy 1.078 -3.152)
        (xy 1.078 -3.128)
        (xy 1.074 -3.104)
        (xy 1.07 -3.081)
        (xy 1.064 -3.059)
        (xy 1.058 -3.036)
        (xy 1.05 -3.015)
        (xy 1.042 -2.994)
        (xy 1.03 -2.972)
        (xy 1.019 -2.951)
        (xy 1.007 -2.932)
        (xy 0.994 -2.912)
        (xy 0.98 -2.894)
        (xy 0.965 -2.876)
        (xy 0.949 -2.859)
        (xy 0.933 -2.843)
        (xy 0.915 -2.829)
        (xy 0.897 -2.814)
        (xy 0.876 -2.801)
        (xy 0.857 -2.789)
        (xy 0.836 -2.778)
        (xy 0.815 -2.767)
        (xy 0.794 -2.759)
        (xy 0.773 -2.751)
        (xy 0.749 -2.745)
        (xy 0.727 -2.74)
        (xy 0.704 -2.734)
        (xy 0.682 -2.732)
        (xy 0.658 -2.73)
        (xy 0.634 -2.729)
        (xy 0.61 -2.73)
        (xy 0.586 -2.732)
        (xy 0.563 -2.734)
        (xy 0.541 -2.74)
        (xy 0.519 -2.745)
        (xy 0.496 -2.751)
        (xy 0.474 -2.758)
        (xy 0.453 -2.767)
        (xy 0.431 -2.777)
        (xy 0.411 -2.789)
        (xy 0.392 -2.801)
        (xy 0.372 -2.814)
        (xy 0.353 -2.829)
        (xy 0.337 -2.843)
        (xy 0.32 -2.859)
        (xy 0.303 -2.876)
        (xy 0.288 -2.894)
        (xy 0.275 -2.912)
        (xy 0.262 -2.931)
        (xy 0.248 -2.951)
        (xy 0.237 -2.971)
        (xy 0.228 -2.992)
        (xy 0.218 -3.015)
        (xy 0.211 -3.036)
        (xy 0.204 -3.059)
        (xy 0.2 -3.08)
        (xy 0.195 -3.104)
        (xy 0.192 -3.126)
        (xy 0.19 -3.15)
        (xy 0.189 -3.172)
        (xy 0.634 -3.172)
        (xy 0.634 -3.177)
      )

      (stroke (width 0.001) (type solid)) (fill solid) (layer "B.Paste"))
    (fp_poly
      (pts
        (xy 0.634 1.903)
        (xy 0.189 1.903)
        (xy 0.19 1.881)
        (xy 0.192 1.857)
        (xy 0.195 1.835)
        (xy 0.2 1.811)
        (xy 0.204 1.789)
        (xy 0.211 1.767)
        (xy 0.218 1.746)
        (xy 0.228 1.724)
        (xy 0.237 1.702)
        (xy 0.248 1.682)
        (xy 0.262 1.662)
        (xy 0.275 1.643)
        (xy 0.288 1.625)
        (xy 0.303 1.607)
        (xy 0.32 1.591)
        (xy 0.337 1.575)
        (xy 0.353 1.559)
        (xy 0.372 1.545)
        (xy 0.392 1.532)
        (xy 0.411 1.519)
        (xy 0.431 1.508)
        (xy 0.453 1.498)
        (xy 0.474 1.49)
        (xy 0.496 1.482)
        (xy 0.519 1.476)
        (xy 0.541 1.47)
        (xy 0.563 1.466)
        (xy 0.586 1.462)
        (xy 0.61 1.462)
        (xy 0.634 1.46)
        (xy 0.658 1.462)
        (xy 0.682 1.462)
        (xy 0.704 1.466)
        (xy 0.727 1.47)
        (xy 0.749 1.476)
        (xy 0.773 1.482)
        (xy 0.794 1.49)
        (xy 0.815 1.498)
        (xy 0.836 1.509)
        (xy 0.857 1.52)
        (xy 0.876 1.532)
        (xy 0.897 1.545)
        (xy 0.915 1.559)
        (xy 0.933 1.575)
        (xy 0.949 1.591)
        (xy 0.965 1.607)
        (xy 0.98 1.625)
        (xy 0.994 1.643)
        (xy 1.007 1.663)
        (xy 1.019 1.684)
        (xy 1.03 1.704)
        (xy 1.042 1.724)
        (xy 1.05 1.746)
        (xy 1.058 1.767)
        (xy 1.064 1.79)
        (xy 1.07 1.813)
        (xy 1.074 1.835)
        (xy 1.078 1.859)
        (xy 1.078 1.882)
        (xy 1.08 1.905)
        (xy 1.078 1.928)
        (xy 1.078 1.952)
        (xy 1.074 1.976)
        (xy 1.07 1.998)
        (xy 1.064 2.02)
        (xy 1.058 2.044)
        (xy 1.05 2.065)
        (xy 1.042 2.086)
        (xy 1.03 2.108)
        (xy 1.019 2.127)
        (xy 1.007 2.147)
        (xy 0.994 2.167)
        (xy 0.98 2.186)
        (xy 0.965 2.203)
        (xy 0.949 2.221)
        (xy 0.933 2.237)
        (xy 0.915 2.251)
        (xy 0.897 2.266)
        (xy 0.876 2.278)
        (xy 0.857 2.29)
        (xy 0.836 2.302)
        (xy 0.815 2.312)
        (xy 0.794 2.32)
        (xy 0.773 2.328)
        (xy 0.749 2.335)
        (xy 0.727 2.34)
        (xy 0.704 2.346)
        (xy 0.682 2.348)
        (xy 0.658 2.35)
        (xy 0.634 2.351)
        (xy 0.61 2.35)
        (xy 0.586 2.348)
        (xy 0.563 2.346)
        (xy 0.541 2.34)
        (xy 0.519 2.335)
        (xy 0.496 2.328)
        (xy 0.474 2.322)
        (xy 0.453 2.312)
        (xy 0.431 2.302)
        (xy 0.411 2.291)
        (xy 0.392 2.278)
        (xy 0.372 2.266)
        (xy 0.353 2.251)
        (xy 0.337 2.237)
        (xy 0.32 2.221)
        (xy 0.303 2.203)
        (xy 0.288 2.186)
        (xy 0.275 2.167)
        (xy 0.262 2.149)
        (xy 0.248 2.129)
        (xy 0.237 2.109)
        (xy 0.228 2.088)
        (xy 0.218 2.065)
        (xy 0.211 2.044)
        (xy 0.204 2.021)
        (xy 0.2 2)
        (xy 0.195 1.976)
        (xy 0.192 1.954)
        (xy 0.19 1.93)
        (xy 0.189 1.907)
        (xy 0.634 1.907)
        (xy 0.634 1.903)
      )

      (stroke (width 0.001) (type solid)) (fill solid) (layer "B.Paste"))
    (fp_poly
      (pts
        (xy 0.634 3.173)
        (xy 0.189 3.173)
        (xy 0.19 3.151)
        (xy 0.192 3.127)
        (xy 0.195 3.105)
        (xy 0.2 3.081)
        (xy 0.204 3.06)
        (xy 0.211 3.037)
        (xy 0.218 3.016)
        (xy 0.228 2.993)
        (xy 0.237 2.972)
        (xy 0.248 2.952)
        (xy 0.262 2.932)
        (xy 0.275 2.913)
        (xy 0.288 2.895)
        (xy 0.303 2.877)
        (xy 0.32 2.86)
        (xy 0.337 2.844)
        (xy 0.353 2.83)
        (xy 0.372 2.815)
        (xy 0.392 2.802)
        (xy 0.411 2.79)
        (xy 0.431 2.778)
        (xy 0.453 2.768)
        (xy 0.474 2.759)
        (xy 0.496 2.752)
        (xy 0.519 2.746)
        (xy 0.541 2.741)
        (xy 0.563 2.735)
        (xy 0.586 2.733)
        (xy 0.61 2.731)
        (xy 0.634 2.73)
        (xy 0.658 2.731)
        (xy 0.682 2.733)
        (xy 0.704 2.735)
        (xy 0.727 2.741)
        (xy 0.749 2.746)
        (xy 0.773 2.752)
        (xy 0.794 2.76)
        (xy 0.815 2.768)
        (xy 0.836 2.779)
        (xy 0.857 2.79)
        (xy 0.876 2.802)
        (xy 0.897 2.815)
        (xy 0.915 2.83)
        (xy 0.933 2.844)
        (xy 0.949 2.86)
        (xy 0.965 2.877)
        (xy 0.98 2.895)
        (xy 0.994 2.913)
        (xy 1.007 2.933)
        (xy 1.019 2.952)
        (xy 1.03 2.973)
        (xy 1.042 2.995)
        (xy 1.05 3.016)
        (xy 1.058 3.037)
        (xy 1.064 3.06)
        (xy 1.07 3.082)
        (xy 1.074 3.105)
        (xy 1.078 3.129)
        (xy 1.078 3.153)
        (xy 1.08 3.175)
        (xy 1.078 3.198)
        (xy 1.078 3.222)
        (xy 1.074 3.246)
        (xy 1.07 3.268)
        (xy 1.064 3.29)
        (xy 1.058 3.314)
        (xy 1.05 3.335)
        (xy 1.042 3.356)
        (xy 1.03 3.377)
        (xy 1.019 3.397)
        (xy 1.007 3.417)
        (xy 0.994 3.437)
        (xy 0.98 3.455)
        (xy 0.965 3.473)
        (xy 0.949 3.491)
        (xy 0.933 3.506)
        (xy 0.915 3.521)
        (xy 0.897 3.536)
        (xy 0.876 3.548)
        (xy 0.856 3.56)
        (xy 0.836 3.572)
        (xy 0.815 3.582)
        (xy 0.794 3.59)
        (xy 0.773 3.598)
        (xy 0.749 3.605)
        (xy 0.727 3.61)
        (xy 0.704 3.616)
        (xy 0.682 3.618)
        (xy 0.658 3.62)
        (xy 0.634 3.621)
        (xy 0.61 3.62)
        (xy 0.586 3.618)
        (xy 0.563 3.616)
        (xy 0.541 3.61)
        (xy 0.519 3.605)
        (xy 0.496 3.598)
        (xy 0.474 3.592)
        (xy 0.453 3.582)
        (xy 0.431 3.572)
        (xy 0.411 3.561)
        (xy 0.392 3.548)
        (xy 0.372 3.536)
        (xy 0.353 3.521)
        (xy 0.337 3.506)
        (xy 0.32 3.491)
        (xy 0.303 3.473)
        (xy 0.288 3.456)
        (xy 0.275 3.437)
        (xy 0.262 3.419)
        (xy 0.248 3.399)
        (xy 0.237 3.379)
        (xy 0.228 3.358)
        (xy 0.218 3.335)
        (xy 0.211 3.314)
        (xy 0.204 3.291)
        (xy 0.2 3.27)
        (xy 0.195 3.246)
        (xy 0.192 3.223)
        (xy 0.19 3.199)
        (xy 0.189 3.178)
        (xy 0.634 3.178)
        (xy 0.634 3.173)
      )

      (stroke (width 0.001) (type solid)) (fill solid) (layer "B.Paste"))
    (fp_poly
      (pts
        (xy 0.634 4.443)
        (xy 0.189 4.443)
        (xy 0.19 4.422)
        (xy 0.192 4.398)
        (xy 0.195 4.374)
        (xy 0.2 4.351)
        (xy 0.204 4.329)
        (xy 0.211 4.308)
        (xy 0.218 4.286)
        (xy 0.228 4.263)
        (xy 0.237 4.242)
        (xy 0.248 4.223)
        (xy 0.262 4.202)
        (xy 0.275 4.183)
        (xy 0.288 4.164)
        (xy 0.303 4.148)
        (xy 0.32 4.13)
        (xy 0.337 4.114)
        (xy 0.353 4.1)
        (xy 0.372 4.085)
        (xy 0.392 4.072)
        (xy 0.411 4.06)
        (xy 0.431 4.048)
        (xy 0.453 4.039)
        (xy 0.474 4.029)
        (xy 0.496 4.023)
        (xy 0.519 4.015)
        (xy 0.541 4.01)
        (xy 0.563 4.005)
        (xy 0.586 4.002)
        (xy 0.61 4.002)
        (xy 0.634 4)
        (xy 0.658 4.002)
        (xy 0.682 4.002)
        (xy 0.704 4.005)
        (xy 0.727 4.01)
        (xy 0.749 4.015)
        (xy 0.773 4.023)
        (xy 0.794 4.031)
        (xy 0.815 4.039)
        (xy 0.836 4.05)
        (xy 0.856 4.06)
        (xy 0.876 4.072)
        (xy 0.897 4.085)
        (xy 0.915 4.1)
        (xy 0.933 4.114)
        (xy 0.949 4.13)
        (xy 0.965 4.148)
        (xy 0.98 4.165)
        (xy 0.994 4.183)
        (xy 1.007 4.204)
        (xy 1.019 4.223)
        (xy 1.03 4.244)
        (xy 1.042 4.265)
        (xy 1.05 4.286)
        (xy 1.058 4.308)
        (xy 1.064 4.33)
        (xy 1.07 4.353)
        (xy 1.074 4.375)
        (xy 1.078 4.398)
        (xy 1.078 4.422)
        (xy 1.08 4.446)
        (xy 1.078 4.468)
        (xy 1.078 4.492)
        (xy 1.074 4.515)
        (xy 1.07 4.539)
        (xy 1.064 4.56)
        (xy 1.058 4.584)
        (xy 1.05 4.604)
        (xy 1.042 4.627)
        (xy 1.03 4.648)
        (xy 1.019 4.669)
        (xy 1.007 4.688)
        (xy 0.994 4.707)
        (xy 0.98 4.725)
        (xy 0.965 4.744)
        (xy 0.949 4.76)
        (xy 0.933 4.776)
        (xy 0.915 4.792)
        (xy 0.897 4.805)
        (xy 0.876 4.818)
        (xy 0.857 4.83)
        (xy 0.836 4.842)
        (xy 0.815 4.853)
        (xy 0.794 4.861)
        (xy 0.773 4.869)
        (xy 0.749 4.875)
        (xy 0.727 4.88)
        (xy 0.704 4.885)
        (xy 0.682 4.888)
        (xy 0.658 4.89)
        (xy 0.634 4.89)
        (xy 0.61 4.89)
        (xy 0.586 4.888)
        (xy 0.563 4.885)
        (xy 0.541 4.88)
        (xy 0.519 4.875)
        (xy 0.496 4.869)
        (xy 0.474 4.861)
        (xy 0.453 4.853)
        (xy 0.431 4.842)
        (xy 0.411 4.832)
        (xy 0.392 4.818)
        (xy 0.372 4.805)
        (xy 0.353 4.792)
        (xy 0.337 4.776)
        (xy 0.32 4.76)
        (xy 0.303 4.744)
        (xy 0.288 4.726)
        (xy 0.275 4.707)
        (xy 0.262 4.688)
        (xy 0.248 4.669)
        (xy 0.237 4.648)
        (xy 0.228 4.627)
        (xy 0.218 4.606)
        (xy 0.211 4.584)
        (xy 0.204 4.561)
        (xy 0.2 4.539)
        (xy 0.195 4.516)
        (xy 0.192 4.494)
        (xy 0.19 4.47)
        (xy 0.189 4.447)
        (xy 0.634 4.447)
        (xy 0.634 4.443)
      )

      (stroke (width 0.001) (type solid)) (fill solid) (layer "B.Paste"))
    (fp_poly
      (pts
        (xy 0.634 5.713)
        (xy 0.189 5.713)
        (xy 0.19 5.691)
        (xy 0.192 5.667)
        (xy 0.195 5.645)
        (xy 0.2 5.622)
        (xy 0.204 5.6)
        (xy 0.211 5.577)
        (xy 0.218 5.555)
        (xy 0.228 5.534)
        (xy 0.237 5.512)
        (xy 0.248 5.492)
        (xy 0.262 5.473)
        (xy 0.275 5.454)
        (xy 0.288 5.435)
        (xy 0.303 5.417)
        (xy 0.32 5.401)
        (xy 0.337 5.385)
        (xy 0.353 5.369)
        (xy 0.372 5.356)
        (xy 0.392 5.342)
        (xy 0.411 5.329)
        (xy 0.431 5.318)
        (xy 0.453 5.308)
        (xy 0.474 5.3)
        (xy 0.496 5.292)
        (xy 0.519 5.286)
        (xy 0.541 5.281)
        (xy 0.563 5.276)
        (xy 0.586 5.273)
        (xy 0.61 5.271)
        (xy 0.634 5.27)
        (xy 0.658 5.271)
        (xy 0.682 5.273)
        (xy 0.704 5.276)
        (xy 0.727 5.281)
        (xy 0.749 5.286)
        (xy 0.773 5.292)
        (xy 0.794 5.3)
        (xy 0.815 5.308)
        (xy 0.836 5.319)
        (xy 0.856 5.33)
        (xy 0.876 5.342)
        (xy 0.897 5.356)
        (xy 0.915 5.369)
        (xy 0.933 5.385)
        (xy 0.949 5.401)
        (xy 0.965 5.417)
        (xy 0.98 5.435)
        (xy 0.994 5.454)
        (xy 1.007 5.473)
        (xy 1.019 5.492)
        (xy 1.03 5.513)
        (xy 1.042 5.534)
        (xy 1.05 5.556)
        (xy 1.058 5.577)
        (xy 1.064 5.6)
        (xy 1.07 5.622)
        (xy 1.074 5.645)
        (xy 1.078 5.669)
        (xy 1.078 5.693)
        (xy 1.08 5.715)
        (xy 1.078 5.739)
        (xy 1.078 5.762)
        (xy 1.074 5.786)
        (xy 1.07 5.808)
        (xy 1.064 5.83)
        (xy 1.058 5.853)
        (xy 1.05 5.874)
        (xy 1.042 5.896)
        (xy 1.03 5.917)
        (xy 1.019 5.938)
        (xy 1.007 5.957)
        (xy 0.994 5.978)
        (xy 0.98 5.995)
        (xy 0.965 6.013)
        (xy 0.949 6.031)
        (xy 0.933 6.047)
        (xy 0.915 6.061)
        (xy 0.897 6.076)
        (xy 0.876 6.088)
        (xy 0.856 6.1)
        (xy 0.836 6.111)
        (xy 0.815 6.122)
        (xy 0.794 6.13)
        (xy 0.773 6.138)
        (xy 0.749 6.145)
        (xy 0.727 6.151)
        (xy 0.704 6.156)
        (xy 0.682 6.159)
        (xy 0.658 6.159)
        (xy 0.634 6.161)
        (xy 0.61 6.159)
        (xy 0.586 6.159)
        (xy 0.563 6.156)
        (xy 0.541 6.151)
        (xy 0.519 6.145)
        (xy 0.496 6.138)
        (xy 0.474 6.132)
        (xy 0.453 6.122)
        (xy 0.431 6.112)
        (xy 0.411 6.101)
        (xy 0.392 6.088)
        (xy 0.372 6.076)
        (xy 0.353 6.061)
        (xy 0.337 6.047)
        (xy 0.32 6.031)
        (xy 0.303 6.013)
        (xy 0.288 5.997)
        (xy 0.275 5.978)
        (xy 0.262 5.959)
        (xy 0.248 5.938)
        (xy 0.237 5.919)
        (xy 0.228 5.898)
        (xy 0.218 5.875)
        (xy 0.211 5.853)
        (xy 0.204 5.832)
        (xy 0.2 5.81)
        (xy 0.195 5.786)
        (xy 0.192 5.763)
        (xy 0.19 5.739)
        (xy 0.189 5.718)
        (xy 0.634 5.718)
        (xy 0.634 5.713)
      )

      (stroke (width 0.001) (type solid)) (fill solid) (layer "B.Paste"))
    (fp_poly
      (pts
        (xy 1.904 -5.717)
        (xy 1.459 -5.717)
        (xy 1.461 -5.738)
        (xy 1.461 -5.762)
        (xy 1.465 -5.785)
        (xy 1.469 -5.809)
        (xy 1.475 -5.831)
        (xy 1.481 -5.852)
        (xy 1.489 -5.874)
        (xy 1.497 -5.897)
        (xy 1.507 -5.918)
        (xy 1.518 -5.937)
        (xy 1.531 -5.958)
        (xy 1.544 -5.977)
        (xy 1.558 -5.996)
        (xy 1.574 -6.012)
        (xy 1.59 -6.03)
        (xy 1.606 -6.046)
        (xy 1.624 -6.06)
        (xy 1.642 -6.075)
        (xy 1.661 -6.087)
        (xy 1.681 -6.1)
        (xy 1.701 -6.111)
        (xy 1.723 -6.121)
        (xy 1.745 -6.131)
        (xy 1.766 -6.137)
        (xy 1.788 -6.144)
        (xy 1.81 -6.15)
        (xy 1.834 -6.155)
        (xy 1.856 -6.158)
        (xy 1.88 -6.158)
        (xy 1.904 -6.16)
        (xy 1.927 -6.158)
        (xy 1.951 -6.158)
        (xy 1.975 -6.155)
        (xy 1.997 -6.15)
        (xy 2.019 -6.144)
        (xy 2.043 -6.137)
        (xy 2.064 -6.129)
        (xy 2.085 -6.121)
        (xy 2.107 -6.11)
        (xy 2.126 -6.099)
        (xy 2.146 -6.087)
        (xy 2.166 -6.075)
        (xy 2.185 -6.06)
        (xy 2.202 -6.046)
        (xy 2.22 -6.03)
        (xy 2.236 -6.012)
        (xy 2.25 -5.994)
        (xy 2.265 -5.977)
        (xy 2.277 -5.956)
        (xy 2.289 -5.937)
        (xy 2.301 -5.916)
        (xy 2.311 -5.895)
        (xy 2.319 -5.873)
        (xy 2.327 -5.852)
        (xy 2.334 -5.829)
        (xy 2.339 -5.807)
        (xy 2.345 -5.785)
        (xy 2.347 -5.761)
        (xy 2.349 -5.738)
        (xy 2.35 -5.714)
        (xy 2.349 -5.692)
        (xy 2.347 -5.668)
        (xy 2.345 -5.644)
        (xy 2.339 -5.621)
        (xy 2.334 -5.599)
        (xy 2.327 -5.576)
        (xy 2.319 -5.555)
        (xy 2.311 -5.533)
        (xy 2.301 -5.512)
        (xy 2.289 -5.491)
        (xy 2.277 -5.472)
        (xy 2.265 -5.453)
        (xy 2.25 -5.434)
        (xy 2.236 -5.416)
        (xy 2.22 -5.4)
        (xy 2.202 -5.384)
        (xy 2.185 -5.368)
        (xy 2.166 -5.355)
        (xy 2.146 -5.341)
        (xy 2.126 -5.329)
        (xy 2.107 -5.318)
        (xy 2.085 -5.307)
        (xy 2.064 -5.299)
        (xy 2.043 -5.291)
        (xy 2.019 -5.285)
        (xy 1.997 -5.28)
        (xy 1.975 -5.275)
        (xy 1.951 -5.272)
        (xy 1.927 -5.27)
        (xy 1.904 -5.269)
        (xy 1.88 -5.27)
        (xy 1.856 -5.272)
        (xy 1.834 -5.275)
        (xy 1.81 -5.28)
        (xy 1.788 -5.285)
        (xy 1.766 -5.291)
        (xy 1.745 -5.299)
        (xy 1.723 -5.307)
        (xy 1.701 -5.317)
        (xy 1.681 -5.328)
        (xy 1.661 -5.341)
        (xy 1.642 -5.355)
        (xy 1.624 -5.368)
        (xy 1.606 -5.384)
        (xy 1.59 -5.4)
        (xy 1.574 -5.416)
        (xy 1.558 -5.434)
        (xy 1.544 -5.453)
        (xy 1.531 -5.472)
        (xy 1.518 -5.491)
        (xy 1.507 -5.511)
        (xy 1.497 -5.533)
        (xy 1.489 -5.554)
        (xy 1.481 -5.576)
        (xy 1.475 -5.599)
        (xy 1.469 -5.621)
        (xy 1.465 -5.644)
        (xy 1.461 -5.666)
        (xy 1.461 -5.69)
        (xy 1.459 -5.712)
        (xy 1.904 -5.712)
        (xy 1.904 -5.717)
      )

      (stroke (width 0.001) (type solid)) (fill solid) (layer "B.Paste"))
    (fp_poly
      (pts
        (xy 1.904 -3.177)
        (xy 1.459 -3.177)
        (xy 1.461 -3.198)
        (xy 1.461 -3.222)
        (xy 1.465 -3.245)
        (xy 1.469 -3.269)
        (xy 1.475 -3.29)
        (xy 1.481 -3.313)
        (xy 1.489 -3.334)
        (xy 1.497 -3.357)
        (xy 1.507 -3.378)
        (xy 1.518 -3.398)
        (xy 1.531 -3.418)
        (xy 1.544 -3.436)
        (xy 1.558 -3.455)
        (xy 1.574 -3.472)
        (xy 1.59 -3.49)
        (xy 1.606 -3.505)
        (xy 1.624 -3.52)
        (xy 1.642 -3.535)
        (xy 1.661 -3.547)
        (xy 1.681 -3.56)
        (xy 1.701 -3.571)
        (xy 1.723 -3.581)
        (xy 1.745 -3.591)
        (xy 1.766 -3.597)
        (xy 1.788 -3.604)
        (xy 1.81 -3.609)
        (xy 1.834 -3.615)
        (xy 1.856 -3.617)
        (xy 1.88 -3.619)
        (xy 1.904 -3.62)
        (xy 1.927 -3.619)
        (xy 1.951 -3.617)
        (xy 1.975 -3.615)
        (xy 1.997 -3.609)
        (xy 2.019 -3.604)
        (xy 2.043 -3.597)
        (xy 2.064 -3.589)
        (xy 2.085 -3.581)
        (xy 2.107 -3.571)
        (xy 2.126 -3.559)
        (xy 2.146 -3.547)
        (xy 2.166 -3.535)
        (xy 2.185 -3.52)
        (xy 2.202 -3.505)
        (xy 2.22 -3.49)
        (xy 2.236 -3.472)
        (xy 2.25 -3.454)
        (xy 2.265 -3.436)
        (xy 2.277 -3.416)
        (xy 2.289 -3.396)
        (xy 2.301 -3.376)
        (xy 2.311 -3.355)
        (xy 2.319 -3.334)
        (xy 2.327 -3.313)
        (xy 2.334 -3.289)
        (xy 2.339 -3.267)
        (xy 2.345 -3.245)
        (xy 2.347 -3.221)
        (xy 2.349 -3.197)
        (xy 2.35 -3.174)
        (xy 2.349 -3.152)
        (xy 2.347 -3.128)
        (xy 2.345 -3.104)
        (xy 2.339 -3.081)
        (xy 2.334 -3.059)
        (xy 2.327 -3.036)
        (xy 2.319 -3.015)
        (xy 2.311 -2.994)
        (xy 2.301 -2.972)
        (xy 2.289 -2.951)
        (xy 2.277 -2.932)
        (xy 2.265 -2.912)
        (xy 2.25 -2.894)
        (xy 2.236 -2.876)
        (xy 2.22 -2.859)
        (xy 2.202 -2.843)
        (xy 2.185 -2.829)
        (xy 2.166 -2.814)
        (xy 2.146 -2.801)
        (xy 2.126 -2.789)
        (xy 2.107 -2.778)
        (xy 2.085 -2.767)
        (xy 2.064 -2.759)
        (xy 2.043 -2.751)
        (xy 2.019 -2.745)
        (xy 1.997 -2.74)
        (xy 1.975 -2.734)
        (xy 1.951 -2.732)
        (xy 1.927 -2.73)
        (xy 1.904 -2.729)
        (xy 1.88 -2.73)
        (xy 1.856 -2.732)
        (xy 1.834 -2.734)
        (xy 1.81 -2.74)
        (xy 1.788 -2.745)
        (xy 1.766 -2.751)
        (xy 1.745 -2.758)
        (xy 1.723 -2.767)
        (xy 1.701 -2.777)
        (xy 1.681 -2.789)
        (xy 1.661 -2.801)
        (xy 1.642 -2.814)
        (xy 1.624 -2.829)
        (xy 1.606 -2.843)
        (xy 1.59 -2.859)
        (xy 1.574 -2.876)
        (xy 1.558 -2.894)
        (xy 1.544 -2.912)
        (xy 1.531 -2.931)
        (xy 1.518 -2.951)
        (xy 1.507 -2.971)
        (xy 1.497 -2.992)
        (xy 1.489 -3.015)
        (xy 1.481 -3.036)
        (xy 1.475 -3.059)
        (xy 1.469 -3.08)
        (xy 1.465 -3.104)
        (xy 1.461 -3.126)
        (xy 1.461 -3.15)
        (xy 1.459 -3.172)
        (xy 1.904 -3.172)
        (xy 1.904 -3.177)
      )

      (stroke (width 0.001) (type solid)) (fill solid) (layer "B.Paste"))
    (fp_poly
      (pts
        (xy 1.904 1.903)
        (xy 1.459 1.903)
        (xy 1.461 1.881)
        (xy 1.461 1.857)
        (xy 1.465 1.835)
        (xy 1.469 1.811)
        (xy 1.475 1.789)
        (xy 1.481 1.767)
        (xy 1.489 1.746)
        (xy 1.497 1.724)
        (xy 1.507 1.702)
        (xy 1.518 1.682)
        (xy 1.531 1.662)
        (xy 1.544 1.643)
        (xy 1.558 1.625)
        (xy 1.574 1.607)
        (xy 1.59 1.591)
        (xy 1.606 1.575)
        (xy 1.624 1.559)
        (xy 1.642 1.545)
        (xy 1.661 1.532)
        (xy 1.681 1.519)
        (xy 1.701 1.508)
        (xy 1.723 1.498)
        (xy 1.745 1.49)
        (xy 1.766 1.482)
        (xy 1.788 1.476)
        (xy 1.81 1.47)
        (xy 1.834 1.466)
        (xy 1.856 1.462)
        (xy 1.88 1.462)
        (xy 1.904 1.46)
        (xy 1.927 1.462)
        (xy 1.951 1.462)
        (xy 1.975 1.466)
        (xy 1.997 1.47)
        (xy 2.019 1.476)
        (xy 2.043 1.482)
        (xy 2.064 1.49)
        (xy 2.085 1.498)
        (xy 2.107 1.509)
        (xy 2.126 1.52)
        (xy 2.146 1.532)
        (xy 2.166 1.545)
        (xy 2.185 1.559)
        (xy 2.202 1.575)
        (xy 2.22 1.591)
        (xy 2.236 1.607)
        (xy 2.25 1.625)
        (xy 2.265 1.643)
        (xy 2.277 1.663)
        (xy 2.289 1.684)
        (xy 2.301 1.704)
        (xy 2.311 1.724)
        (xy 2.319 1.746)
        (xy 2.327 1.767)
        (xy 2.334 1.79)
        (xy 2.339 1.813)
        (xy 2.345 1.835)
        (xy 2.347 1.859)
        (xy 2.349 1.882)
        (xy 2.35 1.905)
        (xy 2.349 1.928)
        (xy 2.347 1.952)
        (xy 2.345 1.976)
        (xy 2.339 1.998)
        (xy 2.334 2.02)
        (xy 2.327 2.044)
        (xy 2.319 2.065)
        (xy 2.311 2.086)
        (xy 2.301 2.108)
        (xy 2.289 2.127)
        (xy 2.277 2.147)
        (xy 2.265 2.167)
        (xy 2.25 2.186)
        (xy 2.236 2.203)
        (xy 2.22 2.221)
        (xy 2.202 2.237)
        (xy 2.185 2.251)
        (xy 2.166 2.266)
        (xy 2.146 2.278)
        (xy 2.126 2.29)
        (xy 2.107 2.302)
        (xy 2.085 2.312)
        (xy 2.064 2.32)
        (xy 2.043 2.328)
        (xy 2.019 2.335)
        (xy 1.997 2.34)
        (xy 1.975 2.346)
        (xy 1.951 2.348)
        (xy 1.927 2.35)
        (xy 1.904 2.351)
        (xy 1.88 2.35)
        (xy 1.856 2.348)
        (xy 1.834 2.346)
        (xy 1.81 2.34)
        (xy 1.788 2.335)
        (xy 1.766 2.328)
        (xy 1.745 2.322)
        (xy 1.723 2.312)
        (xy 1.701 2.302)
        (xy 1.681 2.291)
        (xy 1.661 2.278)
        (xy 1.642 2.266)
        (xy 1.624 2.251)
        (xy 1.606 2.237)
        (xy 1.59 2.221)
        (xy 1.574 2.203)
        (xy 1.558 2.186)
        (xy 1.544 2.167)
        (xy 1.531 2.149)
        (xy 1.518 2.129)
        (xy 1.507 2.109)
        (xy 1.497 2.088)
        (xy 1.489 2.065)
        (xy 1.481 2.044)
        (xy 1.475 2.021)
        (xy 1.469 2)
        (xy 1.465 1.976)
        (xy 1.461 1.954)
        (xy 1.461 1.93)
        (xy 1.459 1.907)
        (xy 1.904 1.907)
        (xy 1.904 1.903)
      )

      (stroke (width 0.001) (type solid)) (fill solid) (layer "B.Paste"))
    (fp_poly
      (pts
        (xy 1.904 3.173)
        (xy 1.459 3.173)
        (xy 1.461 3.151)
        (xy 1.461 3.127)
        (xy 1.465 3.105)
        (xy 1.469 3.081)
        (xy 1.475 3.06)
        (xy 1.481 3.037)
        (xy 1.489 3.016)
        (xy 1.497 2.993)
        (xy 1.507 2.972)
        (xy 1.518 2.952)
        (xy 1.531 2.932)
        (xy 1.544 2.913)
        (xy 1.558 2.895)
        (xy 1.574 2.877)
        (xy 1.59 2.86)
        (xy 1.606 2.844)
        (xy 1.624 2.83)
        (xy 1.642 2.815)
        (xy 1.661 2.802)
        (xy 1.681 2.79)
        (xy 1.701 2.778)
        (xy 1.723 2.768)
        (xy 1.745 2.759)
        (xy 1.766 2.752)
        (xy 1.788 2.746)
        (xy 1.81 2.741)
        (xy 1.834 2.735)
        (xy 1.856 2.733)
        (xy 1.88 2.731)
        (xy 1.904 2.73)
        (xy 1.927 2.731)
        (xy 1.951 2.733)
        (xy 1.975 2.735)
        (xy 1.997 2.741)
        (xy 2.019 2.746)
        (xy 2.043 2.752)
        (xy 2.064 2.76)
        (xy 2.085 2.768)
        (xy 2.107 2.779)
        (xy 2.126 2.79)
        (xy 2.146 2.802)
        (xy 2.166 2.815)
        (xy 2.185 2.83)
        (xy 2.202 2.844)
        (xy 2.22 2.86)
        (xy 2.236 2.877)
        (xy 2.25 2.895)
        (xy 2.265 2.913)
        (xy 2.277 2.933)
        (xy 2.289 2.952)
        (xy 2.301 2.973)
        (xy 2.311 2.995)
        (xy 2.319 3.016)
        (xy 2.327 3.037)
        (xy 2.334 3.06)
        (xy 2.339 3.082)
        (xy 2.345 3.105)
        (xy 2.347 3.129)
        (xy 2.349 3.153)
        (xy 2.35 3.175)
        (xy 2.349 3.198)
        (xy 2.347 3.222)
        (xy 2.345 3.246)
        (xy 2.339 3.268)
        (xy 2.334 3.29)
        (xy 2.327 3.314)
        (xy 2.319 3.335)
        (xy 2.311 3.356)
        (xy 2.301 3.377)
        (xy 2.289 3.397)
        (xy 2.277 3.417)
        (xy 2.265 3.437)
        (xy 2.25 3.455)
        (xy 2.236 3.473)
        (xy 2.22 3.491)
        (xy 2.202 3.506)
        (xy 2.185 3.521)
        (xy 2.166 3.536)
        (xy 2.146 3.548)
        (xy 2.126 3.56)
        (xy 2.107 3.572)
        (xy 2.085 3.582)
        (xy 2.064 3.59)
        (xy 2.043 3.598)
        (xy 2.019 3.605)
        (xy 1.997 3.61)
        (xy 1.975 3.616)
        (xy 1.951 3.618)
        (xy 1.927 3.62)
        (xy 1.904 3.621)
        (xy 1.88 3.62)
        (xy 1.856 3.618)
        (xy 1.834 3.616)
        (xy 1.81 3.61)
        (xy 1.788 3.605)
        (xy 1.766 3.598)
        (xy 1.745 3.592)
        (xy 1.723 3.582)
        (xy 1.701 3.572)
        (xy 1.681 3.561)
        (xy 1.661 3.548)
        (xy 1.642 3.536)
        (xy 1.624 3.521)
        (xy 1.606 3.506)
        (xy 1.59 3.491)
        (xy 1.574 3.473)
        (xy 1.558 3.456)
        (xy 1.544 3.437)
        (xy 1.531 3.419)
        (xy 1.518 3.399)
        (xy 1.507 3.379)
        (xy 1.497 3.358)
        (xy 1.489 3.335)
        (xy 1.481 3.314)
        (xy 1.475 3.291)
        (xy 1.469 3.27)
        (xy 1.465 3.246)
        (xy 1.461 3.223)
        (xy 1.461 3.199)
        (xy 1.459 3.178)
        (xy 1.904 3.178)
        (xy 1.904 3.173)
      )

      (stroke (width 0.001) (type solid)) (fill solid) (layer "B.Paste"))
    (fp_poly
      (pts
        (xy 1.904 4.443)
        (xy 1.459 4.443)
        (xy 1.461 4.422)
        (xy 1.461 4.398)
        (xy 1.465 4.374)
        (xy 1.469 4.351)
        (xy 1.475 4.329)
        (xy 1.481 4.308)
        (xy 1.489 4.286)
        (xy 1.497 4.263)
        (xy 1.507 4.242)
        (xy 1.518 4.223)
        (xy 1.531 4.202)
        (xy 1.544 4.183)
        (xy 1.558 4.164)
        (xy 1.574 4.148)
        (xy 1.59 4.13)
        (xy 1.606 4.114)
        (xy 1.624 4.1)
        (xy 1.642 4.085)
        (xy 1.661 4.072)
        (xy 1.681 4.06)
        (xy 1.701 4.048)
        (xy 1.723 4.039)
        (xy 1.745 4.029)
        (xy 1.766 4.023)
        (xy 1.788 4.015)
        (xy 1.81 4.01)
        (xy 1.834 4.005)
        (xy 1.856 4.002)
        (xy 1.88 4.002)
        (xy 1.904 4)
        (xy 1.927 4.002)
        (xy 1.951 4.002)
        (xy 1.975 4.005)
        (xy 1.997 4.01)
        (xy 2.019 4.015)
        (xy 2.043 4.023)
        (xy 2.064 4.031)
        (xy 2.085 4.039)
        (xy 2.107 4.05)
        (xy 2.126 4.06)
        (xy 2.146 4.072)
        (xy 2.166 4.085)
        (xy 2.185 4.1)
        (xy 2.202 4.114)
        (xy 2.22 4.13)
        (xy 2.236 4.148)
        (xy 2.25 4.165)
        (xy 2.265 4.183)
        (xy 2.277 4.204)
        (xy 2.289 4.223)
        (xy 2.301 4.244)
        (xy 2.311 4.265)
        (xy 2.319 4.286)
        (xy 2.327 4.308)
        (xy 2.334 4.33)
        (xy 2.339 4.353)
        (xy 2.345 4.375)
        (xy 2.347 4.398)
        (xy 2.349 4.422)
        (xy 2.35 4.446)
        (xy 2.349 4.468)
        (xy 2.347 4.492)
        (xy 2.345 4.515)
        (xy 2.339 4.539)
        (xy 2.334 4.56)
        (xy 2.327 4.584)
        (xy 2.319 4.604)
        (xy 2.311 4.627)
        (xy 2.301 4.648)
        (xy 2.289 4.669)
        (xy 2.277 4.688)
        (xy 2.265 4.707)
        (xy 2.25 4.725)
        (xy 2.236 4.744)
        (xy 2.22 4.76)
        (xy 2.202 4.776)
        (xy 2.185 4.792)
        (xy 2.166 4.805)
        (xy 2.146 4.818)
        (xy 2.128 4.83)
        (xy 2.107 4.842)
        (xy 2.085 4.853)
        (xy 2.064 4.861)
        (xy 2.043 4.869)
        (xy 2.019 4.875)
        (xy 1.997 4.88)
        (xy 1.975 4.885)
        (xy 1.951 4.888)
        (xy 1.927 4.89)
        (xy 1.904 4.89)
        (xy 1.88 4.89)
        (xy 1.856 4.888)
        (xy 1.834 4.885)
        (xy 1.81 4.88)
        (xy 1.788 4.875)
        (xy 1.766 4.869)
        (xy 1.745 4.861)
        (xy 1.723 4.853)
        (xy 1.701 4.842)
        (xy 1.681 4.832)
        (xy 1.661 4.818)
        (xy 1.642 4.805)
        (xy 1.624 4.792)
        (xy 1.606 4.776)
        (xy 1.59 4.76)
        (xy 1.574 4.744)
        (xy 1.558 4.726)
        (xy 1.544 4.707)
        (xy 1.531 4.688)
        (xy 1.518 4.669)
        (xy 1.507 4.648)
        (xy 1.497 4.627)
        (xy 1.489 4.606)
        (xy 1.481 4.584)
        (xy 1.475 4.561)
        (xy 1.469 4.539)
        (xy 1.465 4.516)
        (xy 1.461 4.494)
        (xy 1.461 4.47)
        (xy 1.459 4.447)
        (xy 1.904 4.447)
        (xy 1.904 4.443)
      )

      (stroke (width 0.001) (type solid)) (fill solid) (layer "B.Paste"))
    (fp_poly
      (pts
        (xy 1.904 5.713)
        (xy 1.459 5.713)
        (xy 1.461 5.691)
        (xy 1.461 5.667)
        (xy 1.465 5.645)
        (xy 1.469 5.622)
        (xy 1.475 5.6)
        (xy 1.481 5.577)
        (xy 1.489 5.555)
        (xy 1.497 5.534)
        (xy 1.507 5.512)
        (xy 1.518 5.492)
        (xy 1.531 5.473)
        (xy 1.544 5.454)
        (xy 1.558 5.435)
        (xy 1.574 5.417)
        (xy 1.59 5.401)
        (xy 1.606 5.385)
        (xy 1.624 5.369)
        (xy 1.642 5.356)
        (xy 1.661 5.342)
        (xy 1.681 5.329)
        (xy 1.701 5.318)
        (xy 1.723 5.308)
        (xy 1.745 5.3)
        (xy 1.766 5.292)
        (xy 1.788 5.286)
        (xy 1.81 5.281)
        (xy 1.834 5.276)
        (xy 1.856 5.273)
        (xy 1.88 5.271)
        (xy 1.904 5.27)
        (xy 1.927 5.271)
        (xy 1.951 5.273)
        (xy 1.975 5.276)
        (xy 1.997 5.281)
        (xy 2.019 5.286)
        (xy 2.043 5.292)
        (xy 2.064 5.3)
        (xy 2.085 5.308)
        (xy 2.107 5.319)
        (xy 2.126 5.33)
        (xy 2.146 5.342)
        (xy 2.166 5.356)
        (xy 2.185 5.369)
        (xy 2.202 5.385)
        (xy 2.22 5.401)
        (xy 2.236 5.417)
        (xy 2.25 5.435)
        (xy 2.265 5.454)
        (xy 2.277 5.473)
        (xy 2.289 5.492)
        (xy 2.301 5.513)
        (xy 2.311 5.534)
        (xy 2.319 5.556)
        (xy 2.327 5.577)
        (xy 2.334 5.6)
        (xy 2.339 5.622)
        (xy 2.345 5.645)
        (xy 2.347 5.669)
        (xy 2.349 5.693)
        (xy 2.35 5.715)
        (xy 2.349 5.739)
        (xy 2.347 5.762)
        (xy 2.345 5.786)
        (xy 2.339 5.808)
        (xy 2.334 5.83)
        (xy 2.327 5.853)
        (xy 2.319 5.874)
        (xy 2.311 5.896)
        (xy 2.301 5.917)
        (xy 2.289 5.938)
        (xy 2.277 5.957)
        (xy 2.265 5.978)
        (xy 2.25 5.995)
        (xy 2.236 6.013)
        (xy 2.22 6.031)
        (xy 2.202 6.047)
        (xy 2.185 6.061)
        (xy 2.166 6.076)
        (xy 2.146 6.088)
        (xy 2.126 6.1)
        (xy 2.107 6.111)
        (xy 2.085 6.122)
        (xy 2.064 6.13)
        (xy 2.043 6.138)
        (xy 2.019 6.145)
        (xy 1.997 6.151)
        (xy 1.975 6.156)
        (xy 1.951 6.159)
        (xy 1.927 6.159)
        (xy 1.904 6.161)
        (xy 1.88 6.159)
        (xy 1.856 6.159)
        (xy 1.834 6.156)
        (xy 1.81 6.151)
        (xy 1.788 6.145)
        (xy 1.766 6.138)
        (xy 1.745 6.132)
        (xy 1.723 6.122)
        (xy 1.701 6.112)
        (xy 1.681 6.101)
        (xy 1.661 6.088)
        (xy 1.642 6.076)
        (xy 1.624 6.061)
        (xy 1.606 6.047)
        (xy 1.59 6.031)
        (xy 1.574 6.013)
        (xy 1.558 5.997)
        (xy 1.544 5.978)
        (xy 1.531 5.959)
        (xy 1.518 5.938)
        (xy 1.507 5.919)
        (xy 1.497 5.898)
        (xy 1.489 5.875)
        (xy 1.481 5.853)
        (xy 1.475 5.832)
        (xy 1.469 5.81)
        (xy 1.465 5.786)
        (xy 1.461 5.763)
        (xy 1.461 5.739)
        (xy 1.459 5.718)
        (xy 1.904 5.718)
        (xy 1.904 5.713)
      )

      (stroke (width 0.001) (type solid)) (fill solid) (layer "B.Paste"))
    (fp_poly
      (pts
        (xy 3.174 -5.717)
        (xy 2.729 -5.717)
        (xy 2.73 -5.738)
        (xy 2.732 -5.762)
        (xy 2.734 -5.785)
        (xy 2.74 -5.809)
        (xy 2.745 -5.831)
        (xy 2.751 -5.852)
        (xy 2.758 -5.874)
        (xy 2.767 -5.897)
        (xy 2.777 -5.918)
        (xy 2.789 -5.937)
        (xy 2.801 -5.958)
        (xy 2.814 -5.977)
        (xy 2.829 -5.996)
        (xy 2.843 -6.012)
        (xy 2.859 -6.03)
        (xy 2.876 -6.046)
        (xy 2.894 -6.06)
        (xy 2.912 -6.075)
        (xy 2.931 -6.087)
        (xy 2.951 -6.1)
        (xy 2.971 -6.111)
        (xy 2.992 -6.121)
        (xy 3.015 -6.131)
        (xy 3.036 -6.137)
        (xy 3.059 -6.144)
        (xy 3.08 -6.15)
        (xy 3.104 -6.155)
        (xy 3.126 -6.158)
        (xy 3.15 -6.158)
        (xy 3.174 -6.16)
        (xy 3.197 -6.158)
        (xy 3.221 -6.158)
        (xy 3.245 -6.155)
        (xy 3.267 -6.15)
        (xy 3.289 -6.144)
        (xy 3.313 -6.137)
        (xy 3.334 -6.129)
        (xy 3.355 -6.121)
        (xy 3.376 -6.11)
        (xy 3.396 -6.099)
        (xy 3.416 -6.087)
        (xy 3.436 -6.075)
        (xy 3.454 -6.06)
        (xy 3.472 -6.046)
        (xy 3.49 -6.03)
        (xy 3.505 -6.012)
        (xy 3.52 -5.994)
        (xy 3.535 -5.977)
        (xy 3.547 -5.956)
        (xy 3.559 -5.937)
        (xy 3.571 -5.916)
        (xy 3.581 -5.895)
        (xy 3.589 -5.873)
        (xy 3.597 -5.852)
        (xy 3.604 -5.829)
        (xy 3.609 -5.807)
        (xy 3.615 -5.785)
        (xy 3.617 -5.761)
        (xy 3.619 -5.738)
        (xy 3.62 -5.714)
        (xy 3.619 -5.692)
        (xy 3.617 -5.668)
        (xy 3.615 -5.644)
        (xy 3.609 -5.621)
        (xy 3.604 -5.599)
        (xy 3.597 -5.576)
        (xy 3.589 -5.555)
        (xy 3.581 -5.533)
        (xy 3.571 -5.512)
        (xy 3.559 -5.491)
        (xy 3.547 -5.472)
        (xy 3.535 -5.453)
        (xy 3.52 -5.434)
        (xy 3.505 -5.416)
        (xy 3.49 -5.4)
        (xy 3.472 -5.384)
        (xy 3.454 -5.368)
        (xy 3.436 -5.355)
        (xy 3.416 -5.341)
        (xy 3.396 -5.329)
        (xy 3.376 -5.318)
        (xy 3.355 -5.307)
        (xy 3.334 -5.299)
        (xy 3.313 -5.291)
        (xy 3.289 -5.285)
        (xy 3.267 -5.28)
        (xy 3.245 -5.275)
        (xy 3.221 -5.272)
        (xy 3.197 -5.27)
        (xy 3.174 -5.269)
        (xy 3.15 -5.27)
        (xy 3.126 -5.272)
        (xy 3.104 -5.275)
        (xy 3.08 -5.28)
        (xy 3.059 -5.285)
        (xy 3.036 -5.291)
        (xy 3.015 -5.299)
        (xy 2.992 -5.307)
        (xy 2.971 -5.317)
        (xy 2.951 -5.328)
        (xy 2.931 -5.341)
        (xy 2.912 -5.355)
        (xy 2.894 -5.368)
        (xy 2.876 -5.384)
        (xy 2.859 -5.4)
        (xy 2.843 -5.416)
        (xy 2.829 -5.434)
        (xy 2.814 -5.453)
        (xy 2.801 -5.472)
        (xy 2.789 -5.491)
        (xy 2.777 -5.511)
        (xy 2.767 -5.533)
        (xy 2.758 -5.554)
        (xy 2.751 -5.576)
        (xy 2.745 -5.599)
        (xy 2.74 -5.621)
        (xy 2.734 -5.644)
        (xy 2.732 -5.666)
        (xy 2.73 -5.69)
        (xy 2.729 -5.712)
        (xy 3.174 -5.712)
        (xy 3.174 -5.717)
      )

      (stroke (width 0.001) (type solid)) (fill solid) (layer "B.Paste"))
    (fp_poly
      (pts
        (xy 3.174 -3.177)
        (xy 2.729 -3.177)
        (xy 2.73 -3.198)
        (xy 2.732 -3.222)
        (xy 2.734 -3.245)
        (xy 2.74 -3.269)
        (xy 2.745 -3.29)
        (xy 2.751 -3.313)
        (xy 2.758 -3.334)
        (xy 2.767 -3.357)
        (xy 2.777 -3.378)
        (xy 2.789 -3.398)
        (xy 2.801 -3.418)
        (xy 2.814 -3.436)
        (xy 2.829 -3.455)
        (xy 2.843 -3.472)
        (xy 2.859 -3.49)
        (xy 2.876 -3.505)
        (xy 2.894 -3.52)
        (xy 2.912 -3.535)
        (xy 2.931 -3.547)
        (xy 2.951 -3.56)
        (xy 2.971 -3.571)
        (xy 2.992 -3.581)
        (xy 3.015 -3.591)
        (xy 3.036 -3.597)
        (xy 3.059 -3.604)
        (xy 3.08 -3.609)
        (xy 3.104 -3.615)
        (xy 3.126 -3.617)
        (xy 3.15 -3.619)
        (xy 3.174 -3.62)
        (xy 3.197 -3.619)
        (xy 3.221 -3.617)
        (xy 3.245 -3.615)
        (xy 3.267 -3.609)
        (xy 3.289 -3.604)
        (xy 3.313 -3.597)
        (xy 3.334 -3.589)
        (xy 3.355 -3.581)
        (xy 3.376 -3.571)
        (xy 3.396 -3.559)
        (xy 3.416 -3.547)
        (xy 3.436 -3.535)
        (xy 3.454 -3.52)
        (xy 3.472 -3.505)
        (xy 3.49 -3.49)
        (xy 3.505 -3.472)
        (xy 3.52 -3.454)
        (xy 3.535 -3.436)
        (xy 3.547 -3.416)
        (xy 3.559 -3.396)
        (xy 3.571 -3.376)
        (xy 3.581 -3.355)
        (xy 3.589 -3.334)
        (xy 3.597 -3.313)
        (xy 3.604 -3.289)
        (xy 3.609 -3.267)
        (xy 3.615 -3.245)
        (xy 3.617 -3.221)
        (xy 3.619 -3.197)
        (xy 3.62 -3.174)
        (xy 3.619 -3.152)
        (xy 3.617 -3.128)
        (xy 3.615 -3.104)
        (xy 3.609 -3.081)
        (xy 3.604 -3.059)
        (xy 3.597 -3.036)
        (xy 3.589 -3.015)
        (xy 3.581 -2.994)
        (xy 3.571 -2.972)
        (xy 3.559 -2.951)
        (xy 3.547 -2.932)
        (xy 3.535 -2.912)
        (xy 3.52 -2.894)
        (xy 3.505 -2.876)
        (xy 3.49 -2.859)
        (xy 3.472 -2.843)
        (xy 3.454 -2.829)
        (xy 3.436 -2.814)
        (xy 3.416 -2.801)
        (xy 3.396 -2.789)
        (xy 3.376 -2.778)
        (xy 3.355 -2.767)
        (xy 3.334 -2.759)
        (xy 3.313 -2.751)
        (xy 3.289 -2.745)
        (xy 3.267 -2.74)
        (xy 3.245 -2.734)
        (xy 3.221 -2.732)
        (xy 3.197 -2.73)
        (xy 3.174 -2.729)
        (xy 3.15 -2.73)
        (xy 3.126 -2.732)
        (xy 3.104 -2.734)
        (xy 3.08 -2.74)
        (xy 3.059 -2.745)
        (xy 3.036 -2.751)
        (xy 3.015 -2.758)
        (xy 2.992 -2.767)
        (xy 2.971 -2.777)
        (xy 2.951 -2.789)
        (xy 2.931 -2.801)
        (xy 2.912 -2.814)
        (xy 2.894 -2.829)
        (xy 2.876 -2.843)
        (xy 2.859 -2.859)
        (xy 2.843 -2.876)
        (xy 2.829 -2.894)
        (xy 2.814 -2.912)
        (xy 2.801 -2.931)
        (xy 2.789 -2.951)
        (xy 2.777 -2.971)
        (xy 2.767 -2.992)
        (xy 2.758 -3.015)
        (xy 2.751 -3.036)
        (xy 2.745 -3.059)
        (xy 2.74 -3.08)
        (xy 2.734 -3.104)
        (xy 2.732 -3.126)
        (xy 2.73 -3.15)
        (xy 2.729 -3.172)
        (xy 3.174 -3.172)
        (xy 3.174 -3.177)
      )

      (stroke (width 0.001) (type solid)) (fill solid) (layer "B.Paste"))
    (fp_poly
      (pts
        (xy 3.174 1.903)
        (xy 2.729 1.903)
        (xy 2.73 1.881)
        (xy 2.732 1.857)
        (xy 2.734 1.835)
        (xy 2.74 1.811)
        (xy 2.745 1.789)
        (xy 2.751 1.767)
        (xy 2.758 1.746)
        (xy 2.767 1.724)
        (xy 2.777 1.702)
        (xy 2.789 1.682)
        (xy 2.801 1.662)
        (xy 2.814 1.643)
        (xy 2.829 1.625)
        (xy 2.843 1.607)
        (xy 2.859 1.591)
        (xy 2.876 1.575)
        (xy 2.894 1.559)
        (xy 2.912 1.545)
        (xy 2.931 1.532)
        (xy 2.951 1.519)
        (xy 2.971 1.508)
        (xy 2.992 1.498)
        (xy 3.015 1.49)
        (xy 3.036 1.482)
        (xy 3.059 1.476)
        (xy 3.08 1.47)
        (xy 3.104 1.466)
        (xy 3.126 1.462)
        (xy 3.15 1.462)
        (xy 3.174 1.46)
        (xy 3.197 1.462)
        (xy 3.221 1.462)
        (xy 3.245 1.466)
        (xy 3.267 1.47)
        (xy 3.289 1.476)
        (xy 3.313 1.482)
        (xy 3.334 1.49)
        (xy 3.355 1.498)
        (xy 3.376 1.509)
        (xy 3.396 1.52)
        (xy 3.416 1.532)
        (xy 3.436 1.545)
        (xy 3.454 1.559)
        (xy 3.472 1.575)
        (xy 3.49 1.591)
        (xy 3.505 1.607)
        (xy 3.52 1.625)
        (xy 3.535 1.643)
        (xy 3.547 1.663)
        (xy 3.559 1.684)
        (xy 3.571 1.704)
        (xy 3.581 1.724)
        (xy 3.589 1.746)
        (xy 3.597 1.767)
        (xy 3.604 1.79)
        (xy 3.609 1.813)
        (xy 3.615 1.835)
        (xy 3.617 1.859)
        (xy 3.619 1.882)
        (xy 3.62 1.905)
        (xy 3.619 1.928)
        (xy 3.617 1.952)
        (xy 3.615 1.976)
        (xy 3.609 1.998)
        (xy 3.604 2.02)
        (xy 3.597 2.044)
        (xy 3.589 2.065)
        (xy 3.581 2.086)
        (xy 3.571 2.108)
        (xy 3.559 2.127)
        (xy 3.547 2.147)
        (xy 3.535 2.167)
        (xy 3.52 2.186)
        (xy 3.505 2.203)
        (xy 3.49 2.221)
        (xy 3.472 2.237)
        (xy 3.454 2.251)
        (xy 3.436 2.266)
        (xy 3.416 2.278)
        (xy 3.396 2.29)
        (xy 3.376 2.302)
        (xy 3.355 2.312)
        (xy 3.334 2.32)
        (xy 3.313 2.328)
        (xy 3.289 2.335)
        (xy 3.267 2.34)
        (xy 3.245 2.346)
        (xy 3.221 2.348)
        (xy 3.197 2.35)
        (xy 3.174 2.351)
        (xy 3.15 2.35)
        (xy 3.126 2.348)
        (xy 3.104 2.346)
        (xy 3.08 2.34)
        (xy 3.059 2.335)
        (xy 3.036 2.328)
        (xy 3.015 2.322)
        (xy 2.992 2.312)
        (xy 2.971 2.302)
        (xy 2.951 2.291)
        (xy 2.931 2.278)
        (xy 2.912 2.266)
        (xy 2.894 2.251)
        (xy 2.876 2.237)
        (xy 2.859 2.221)
        (xy 2.843 2.203)
        (xy 2.829 2.186)
        (xy 2.814 2.167)
        (xy 2.801 2.149)
        (xy 2.789 2.129)
        (xy 2.777 2.109)
        (xy 2.767 2.088)
        (xy 2.758 2.065)
        (xy 2.751 2.044)
        (xy 2.745 2.021)
        (xy 2.74 2)
        (xy 2.734 1.976)
        (xy 2.732 1.954)
        (xy 2.73 1.93)
        (xy 2.729 1.907)
        (xy 3.174 1.907)
        (xy 3.174 1.903)
      )

      (stroke (width 0.001) (type solid)) (fill solid) (layer "B.Paste"))
    (fp_poly
      (pts
        (xy 3.174 3.173)
        (xy 2.729 3.173)
        (xy 2.73 3.151)
        (xy 2.732 3.127)
        (xy 2.734 3.105)
        (xy 2.74 3.081)
        (xy 2.745 3.06)
        (xy 2.751 3.037)
        (xy 2.758 3.016)
        (xy 2.767 2.993)
        (xy 2.777 2.972)
        (xy 2.789 2.952)
        (xy 2.801 2.932)
        (xy 2.814 2.913)
        (xy 2.829 2.895)
        (xy 2.843 2.877)
        (xy 2.859 2.86)
        (xy 2.876 2.844)
        (xy 2.894 2.83)
        (xy 2.912 2.815)
        (xy 2.931 2.802)
        (xy 2.951 2.79)
        (xy 2.971 2.778)
        (xy 2.992 2.768)
        (xy 3.015 2.759)
        (xy 3.036 2.752)
        (xy 3.059 2.746)
        (xy 3.08 2.741)
        (xy 3.104 2.735)
        (xy 3.126 2.733)
        (xy 3.15 2.731)
        (xy 3.174 2.73)
        (xy 3.197 2.731)
        (xy 3.221 2.733)
        (xy 3.245 2.735)
        (xy 3.267 2.741)
        (xy 3.289 2.746)
        (xy 3.313 2.752)
        (xy 3.334 2.76)
        (xy 3.355 2.768)
        (xy 3.376 2.779)
        (xy 3.396 2.79)
        (xy 3.416 2.802)
        (xy 3.436 2.815)
        (xy 3.454 2.83)
        (xy 3.472 2.844)
        (xy 3.49 2.86)
        (xy 3.505 2.877)
        (xy 3.52 2.895)
        (xy 3.535 2.913)
        (xy 3.547 2.933)
        (xy 3.559 2.952)
        (xy 3.571 2.973)
        (xy 3.581 2.995)
        (xy 3.589 3.016)
        (xy 3.597 3.037)
        (xy 3.604 3.06)
        (xy 3.609 3.082)
        (xy 3.615 3.105)
        (xy 3.617 3.129)
        (xy 3.619 3.153)
        (xy 3.62 3.175)
        (xy 3.619 3.198)
        (xy 3.617 3.222)
        (xy 3.615 3.246)
        (xy 3.609 3.268)
        (xy 3.604 3.29)
        (xy 3.597 3.314)
        (xy 3.589 3.335)
        (xy 3.581 3.356)
        (xy 3.571 3.377)
        (xy 3.559 3.397)
        (xy 3.547 3.417)
        (xy 3.535 3.437)
        (xy 3.52 3.455)
        (xy 3.505 3.473)
        (xy 3.49 3.491)
        (xy 3.472 3.506)
        (xy 3.454 3.521)
        (xy 3.436 3.536)
        (xy 3.416 3.548)
        (xy 3.396 3.56)
        (xy 3.376 3.572)
        (xy 3.355 3.582)
        (xy 3.334 3.59)
        (xy 3.313 3.598)
        (xy 3.289 3.605)
        (xy 3.267 3.61)
        (xy 3.245 3.616)
        (xy 3.221 3.618)
        (xy 3.197 3.62)
        (xy 3.174 3.621)
        (xy 3.15 3.62)
        (xy 3.126 3.618)
        (xy 3.104 3.616)
        (xy 3.08 3.61)
        (xy 3.059 3.605)
        (xy 3.036 3.598)
        (xy 3.015 3.592)
        (xy 2.992 3.582)
        (xy 2.971 3.572)
        (xy 2.951 3.561)
        (xy 2.931 3.548)
        (xy 2.912 3.536)
        (xy 2.894 3.521)
        (xy 2.876 3.506)
        (xy 2.859 3.491)
        (xy 2.843 3.473)
        (xy 2.829 3.456)
        (xy 2.814 3.437)
        (xy 2.801 3.419)
        (xy 2.789 3.399)
        (xy 2.777 3.379)
        (xy 2.767 3.358)
        (xy 2.758 3.335)
        (xy 2.751 3.314)
        (xy 2.745 3.291)
        (xy 2.74 3.27)
        (xy 2.734 3.246)
        (xy 2.732 3.223)
        (xy 2.73 3.199)
        (xy 2.729 3.178)
        (xy 3.174 3.178)
        (xy 3.174 3.173)
      )

      (stroke (width 0.001) (type solid)) (fill solid) (layer "B.Paste"))
    (fp_poly
      (pts
        (xy 3.174 4.443)
        (xy 2.729 4.443)
        (xy 2.73 4.422)
        (xy 2.732 4.398)
        (xy 2.734 4.374)
        (xy 2.74 4.351)
        (xy 2.745 4.329)
        (xy 2.751 4.308)
        (xy 2.758 4.286)
        (xy 2.767 4.263)
        (xy 2.777 4.242)
        (xy 2.789 4.223)
        (xy 2.801 4.202)
        (xy 2.814 4.183)
        (xy 2.829 4.164)
        (xy 2.843 4.148)
        (xy 2.859 4.13)
        (xy 2.876 4.114)
        (xy 2.894 4.1)
        (xy 2.912 4.085)
        (xy 2.931 4.072)
        (xy 2.951 4.06)
        (xy 2.971 4.048)
        (xy 2.992 4.039)
        (xy 3.015 4.029)
        (xy 3.036 4.023)
        (xy 3.059 4.015)
        (xy 3.08 4.01)
        (xy 3.104 4.005)
        (xy 3.126 4.002)
        (xy 3.15 4.002)
        (xy 3.174 4)
        (xy 3.197 4.002)
        (xy 3.221 4.002)
        (xy 3.245 4.005)
        (xy 3.267 4.01)
        (xy 3.289 4.015)
        (xy 3.313 4.023)
        (xy 3.334 4.031)
        (xy 3.355 4.039)
        (xy 3.376 4.05)
        (xy 3.396 4.06)
        (xy 3.416 4.072)
        (xy 3.436 4.085)
        (xy 3.454 4.1)
        (xy 3.472 4.114)
        (xy 3.49 4.13)
        (xy 3.505 4.148)
        (xy 3.52 4.165)
        (xy 3.535 4.183)
        (xy 3.547 4.204)
        (xy 3.559 4.223)
        (xy 3.571 4.244)
        (xy 3.581 4.265)
        (xy 3.589 4.286)
        (xy 3.597 4.308)
        (xy 3.604 4.33)
        (xy 3.609 4.353)
        (xy 3.615 4.375)
        (xy 3.617 4.398)
        (xy 3.619 4.422)
        (xy 3.62 4.446)
        (xy 3.619 4.468)
        (xy 3.617 4.492)
        (xy 3.615 4.515)
        (xy 3.609 4.539)
        (xy 3.604 4.56)
        (xy 3.597 4.584)
        (xy 3.589 4.604)
        (xy 3.581 4.627)
        (xy 3.571 4.648)
        (xy 3.559 4.669)
        (xy 3.547 4.688)
        (xy 3.535 4.707)
        (xy 3.52 4.725)
        (xy 3.505 4.744)
        (xy 3.49 4.76)
        (xy 3.472 4.776)
        (xy 3.454 4.792)
        (xy 3.436 4.805)
        (xy 3.416 4.818)
        (xy 3.398 4.83)
        (xy 3.376 4.842)
        (xy 3.355 4.853)
        (xy 3.334 4.861)
        (xy 3.313 4.869)
        (xy 3.289 4.875)
        (xy 3.267 4.88)
        (xy 3.245 4.885)
        (xy 3.221 4.888)
        (xy 3.197 4.89)
        (xy 3.174 4.89)
        (xy 3.15 4.89)
        (xy 3.126 4.888)
        (xy 3.104 4.885)
        (xy 3.08 4.88)
        (xy 3.059 4.875)
        (xy 3.036 4.869)
        (xy 3.015 4.861)
        (xy 2.992 4.853)
        (xy 2.971 4.842)
        (xy 2.951 4.832)
        (xy 2.931 4.818)
        (xy 2.912 4.805)
        (xy 2.894 4.792)
        (xy 2.876 4.776)
        (xy 2.859 4.76)
        (xy 2.843 4.744)
        (xy 2.829 4.726)
        (xy 2.814 4.707)
        (xy 2.801 4.688)
        (xy 2.789 4.669)
        (xy 2.777 4.648)
        (xy 2.767 4.627)
        (xy 2.758 4.606)
        (xy 2.751 4.584)
        (xy 2.745 4.561)
        (xy 2.74 4.539)
        (xy 2.734 4.516)
        (xy 2.732 4.494)
        (xy 2.73 4.47)
        (xy 2.729 4.447)
        (xy 3.174 4.447)
        (xy 3.174 4.443)
      )

      (stroke (width 0.001) (type solid)) (fill solid) (layer "B.Paste"))
    (fp_poly
      (pts
        (xy 3.174 5.713)
        (xy 2.729 5.713)
        (xy 2.73 5.691)
        (xy 2.732 5.667)
        (xy 2.734 5.645)
        (xy 2.74 5.622)
        (xy 2.745 5.6)
        (xy 2.751 5.577)
        (xy 2.758 5.555)
        (xy 2.767 5.534)
        (xy 2.777 5.512)
        (xy 2.789 5.492)
        (xy 2.801 5.473)
        (xy 2.814 5.454)
        (xy 2.829 5.435)
        (xy 2.843 5.417)
        (xy 2.859 5.401)
        (xy 2.876 5.385)
        (xy 2.894 5.369)
        (xy 2.912 5.356)
        (xy 2.931 5.342)
        (xy 2.951 5.329)
        (xy 2.971 5.318)
        (xy 2.992 5.308)
        (xy 3.015 5.3)
        (xy 3.036 5.292)
        (xy 3.059 5.286)
        (xy 3.08 5.281)
        (xy 3.104 5.276)
        (xy 3.126 5.273)
        (xy 3.15 5.271)
        (xy 3.174 5.27)
        (xy 3.197 5.271)
        (xy 3.221 5.273)
        (xy 3.245 5.276)
        (xy 3.267 5.281)
        (xy 3.289 5.286)
        (xy 3.313 5.292)
        (xy 3.334 5.3)
        (xy 3.355 5.308)
        (xy 3.376 5.319)
        (xy 3.396 5.33)
        (xy 3.416 5.342)
        (xy 3.436 5.356)
        (xy 3.454 5.369)
        (xy 3.472 5.385)
        (xy 3.49 5.401)
        (xy 3.505 5.417)
        (xy 3.52 5.435)
        (xy 3.535 5.454)
        (xy 3.547 5.473)
        (xy 3.559 5.492)
        (xy 3.571 5.513)
        (xy 3.581 5.534)
        (xy 3.589 5.556)
        (xy 3.597 5.577)
        (xy 3.604 5.6)
        (xy 3.609 5.622)
        (xy 3.615 5.645)
        (xy 3.617 5.669)
        (xy 3.619 5.693)
        (xy 3.62 5.715)
        (xy 3.619 5.739)
        (xy 3.617 5.762)
        (xy 3.615 5.786)
        (xy 3.609 5.808)
        (xy 3.604 5.83)
        (xy 3.597 5.853)
        (xy 3.589 5.874)
        (xy 3.581 5.896)
        (xy 3.571 5.917)
        (xy 3.559 5.938)
        (xy 3.547 5.957)
        (xy 3.535 5.978)
        (xy 3.52 5.995)
        (xy 3.505 6.013)
        (xy 3.49 6.031)
        (xy 3.472 6.047)
        (xy 3.454 6.061)
        (xy 3.436 6.076)
        (xy 3.416 6.088)
        (xy 3.396 6.1)
        (xy 3.376 6.111)
        (xy 3.355 6.122)
        (xy 3.334 6.13)
        (xy 3.313 6.138)
        (xy 3.289 6.145)
        (xy 3.267 6.151)
        (xy 3.245 6.156)
        (xy 3.221 6.159)
        (xy 3.197 6.159)
        (xy 3.174 6.161)
        (xy 3.15 6.159)
        (xy 3.126 6.159)
        (xy 3.104 6.156)
        (xy 3.08 6.151)
        (xy 3.059 6.145)
        (xy 3.036 6.138)
        (xy 3.015 6.132)
        (xy 2.992 6.122)
        (xy 2.971 6.112)
        (xy 2.951 6.101)
        (xy 2.931 6.088)
        (xy 2.912 6.076)
        (xy 2.894 6.061)
        (xy 2.876 6.047)
        (xy 2.859 6.031)
        (xy 2.843 6.013)
        (xy 2.829 5.997)
        (xy 2.814 5.978)
        (xy 2.801 5.959)
        (xy 2.789 5.938)
        (xy 2.777 5.919)
        (xy 2.767 5.898)
        (xy 2.758 5.875)
        (xy 2.751 5.853)
        (xy 2.745 5.832)
        (xy 2.74 5.81)
        (xy 2.734 5.786)
        (xy 2.732 5.763)
        (xy 2.73 5.739)
        (xy 2.729 5.718)
        (xy 3.174 5.718)
        (xy 3.174 5.713)
      )

      (stroke (width 0.001) (type solid)) (fill solid) (layer "B.Paste"))
    (fp_poly
      (pts
        (xy 4.445 -5.717)
        (xy 3.999 -5.717)
        (xy 4.001 -5.738)
        (xy 4.001 -5.762)
        (xy 4.004 -5.785)
        (xy 4.009 -5.809)
        (xy 4.014 -5.831)
        (xy 4.022 -5.852)
        (xy 4.028 -5.874)
        (xy 4.038 -5.897)
        (xy 4.047 -5.918)
        (xy 4.059 -5.937)
        (xy 4.071 -5.958)
        (xy 4.084 -5.977)
        (xy 4.099 -5.996)
        (xy 4.113 -6.012)
        (xy 4.129 -6.03)
        (xy 4.147 -6.046)
        (xy 4.163 -6.06)
        (xy 4.182 -6.075)
        (xy 4.201 -6.087)
        (xy 4.222 -6.1)
        (xy 4.241 -6.111)
        (xy 4.262 -6.121)
        (xy 4.285 -6.131)
        (xy 4.307 -6.137)
        (xy 4.328 -6.144)
        (xy 4.35 -6.15)
        (xy 4.373 -6.155)
        (xy 4.397 -6.158)
        (xy 4.421 -6.158)
        (xy 4.445 -6.16)
        (xy 4.467 -6.158)
        (xy 4.491 -6.158)
        (xy 4.514 -6.155)
        (xy 4.538 -6.15)
        (xy 4.559 -6.144)
        (xy 4.583 -6.137)
        (xy 4.603 -6.129)
        (xy 4.626 -6.121)
        (xy 4.647 -6.11)
        (xy 4.668 -6.099)
        (xy 4.687 -6.087)
        (xy 4.706 -6.075)
        (xy 4.724 -6.06)
        (xy 4.743 -6.046)
        (xy 4.759 -6.03)
        (xy 4.775 -6.012)
        (xy 4.791 -5.994)
        (xy 4.804 -5.977)
        (xy 4.817 -5.956)
        (xy 4.829 -5.937)
        (xy 4.841 -5.916)
        (xy 4.852 -5.895)
        (xy 4.86 -5.873)
        (xy 4.868 -5.852)
        (xy 4.874 -5.829)
        (xy 4.879 -5.807)
        (xy 4.884 -5.785)
        (xy 4.887 -5.761)
        (xy 4.889 -5.738)
        (xy 4.889 -5.714)
        (xy 4.889 -5.692)
        (xy 4.887 -5.668)
        (xy 4.884 -5.644)
        (xy 4.879 -5.621)
        (xy 4.874 -5.599)
        (xy 4.868 -5.576)
        (xy 4.86 -5.555)
        (xy 4.852 -5.533)
        (xy 4.841 -5.512)
        (xy 4.829 -5.491)
        (xy 4.817 -5.472)
        (xy 4.804 -5.453)
        (xy 4.791 -5.434)
        (xy 4.775 -5.416)
        (xy 4.759 -5.4)
        (xy 4.743 -5.384)
        (xy 4.724 -5.368)
        (xy 4.706 -5.355)
        (xy 4.687 -5.341)
        (xy 4.668 -5.329)
        (xy 4.647 -5.318)
        (xy 4.626 -5.307)
        (xy 4.603 -5.299)
        (xy 4.583 -5.291)
        (xy 4.559 -5.285)
        (xy 4.538 -5.28)
        (xy 4.514 -5.275)
        (xy 4.491 -5.272)
        (xy 4.467 -5.27)
        (xy 4.445 -5.269)
        (xy 4.421 -5.27)
        (xy 4.397 -5.272)
        (xy 4.373 -5.275)
        (xy 4.35 -5.28)
        (xy 4.328 -5.285)
        (xy 4.307 -5.291)
        (xy 4.285 -5.299)
        (xy 4.262 -5.307)
        (xy 4.241 -5.317)
        (xy 4.222 -5.328)
        (xy 4.201 -5.341)
        (xy 4.182 -5.355)
        (xy 4.163 -5.368)
        (xy 4.147 -5.384)
        (xy 4.129 -5.4)
        (xy 4.113 -5.416)
        (xy 4.099 -5.434)
        (xy 4.084 -5.453)
        (xy 4.071 -5.472)
        (xy 4.059 -5.491)
        (xy 4.047 -5.511)
        (xy 4.038 -5.533)
        (xy 4.028 -5.554)
        (xy 4.022 -5.576)
        (xy 4.014 -5.599)
        (xy 4.009 -5.621)
        (xy 4.004 -5.644)
        (xy 4.001 -5.666)
        (xy 4.001 -5.69)
        (xy 3.999 -5.712)
        (xy 4.445 -5.712)
        (xy 4.445 -5.717)
      )

      (stroke (width 0.001) (type solid)) (fill solid) (layer "B.Paste"))
    (fp_poly
      (pts
        (xy 4.445 -3.177)
        (xy 3.999 -3.177)
        (xy 4.001 -3.198)
        (xy 4.001 -3.222)
        (xy 4.004 -3.245)
        (xy 4.009 -3.269)
        (xy 4.014 -3.29)
        (xy 4.022 -3.313)
        (xy 4.028 -3.334)
        (xy 4.038 -3.357)
        (xy 4.047 -3.378)
        (xy 4.059 -3.398)
        (xy 4.071 -3.418)
        (xy 4.084 -3.436)
        (xy 4.099 -3.455)
        (xy 4.113 -3.472)
        (xy 4.129 -3.49)
        (xy 4.147 -3.505)
        (xy 4.163 -3.52)
        (xy 4.182 -3.535)
        (xy 4.201 -3.547)
        (xy 4.222 -3.56)
        (xy 4.241 -3.571)
        (xy 4.262 -3.581)
        (xy 4.285 -3.591)
        (xy 4.307 -3.597)
        (xy 4.328 -3.604)
        (xy 4.35 -3.609)
        (xy 4.373 -3.615)
        (xy 4.397 -3.617)
        (xy 4.421 -3.619)
        (xy 4.445 -3.62)
        (xy 4.467 -3.619)
        (xy 4.491 -3.617)
        (xy 4.514 -3.615)
        (xy 4.538 -3.609)
        (xy 4.559 -3.604)
        (xy 4.583 -3.597)
        (xy 4.603 -3.589)
        (xy 4.626 -3.581)
        (xy 4.647 -3.571)
        (xy 4.668 -3.559)
        (xy 4.687 -3.547)
        (xy 4.706 -3.535)
        (xy 4.724 -3.52)
        (xy 4.743 -3.505)
        (xy 4.759 -3.49)
        (xy 4.775 -3.472)
        (xy 4.791 -3.454)
        (xy 4.804 -3.436)
        (xy 4.817 -3.416)
        (xy 4.829 -3.396)
        (xy 4.841 -3.376)
        (xy 4.852 -3.355)
        (xy 4.86 -3.334)
        (xy 4.868 -3.313)
        (xy 4.874 -3.289)
        (xy 4.879 -3.267)
        (xy 4.884 -3.245)
        (xy 4.887 -3.221)
        (xy 4.889 -3.197)
        (xy 4.889 -3.174)
        (xy 4.889 -3.152)
        (xy 4.887 -3.128)
        (xy 4.884 -3.104)
        (xy 4.879 -3.081)
        (xy 4.874 -3.059)
        (xy 4.868 -3.036)
        (xy 4.86 -3.015)
        (xy 4.852 -2.994)
        (xy 4.841 -2.972)
        (xy 4.829 -2.951)
        (xy 4.817 -2.932)
        (xy 4.804 -2.912)
        (xy 4.791 -2.894)
        (xy 4.775 -2.876)
        (xy 4.759 -2.859)
        (xy 4.743 -2.843)
        (xy 4.724 -2.829)
        (xy 4.706 -2.814)
        (xy 4.687 -2.801)
        (xy 4.668 -2.789)
        (xy 4.647 -2.778)
        (xy 4.626 -2.767)
        (xy 4.603 -2.759)
        (xy 4.583 -2.751)
        (xy 4.559 -2.745)
        (xy 4.538 -2.74)
        (xy 4.514 -2.734)
        (xy 4.491 -2.732)
        (xy 4.467 -2.73)
        (xy 4.445 -2.729)
        (xy 4.421 -2.73)
        (xy 4.397 -2.732)
        (xy 4.373 -2.734)
        (xy 4.35 -2.74)
        (xy 4.328 -2.745)
        (xy 4.307 -2.751)
        (xy 4.285 -2.758)
        (xy 4.262 -2.767)
        (xy 4.241 -2.777)
        (xy 4.222 -2.789)
        (xy 4.201 -2.801)
        (xy 4.182 -2.814)
        (xy 4.163 -2.829)
        (xy 4.147 -2.843)
        (xy 4.129 -2.859)
        (xy 4.113 -2.876)
        (xy 4.099 -2.894)
        (xy 4.084 -2.912)
        (xy 4.071 -2.931)
        (xy 4.059 -2.951)
        (xy 4.047 -2.971)
        (xy 4.038 -2.992)
        (xy 4.028 -3.015)
        (xy 4.022 -3.036)
        (xy 4.014 -3.059)
        (xy 4.009 -3.08)
        (xy 4.004 -3.104)
        (xy 4.001 -3.126)
        (xy 4.001 -3.15)
        (xy 3.999 -3.172)
        (xy 4.445 -3.172)
        (xy 4.445 -3.177)
      )

      (stroke (width 0.001) (type solid)) (fill solid) (layer "B.Paste"))
    (fp_poly
      (pts
        (xy 4.445 1.903)
        (xy 3.999 1.903)
        (xy 4.001 1.881)
        (xy 4.001 1.857)
        (xy 4.004 1.835)
        (xy 4.009 1.811)
        (xy 4.014 1.789)
        (xy 4.022 1.767)
        (xy 4.028 1.746)
        (xy 4.038 1.724)
        (xy 4.047 1.702)
        (xy 4.059 1.682)
        (xy 4.071 1.662)
        (xy 4.084 1.643)
        (xy 4.099 1.625)
        (xy 4.113 1.607)
        (xy 4.129 1.591)
        (xy 4.147 1.575)
        (xy 4.163 1.559)
        (xy 4.182 1.545)
        (xy 4.201 1.532)
        (xy 4.222 1.519)
        (xy 4.241 1.508)
        (xy 4.262 1.498)
        (xy 4.285 1.49)
        (xy 4.307 1.482)
        (xy 4.328 1.476)
        (xy 4.35 1.47)
        (xy 4.373 1.466)
        (xy 4.397 1.462)
        (xy 4.421 1.462)
        (xy 4.445 1.46)
        (xy 4.467 1.462)
        (xy 4.491 1.462)
        (xy 4.514 1.466)
        (xy 4.538 1.47)
        (xy 4.559 1.476)
        (xy 4.583 1.482)
        (xy 4.603 1.49)
        (xy 4.626 1.498)
        (xy 4.647 1.509)
        (xy 4.668 1.52)
        (xy 4.687 1.532)
        (xy 4.706 1.545)
        (xy 4.724 1.559)
        (xy 4.743 1.575)
        (xy 4.759 1.591)
        (xy 4.775 1.607)
        (xy 4.791 1.625)
        (xy 4.804 1.643)
        (xy 4.817 1.663)
        (xy 4.829 1.682)
        (xy 4.841 1.704)
        (xy 4.852 1.724)
        (xy 4.86 1.746)
        (xy 4.868 1.767)
        (xy 4.874 1.79)
        (xy 4.879 1.813)
        (xy 4.884 1.835)
        (xy 4.887 1.859)
        (xy 4.889 1.882)
        (xy 4.889 1.905)
        (xy 4.889 1.928)
        (xy 4.887 1.952)
        (xy 4.884 1.976)
        (xy 4.879 1.998)
        (xy 4.874 2.02)
        (xy 4.868 2.044)
        (xy 4.86 2.065)
        (xy 4.852 2.086)
        (xy 4.841 2.108)
        (xy 4.829 2.127)
        (xy 4.817 2.147)
        (xy 4.804 2.167)
        (xy 4.791 2.186)
        (xy 4.775 2.203)
        (xy 4.759 2.221)
        (xy 4.743 2.237)
        (xy 4.724 2.251)
        (xy 4.706 2.266)
        (xy 4.687 2.278)
        (xy 4.668 2.29)
        (xy 4.647 2.302)
        (xy 4.626 2.312)
        (xy 4.603 2.32)
        (xy 4.583 2.328)
        (xy 4.559 2.335)
        (xy 4.538 2.34)
        (xy 4.514 2.346)
        (xy 4.491 2.348)
        (xy 4.467 2.35)
        (xy 4.445 2.351)
        (xy 4.421 2.35)
        (xy 4.397 2.348)
        (xy 4.373 2.346)
        (xy 4.35 2.34)
        (xy 4.328 2.335)
        (xy 4.307 2.328)
        (xy 4.285 2.322)
        (xy 4.262 2.312)
        (xy 4.241 2.302)
        (xy 4.222 2.291)
        (xy 4.201 2.278)
        (xy 4.182 2.266)
        (xy 4.163 2.251)
        (xy 4.147 2.237)
        (xy 4.129 2.221)
        (xy 4.113 2.203)
        (xy 4.099 2.186)
        (xy 4.084 2.167)
        (xy 4.071 2.149)
        (xy 4.059 2.129)
        (xy 4.047 2.109)
        (xy 4.038 2.088)
        (xy 4.028 2.065)
        (xy 4.022 2.044)
        (xy 4.014 2.021)
        (xy 4.009 2)
        (xy 4.004 1.976)
        (xy 4.001 1.954)
        (xy 4.001 1.93)
        (xy 3.999 1.907)
        (xy 4.445 1.907)
        (xy 4.445 1.903)
      )

      (stroke (width 0.001) (type solid)) (fill solid) (layer "B.Paste"))
    (fp_poly
      (pts
        (xy 4.445 3.173)
        (xy 3.999 3.173)
        (xy 4.001 3.151)
        (xy 4.001 3.127)
        (xy 4.004 3.105)
        (xy 4.009 3.081)
        (xy 4.014 3.06)
        (xy 4.022 3.037)
        (xy 4.028 3.016)
        (xy 4.038 2.993)
        (xy 4.047 2.972)
        (xy 4.059 2.952)
        (xy 4.071 2.932)
        (xy 4.084 2.913)
        (xy 4.099 2.895)
        (xy 4.113 2.877)
        (xy 4.129 2.86)
        (xy 4.147 2.844)
        (xy 4.163 2.83)
        (xy 4.182 2.815)
        (xy 4.201 2.802)
        (xy 4.222 2.79)
        (xy 4.241 2.778)
        (xy 4.262 2.768)
        (xy 4.285 2.759)
        (xy 4.307 2.752)
        (xy 4.328 2.746)
        (xy 4.35 2.741)
        (xy 4.373 2.735)
        (xy 4.397 2.733)
        (xy 4.421 2.731)
        (xy 4.445 2.73)
        (xy 4.467 2.731)
        (xy 4.491 2.733)
        (xy 4.514 2.735)
        (xy 4.538 2.741)
        (xy 4.559 2.746)
        (xy 4.583 2.752)
        (xy 4.603 2.76)
        (xy 4.626 2.768)
        (xy 4.647 2.779)
        (xy 4.668 2.79)
        (xy 4.687 2.802)
        (xy 4.706 2.815)
        (xy 4.724 2.83)
        (xy 4.743 2.844)
        (xy 4.759 2.86)
        (xy 4.775 2.877)
        (xy 4.791 2.895)
        (xy 4.804 2.913)
        (xy 4.817 2.933)
        (xy 4.829 2.952)
        (xy 4.841 2.973)
        (xy 4.852 2.995)
        (xy 4.86 3.016)
        (xy 4.868 3.037)
        (xy 4.874 3.06)
        (xy 4.879 3.082)
        (xy 4.884 3.105)
        (xy 4.887 3.129)
        (xy 4.889 3.153)
        (xy 4.889 3.175)
        (xy 4.889 3.198)
        (xy 4.887 3.222)
        (xy 4.884 3.246)
        (xy 4.879 3.268)
        (xy 4.874 3.29)
        (xy 4.868 3.314)
        (xy 4.86 3.335)
        (xy 4.852 3.356)
        (xy 4.841 3.377)
        (xy 4.829 3.397)
        (xy 4.817 3.417)
        (xy 4.804 3.437)
        (xy 4.791 3.455)
        (xy 4.775 3.473)
        (xy 4.759 3.491)
        (xy 4.743 3.506)
        (xy 4.724 3.521)
        (xy 4.706 3.536)
        (xy 4.687 3.548)
        (xy 4.668 3.56)
        (xy 4.647 3.572)
        (xy 4.626 3.582)
        (xy 4.603 3.59)
        (xy 4.583 3.598)
        (xy 4.559 3.605)
        (xy 4.538 3.61)
        (xy 4.514 3.616)
        (xy 4.491 3.618)
        (xy 4.467 3.62)
        (xy 4.445 3.621)
        (xy 4.421 3.62)
        (xy 4.397 3.618)
        (xy 4.373 3.616)
        (xy 4.35 3.61)
        (xy 4.328 3.605)
        (xy 4.307 3.598)
        (xy 4.285 3.592)
        (xy 4.262 3.582)
        (xy 4.241 3.572)
        (xy 4.222 3.561)
        (xy 4.201 3.548)
        (xy 4.182 3.536)
        (xy 4.163 3.521)
        (xy 4.147 3.506)
        (xy 4.129 3.491)
        (xy 4.113 3.473)
        (xy 4.099 3.456)
        (xy 4.084 3.437)
        (xy 4.071 3.419)
        (xy 4.059 3.399)
        (xy 4.047 3.379)
        (xy 4.038 3.358)
        (xy 4.028 3.335)
        (xy 4.022 3.314)
        (xy 4.014 3.291)
        (xy 4.009 3.27)
        (xy 4.004 3.246)
        (xy 4.001 3.223)
        (xy 4.001 3.199)
        (xy 3.999 3.178)
        (xy 4.445 3.178)
        (xy 4.445 3.173)
      )

      (stroke (width 0.001) (type solid)) (fill solid) (layer "B.Paste"))
    (fp_poly
      (pts
        (xy 4.445 4.443)
        (xy 3.999 4.443)
        (xy 4.001 4.422)
        (xy 4.001 4.398)
        (xy 4.004 4.374)
        (xy 4.009 4.351)
        (xy 4.014 4.329)
        (xy 4.022 4.308)
        (xy 4.028 4.286)
        (xy 4.038 4.263)
        (xy 4.047 4.242)
        (xy 4.059 4.223)
        (xy 4.071 4.202)
        (xy 4.084 4.183)
        (xy 4.099 4.164)
        (xy 4.113 4.148)
        (xy 4.129 4.13)
        (xy 4.147 4.114)
        (xy 4.163 4.1)
        (xy 4.182 4.085)
        (xy 4.201 4.072)
        (xy 4.222 4.06)
        (xy 4.241 4.048)
        (xy 4.262 4.039)
        (xy 4.285 4.029)
        (xy 4.307 4.023)
        (xy 4.328 4.015)
        (xy 4.35 4.01)
        (xy 4.373 4.005)
        (xy 4.397 4.002)
        (xy 4.421 4.002)
        (xy 4.445 4)
        (xy 4.467 4.002)
        (xy 4.491 4.002)
        (xy 4.514 4.005)
        (xy 4.538 4.01)
        (xy 4.559 4.015)
        (xy 4.583 4.023)
        (xy 4.603 4.031)
        (xy 4.626 4.039)
        (xy 4.647 4.05)
        (xy 4.668 4.06)
        (xy 4.687 4.072)
        (xy 4.706 4.085)
        (xy 4.724 4.1)
        (xy 4.743 4.114)
        (xy 4.759 4.13)
        (xy 4.775 4.148)
        (xy 4.791 4.165)
        (xy 4.804 4.183)
        (xy 4.817 4.204)
        (xy 4.829 4.223)
        (xy 4.841 4.244)
        (xy 4.852 4.265)
        (xy 4.86 4.286)
        (xy 4.868 4.308)
        (xy 4.874 4.33)
        (xy 4.879 4.353)
        (xy 4.884 4.375)
        (xy 4.887 4.398)
        (xy 4.889 4.422)
        (xy 4.889 4.446)
        (xy 4.889 4.468)
        (xy 4.887 4.492)
        (xy 4.884 4.515)
        (xy 4.879 4.539)
        (xy 4.874 4.56)
        (xy 4.868 4.584)
        (xy 4.86 4.604)
        (xy 4.852 4.627)
        (xy 4.841 4.648)
        (xy 4.829 4.669)
        (xy 4.817 4.688)
        (xy 4.804 4.707)
        (xy 4.791 4.725)
        (xy 4.775 4.744)
        (xy 4.759 4.76)
        (xy 4.743 4.776)
        (xy 4.724 4.792)
        (xy 4.706 4.805)
        (xy 4.687 4.818)
        (xy 4.668 4.83)
        (xy 4.647 4.842)
        (xy 4.626 4.853)
        (xy 4.603 4.861)
        (xy 4.583 4.869)
        (xy 4.559 4.875)
        (xy 4.538 4.88)
        (xy 4.514 4.885)
        (xy 4.491 4.888)
        (xy 4.467 4.89)
        (xy 4.445 4.89)
        (xy 4.421 4.89)
        (xy 4.397 4.888)
        (xy 4.373 4.885)
        (xy 4.35 4.88)
        (xy 4.328 4.875)
        (xy 4.307 4.869)
        (xy 4.285 4.861)
        (xy 4.262 4.853)
        (xy 4.241 4.842)
        (xy 4.222 4.832)
        (xy 4.201 4.818)
        (xy 4.182 4.805)
        (xy 4.163 4.792)
        (xy 4.147 4.776)
        (xy 4.129 4.76)
        (xy 4.113 4.744)
        (xy 4.099 4.726)
        (xy 4.084 4.707)
        (xy 4.071 4.688)
        (xy 4.059 4.669)
        (xy 4.047 4.648)
        (xy 4.038 4.627)
        (xy 4.028 4.606)
        (xy 4.022 4.584)
        (xy 4.014 4.561)
        (xy 4.009 4.539)
        (xy 4.004 4.516)
        (xy 4.001 4.494)
        (xy 4.001 4.47)
        (xy 3.999 4.447)
        (xy 4.445 4.447)
        (xy 4.445 4.443)
      )

      (stroke (width 0.001) (type solid)) (fill solid) (layer "B.Paste"))
    (fp_poly
      (pts
        (xy 4.445 5.713)
        (xy 3.999 5.713)
        (xy 4.001 5.691)
        (xy 4.001 5.667)
        (xy 4.004 5.645)
        (xy 4.009 5.622)
        (xy 4.014 5.6)
        (xy 4.022 5.577)
        (xy 4.028 5.555)
        (xy 4.038 5.534)
        (xy 4.047 5.512)
        (xy 4.059 5.492)
        (xy 4.071 5.473)
        (xy 4.084 5.454)
        (xy 4.099 5.435)
        (xy 4.113 5.417)
        (xy 4.129 5.401)
        (xy 4.147 5.385)
        (xy 4.163 5.369)
        (xy 4.182 5.356)
        (xy 4.201 5.342)
        (xy 4.222 5.329)
        (xy 4.241 5.318)
        (xy 4.262 5.308)
        (xy 4.285 5.3)
        (xy 4.307 5.292)
        (xy 4.328 5.286)
        (xy 4.35 5.281)
        (xy 4.373 5.276)
        (xy 4.397 5.273)
        (xy 4.421 5.271)
        (xy 4.445 5.27)
        (xy 4.467 5.271)
        (xy 4.491 5.273)
        (xy 4.514 5.276)
        (xy 4.538 5.281)
        (xy 4.559 5.286)
        (xy 4.583 5.292)
        (xy 4.603 5.3)
        (xy 4.626 5.308)
        (xy 4.647 5.319)
        (xy 4.668 5.33)
        (xy 4.687 5.342)
        (xy 4.706 5.356)
        (xy 4.724 5.369)
        (xy 4.743 5.385)
        (xy 4.759 5.401)
        (xy 4.775 5.417)
        (xy 4.791 5.435)
        (xy 4.804 5.454)
        (xy 4.817 5.473)
        (xy 4.829 5.492)
        (xy 4.841 5.513)
        (xy 4.852 5.534)
        (xy 4.86 5.556)
        (xy 4.868 5.577)
        (xy 4.874 5.6)
        (xy 4.879 5.622)
        (xy 4.884 5.645)
        (xy 4.887 5.669)
        (xy 4.889 5.693)
        (xy 4.889 5.715)
        (xy 4.889 5.739)
        (xy 4.887 5.762)
        (xy 4.884 5.786)
        (xy 4.879 5.808)
        (xy 4.874 5.83)
        (xy 4.868 5.853)
        (xy 4.86 5.874)
        (xy 4.852 5.896)
        (xy 4.841 5.917)
        (xy 4.829 5.938)
        (xy 4.817 5.957)
        (xy 4.804 5.978)
        (xy 4.791 5.995)
        (xy 4.775 6.013)
        (xy 4.759 6.031)
        (xy 4.743 6.047)
        (xy 4.724 6.061)
        (xy 4.706 6.076)
        (xy 4.687 6.088)
        (xy 4.668 6.1)
        (xy 4.647 6.111)
        (xy 4.626 6.122)
        (xy 4.603 6.13)
        (xy 4.583 6.138)
        (xy 4.559 6.145)
        (xy 4.538 6.151)
        (xy 4.514 6.156)
        (xy 4.491 6.159)
        (xy 4.467 6.159)
        (xy 4.445 6.161)
        (xy 4.421 6.159)
        (xy 4.397 6.159)
        (xy 4.373 6.156)
        (xy 4.35 6.151)
        (xy 4.328 6.145)
        (xy 4.307 6.138)
        (xy 4.285 6.132)
        (xy 4.262 6.122)
        (xy 4.241 6.112)
        (xy 4.222 6.101)
        (xy 4.201 6.088)
        (xy 4.182 6.076)
        (xy 4.163 6.061)
        (xy 4.147 6.047)
        (xy 4.129 6.031)
        (xy 4.113 6.013)
        (xy 4.099 5.997)
        (xy 4.084 5.978)
        (xy 4.071 5.959)
        (xy 4.059 5.938)
        (xy 4.047 5.919)
        (xy 4.038 5.898)
        (xy 4.028 5.875)
        (xy 4.022 5.853)
        (xy 4.014 5.832)
        (xy 4.009 5.81)
        (xy 4.004 5.786)
        (xy 4.001 5.763)
        (xy 4.001 5.739)
        (xy 3.999 5.718)
        (xy 4.445 5.718)
        (xy 4.445 5.713)
      )

      (stroke (width 0.001) (type solid)) (fill solid) (layer "B.Paste"))
    (fp_poly
      (pts
        (xy 5.714 -5.717)
        (xy 5.269 -5.717)
        (xy 5.27 -5.738)
        (xy 5.272 -5.762)
        (xy 5.275 -5.785)
        (xy 5.28 -5.809)
        (xy 5.285 -5.831)
        (xy 5.291 -5.852)
        (xy 5.299 -5.874)
        (xy 5.307 -5.897)
        (xy 5.317 -5.918)
        (xy 5.328 -5.937)
        (xy 5.341 -5.958)
        (xy 5.355 -5.977)
        (xy 5.368 -5.996)
        (xy 5.384 -6.012)
        (xy 5.4 -6.03)
        (xy 5.416 -6.046)
        (xy 5.434 -6.06)
        (xy 5.453 -6.075)
        (xy 5.472 -6.087)
        (xy 5.491 -6.1)
        (xy 5.511 -6.111)
        (xy 5.533 -6.121)
        (xy 5.554 -6.131)
        (xy 5.576 -6.137)
        (xy 5.599 -6.144)
        (xy 5.621 -6.15)
        (xy 5.644 -6.155)
        (xy 5.666 -6.158)
        (xy 5.69 -6.158)
        (xy 5.714 -6.16)
        (xy 5.738 -6.158)
        (xy 5.761 -6.158)
        (xy 5.785 -6.155)
        (xy 5.807 -6.15)
        (xy 5.829 -6.144)
        (xy 5.852 -6.137)
        (xy 5.873 -6.129)
        (xy 5.895 -6.121)
        (xy 5.916 -6.11)
        (xy 5.937 -6.099)
        (xy 5.956 -6.087)
        (xy 5.977 -6.075)
        (xy 5.994 -6.06)
        (xy 6.012 -6.046)
        (xy 6.03 -6.03)
        (xy 6.046 -6.012)
        (xy 6.06 -5.994)
        (xy 6.075 -5.977)
        (xy 6.087 -5.956)
        (xy 6.099 -5.937)
        (xy 6.11 -5.916)
        (xy 6.121 -5.895)
        (xy 6.129 -5.873)
        (xy 6.137 -5.852)
        (xy 6.144 -5.829)
        (xy 6.15 -5.807)
        (xy 6.155 -5.785)
        (xy 6.158 -5.761)
        (xy 6.158 -5.738)
        (xy 6.16 -5.714)
        (xy 6.158 -5.692)
        (xy 6.158 -5.668)
        (xy 6.155 -5.644)
        (xy 6.15 -5.621)
        (xy 6.144 -5.599)
        (xy 6.137 -5.576)
        (xy 6.129 -5.555)
        (xy 6.121 -5.533)
        (xy 6.11 -5.512)
        (xy 6.099 -5.491)
        (xy 6.087 -5.472)
        (xy 6.075 -5.453)
        (xy 6.06 -5.434)
        (xy 6.046 -5.416)
        (xy 6.03 -5.4)
        (xy 6.012 -5.384)
        (xy 5.994 -5.368)
        (xy 5.977 -5.355)
        (xy 5.956 -5.341)
        (xy 5.937 -5.329)
        (xy 5.916 -5.318)
        (xy 5.895 -5.307)
        (xy 5.873 -5.299)
        (xy 5.852 -5.291)
        (xy 5.829 -5.285)
        (xy 5.807 -5.28)
        (xy 5.785 -5.275)
        (xy 5.761 -5.272)
        (xy 5.738 -5.27)
        (xy 5.714 -5.269)
        (xy 5.69 -5.27)
        (xy 5.666 -5.272)
        (xy 5.644 -5.275)
        (xy 5.621 -5.28)
        (xy 5.599 -5.285)
        (xy 5.576 -5.291)
        (xy 5.554 -5.299)
        (xy 5.533 -5.307)
        (xy 5.511 -5.317)
        (xy 5.491 -5.328)
        (xy 5.472 -5.341)
        (xy 5.453 -5.355)
        (xy 5.434 -5.368)
        (xy 5.416 -5.384)
        (xy 5.4 -5.4)
        (xy 5.384 -5.416)
        (xy 5.368 -5.434)
        (xy 5.355 -5.453)
        (xy 5.341 -5.472)
        (xy 5.328 -5.491)
        (xy 5.317 -5.511)
        (xy 5.307 -5.533)
        (xy 5.299 -5.554)
        (xy 5.291 -5.576)
        (xy 5.285 -5.599)
        (xy 5.28 -5.621)
        (xy 5.275 -5.644)
        (xy 5.272 -5.666)
        (xy 5.27 -5.69)
        (xy 5.269 -5.712)
        (xy 5.714 -5.712)
        (xy 5.714 -5.717)
      )

      (stroke (width 0.001) (type solid)) (fill solid) (layer "B.Paste"))
    (fp_poly
      (pts
        (xy 5.714 -3.177)
        (xy 5.269 -3.177)
        (xy 5.27 -3.198)
        (xy 5.272 -3.222)
        (xy 5.275 -3.245)
        (xy 5.28 -3.269)
        (xy 5.285 -3.29)
        (xy 5.291 -3.313)
        (xy 5.299 -3.334)
        (xy 5.307 -3.357)
        (xy 5.317 -3.378)
        (xy 5.328 -3.398)
        (xy 5.341 -3.418)
        (xy 5.355 -3.436)
        (xy 5.368 -3.455)
        (xy 5.384 -3.472)
        (xy 5.4 -3.49)
        (xy 5.416 -3.505)
        (xy 5.434 -3.52)
        (xy 5.453 -3.535)
        (xy 5.472 -3.547)
        (xy 5.491 -3.56)
        (xy 5.511 -3.571)
        (xy 5.533 -3.581)
        (xy 5.554 -3.591)
        (xy 5.576 -3.597)
        (xy 5.599 -3.604)
        (xy 5.621 -3.609)
        (xy 5.644 -3.615)
        (xy 5.666 -3.617)
        (xy 5.69 -3.619)
        (xy 5.714 -3.62)
        (xy 5.738 -3.619)
        (xy 5.761 -3.617)
        (xy 5.785 -3.615)
        (xy 5.807 -3.609)
        (xy 5.829 -3.604)
        (xy 5.852 -3.597)
        (xy 5.873 -3.589)
        (xy 5.895 -3.581)
        (xy 5.916 -3.571)
        (xy 5.937 -3.559)
        (xy 5.956 -3.547)
        (xy 5.977 -3.535)
        (xy 5.994 -3.52)
        (xy 6.012 -3.505)
        (xy 6.03 -3.49)
        (xy 6.046 -3.472)
        (xy 6.06 -3.454)
        (xy 6.075 -3.436)
        (xy 6.087 -3.416)
        (xy 6.099 -3.396)
        (xy 6.11 -3.376)
        (xy 6.121 -3.355)
        (xy 6.129 -3.334)
        (xy 6.137 -3.313)
        (xy 6.144 -3.289)
        (xy 6.15 -3.267)
        (xy 6.155 -3.245)
        (xy 6.158 -3.221)
        (xy 6.158 -3.197)
        (xy 6.16 -3.174)
        (xy 6.158 -3.152)
        (xy 6.158 -3.128)
        (xy 6.155 -3.104)
        (xy 6.15 -3.081)
        (xy 6.144 -3.059)
        (xy 6.137 -3.036)
        (xy 6.129 -3.015)
        (xy 6.121 -2.994)
        (xy 6.11 -2.972)
        (xy 6.099 -2.951)
        (xy 6.087 -2.932)
        (xy 6.075 -2.912)
        (xy 6.06 -2.894)
        (xy 6.046 -2.876)
        (xy 6.03 -2.859)
        (xy 6.012 -2.843)
        (xy 5.994 -2.829)
        (xy 5.977 -2.814)
        (xy 5.956 -2.801)
        (xy 5.937 -2.789)
        (xy 5.916 -2.778)
        (xy 5.895 -2.767)
        (xy 5.873 -2.759)
        (xy 5.852 -2.751)
        (xy 5.829 -2.745)
        (xy 5.807 -2.74)
        (xy 5.785 -2.734)
        (xy 5.761 -2.732)
        (xy 5.738 -2.73)
        (xy 5.714 -2.729)
        (xy 5.69 -2.73)
        (xy 5.666 -2.732)
        (xy 5.644 -2.734)
        (xy 5.621 -2.74)
        (xy 5.599 -2.745)
        (xy 5.576 -2.751)
        (xy 5.554 -2.758)
        (xy 5.533 -2.767)
        (xy 5.511 -2.777)
        (xy 5.491 -2.789)
        (xy 5.472 -2.801)
        (xy 5.453 -2.814)
        (xy 5.434 -2.829)
        (xy 5.416 -2.843)
        (xy 5.4 -2.859)
        (xy 5.384 -2.876)
        (xy 5.368 -2.894)
        (xy 5.355 -2.912)
        (xy 5.341 -2.931)
        (xy 5.328 -2.951)
        (xy 5.317 -2.971)
        (xy 5.307 -2.992)
        (xy 5.299 -3.015)
        (xy 5.291 -3.036)
        (xy 5.285 -3.059)
        (xy 5.28 -3.08)
        (xy 5.275 -3.104)
        (xy 5.272 -3.126)
        (xy 5.27 -3.15)
        (xy 5.269 -3.172)
        (xy 5.714 -3.172)
        (xy 5.714 -3.177)
      )

      (stroke (width 0.001) (type solid)) (fill solid) (layer "B.Paste"))
    (fp_poly
      (pts
        (xy 5.714 1.903)
        (xy 5.269 1.903)
        (xy 5.27 1.881)
        (xy 5.272 1.857)
        (xy 5.275 1.835)
        (xy 5.28 1.811)
        (xy 5.285 1.789)
        (xy 5.291 1.767)
        (xy 5.299 1.746)
        (xy 5.307 1.724)
        (xy 5.317 1.702)
        (xy 5.328 1.682)
        (xy 5.341 1.662)
        (xy 5.355 1.643)
        (xy 5.368 1.625)
        (xy 5.384 1.607)
        (xy 5.4 1.591)
        (xy 5.416 1.575)
        (xy 5.434 1.559)
        (xy 5.453 1.545)
        (xy 5.472 1.532)
        (xy 5.491 1.519)
        (xy 5.511 1.508)
        (xy 5.533 1.498)
        (xy 5.554 1.49)
        (xy 5.576 1.482)
        (xy 5.599 1.476)
        (xy 5.621 1.47)
        (xy 5.644 1.466)
        (xy 5.666 1.462)
        (xy 5.69 1.462)
        (xy 5.714 1.46)
        (xy 5.738 1.462)
        (xy 5.761 1.462)
        (xy 5.785 1.466)
        (xy 5.807 1.47)
        (xy 5.829 1.476)
        (xy 5.852 1.482)
        (xy 5.873 1.49)
        (xy 5.895 1.498)
        (xy 5.916 1.509)
        (xy 5.937 1.52)
        (xy 5.956 1.532)
        (xy 5.977 1.545)
        (xy 5.994 1.559)
        (xy 6.012 1.575)
        (xy 6.03 1.591)
        (xy 6.046 1.607)
        (xy 6.06 1.625)
        (xy 6.075 1.643)
        (xy 6.087 1.663)
        (xy 6.099 1.684)
        (xy 6.11 1.704)
        (xy 6.121 1.724)
        (xy 6.129 1.746)
        (xy 6.137 1.767)
        (xy 6.144 1.79)
        (xy 6.15 1.813)
        (xy 6.155 1.835)
        (xy 6.158 1.859)
        (xy 6.158 1.882)
        (xy 6.16 1.905)
        (xy 6.158 1.928)
        (xy 6.158 1.952)
        (xy 6.155 1.976)
        (xy 6.15 1.998)
        (xy 6.144 2.02)
        (xy 6.137 2.044)
        (xy 6.129 2.065)
        (xy 6.121 2.086)
        (xy 6.11 2.108)
        (xy 6.099 2.127)
        (xy 6.087 2.147)
        (xy 6.075 2.167)
        (xy 6.06 2.186)
        (xy 6.046 2.203)
        (xy 6.03 2.221)
        (xy 6.012 2.237)
        (xy 5.994 2.251)
        (xy 5.977 2.266)
        (xy 5.956 2.278)
        (xy 5.937 2.29)
        (xy 5.916 2.302)
        (xy 5.895 2.312)
        (xy 5.873 2.32)
        (xy 5.852 2.328)
        (xy 5.829 2.335)
        (xy 5.807 2.34)
        (xy 5.785 2.346)
        (xy 5.761 2.348)
        (xy 5.738 2.35)
        (xy 5.714 2.351)
        (xy 5.69 2.35)
        (xy 5.666 2.348)
        (xy 5.644 2.346)
        (xy 5.621 2.34)
        (xy 5.599 2.335)
        (xy 5.576 2.328)
        (xy 5.554 2.322)
        (xy 5.533 2.312)
        (xy 5.511 2.302)
        (xy 5.491 2.291)
        (xy 5.472 2.278)
        (xy 5.453 2.266)
        (xy 5.434 2.251)
        (xy 5.416 2.237)
        (xy 5.4 2.221)
        (xy 5.384 2.203)
        (xy 5.368 2.186)
        (xy 5.355 2.167)
        (xy 5.341 2.149)
        (xy 5.328 2.129)
        (xy 5.317 2.109)
        (xy 5.307 2.088)
        (xy 5.299 2.065)
        (xy 5.291 2.044)
        (xy 5.285 2.021)
        (xy 5.28 2)
        (xy 5.275 1.976)
        (xy 5.272 1.954)
        (xy 5.27 1.93)
        (xy 5.269 1.907)
        (xy 5.714 1.907)
        (xy 5.714 1.903)
      )

      (stroke (width 0.001) (type solid)) (fill solid) (layer "B.Paste"))
    (fp_poly
      (pts
        (xy 5.714 3.173)
        (xy 5.269 3.173)
        (xy 5.27 3.151)
        (xy 5.272 3.127)
        (xy 5.275 3.105)
        (xy 5.28 3.081)
        (xy 5.285 3.06)
        (xy 5.291 3.037)
        (xy 5.299 3.016)
        (xy 5.307 2.993)
        (xy 5.317 2.972)
        (xy 5.328 2.952)
        (xy 5.341 2.932)
        (xy 5.355 2.913)
        (xy 5.368 2.895)
        (xy 5.384 2.877)
        (xy 5.4 2.86)
        (xy 5.416 2.844)
        (xy 5.434 2.83)
        (xy 5.453 2.815)
        (xy 5.472 2.802)
        (xy 5.491 2.79)
        (xy 5.511 2.778)
        (xy 5.533 2.768)
        (xy 5.554 2.759)
        (xy 5.576 2.752)
        (xy 5.599 2.746)
        (xy 5.621 2.741)
        (xy 5.644 2.735)
        (xy 5.666 2.733)
        (xy 5.69 2.731)
        (xy 5.714 2.73)
        (xy 5.738 2.731)
        (xy 5.761 2.733)
        (xy 5.785 2.735)
        (xy 5.807 2.741)
        (xy 5.829 2.746)
        (xy 5.852 2.752)
        (xy 5.873 2.76)
        (xy 5.895 2.768)
        (xy 5.916 2.779)
        (xy 5.937 2.79)
        (xy 5.956 2.802)
        (xy 5.977 2.815)
        (xy 5.994 2.83)
        (xy 6.012 2.844)
        (xy 6.03 2.86)
        (xy 6.046 2.877)
        (xy 6.06 2.895)
        (xy 6.075 2.913)
        (xy 6.087 2.933)
        (xy 6.099 2.952)
        (xy 6.11 2.973)
        (xy 6.121 2.995)
        (xy 6.129 3.016)
        (xy 6.137 3.037)
        (xy 6.144 3.06)
        (xy 6.15 3.082)
        (xy 6.155 3.105)
        (xy 6.158 3.129)
        (xy 6.158 3.153)
        (xy 6.16 3.175)
        (xy 6.158 3.198)
        (xy 6.158 3.222)
        (xy 6.155 3.246)
        (xy 6.15 3.268)
        (xy 6.144 3.29)
        (xy 6.137 3.314)
        (xy 6.129 3.335)
        (xy 6.121 3.356)
        (xy 6.11 3.377)
        (xy 6.099 3.397)
        (xy 6.087 3.417)
        (xy 6.075 3.437)
        (xy 6.06 3.455)
        (xy 6.046 3.473)
        (xy 6.03 3.491)
        (xy 6.012 3.506)
        (xy 5.994 3.521)
        (xy 5.977 3.536)
        (xy 5.956 3.548)
        (xy 5.937 3.56)
        (xy 5.916 3.572)
        (xy 5.895 3.582)
        (xy 5.873 3.59)
        (xy 5.852 3.598)
        (xy 5.829 3.605)
        (xy 5.807 3.61)
        (xy 5.785 3.616)
        (xy 5.761 3.618)
        (xy 5.738 3.62)
        (xy 5.714 3.621)
        (xy 5.69 3.62)
        (xy 5.666 3.618)
        (xy 5.644 3.616)
        (xy 5.621 3.61)
        (xy 5.599 3.605)
        (xy 5.576 3.598)
        (xy 5.554 3.592)
        (xy 5.533 3.582)
        (xy 5.511 3.572)
        (xy 5.491 3.561)
        (xy 5.472 3.548)
        (xy 5.453 3.536)
        (xy 5.434 3.521)
        (xy 5.416 3.506)
        (xy 5.4 3.491)
        (xy 5.384 3.473)
        (xy 5.368 3.456)
        (xy 5.355 3.437)
        (xy 5.341 3.419)
        (xy 5.328 3.399)
        (xy 5.317 3.379)
        (xy 5.307 3.358)
        (xy 5.299 3.335)
        (xy 5.291 3.314)
        (xy 5.285 3.291)
        (xy 5.28 3.27)
        (xy 5.275 3.246)
        (xy 5.272 3.223)
        (xy 5.27 3.199)
        (xy 5.269 3.178)
        (xy 5.714 3.178)
        (xy 5.714 3.173)
      )

      (stroke (width 0.001) (type solid)) (fill solid) (layer "B.Paste"))
    (fp_poly
      (pts
        (xy 5.714 4.443)
        (xy 5.269 4.443)
        (xy 5.27 4.422)
        (xy 5.272 4.398)
        (xy 5.275 4.374)
        (xy 5.28 4.351)
        (xy 5.285 4.329)
        (xy 5.291 4.308)
        (xy 5.299 4.286)
        (xy 5.307 4.263)
        (xy 5.317 4.242)
        (xy 5.328 4.223)
        (xy 5.341 4.202)
        (xy 5.355 4.183)
        (xy 5.368 4.164)
        (xy 5.384 4.148)
        (xy 5.4 4.13)
        (xy 5.416 4.114)
        (xy 5.434 4.1)
        (xy 5.453 4.085)
        (xy 5.472 4.072)
        (xy 5.491 4.06)
        (xy 5.511 4.048)
        (xy 5.533 4.039)
        (xy 5.554 4.029)
        (xy 5.576 4.023)
        (xy 5.599 4.015)
        (xy 5.621 4.01)
        (xy 5.644 4.005)
        (xy 5.666 4.002)
        (xy 5.69 4.002)
        (xy 5.714 4)
        (xy 5.738 4.002)
        (xy 5.761 4.002)
        (xy 5.785 4.005)
        (xy 5.807 4.01)
        (xy 5.829 4.015)
        (xy 5.852 4.023)
        (xy 5.873 4.031)
        (xy 5.895 4.039)
        (xy 5.916 4.05)
        (xy 5.937 4.06)
        (xy 5.956 4.072)
        (xy 5.977 4.085)
        (xy 5.994 4.1)
        (xy 6.012 4.114)
        (xy 6.03 4.13)
        (xy 6.046 4.148)
        (xy 6.06 4.165)
        (xy 6.075 4.183)
        (xy 6.087 4.204)
        (xy 6.099 4.223)
        (xy 6.11 4.244)
        (xy 6.121 4.265)
        (xy 6.129 4.286)
        (xy 6.137 4.308)
        (xy 6.144 4.33)
        (xy 6.15 4.353)
        (xy 6.155 4.375)
        (xy 6.158 4.398)
        (xy 6.158 4.422)
        (xy 6.16 4.446)
        (xy 6.158 4.468)
        (xy 6.158 4.492)
        (xy 6.155 4.515)
        (xy 6.15 4.539)
        (xy 6.144 4.56)
        (xy 6.137 4.584)
        (xy 6.129 4.604)
        (xy 6.121 4.627)
        (xy 6.11 4.648)
        (xy 6.099 4.669)
        (xy 6.087 4.688)
        (xy 6.075 4.707)
        (xy 6.06 4.725)
        (xy 6.046 4.744)
        (xy 6.03 4.76)
        (xy 6.012 4.776)
        (xy 5.994 4.792)
        (xy 5.977 4.805)
        (xy 5.956 4.818)
        (xy 5.937 4.83)
        (xy 5.916 4.842)
        (xy 5.895 4.853)
        (xy 5.873 4.861)
        (xy 5.852 4.869)
        (xy 5.829 4.875)
        (xy 5.807 4.88)
        (xy 5.785 4.885)
        (xy 5.761 4.888)
        (xy 5.738 4.89)
        (xy 5.714 4.89)
        (xy 5.69 4.89)
        (xy 5.666 4.888)
        (xy 5.644 4.885)
        (xy 5.621 4.88)
        (xy 5.599 4.875)
        (xy 5.576 4.869)
        (xy 5.554 4.861)
        (xy 5.533 4.853)
        (xy 5.511 4.842)
        (xy 5.491 4.832)
        (xy 5.472 4.818)
        (xy 5.453 4.805)
        (xy 5.434 4.792)
        (xy 5.416 4.776)
        (xy 5.4 4.76)
        (xy 5.384 4.744)
        (xy 5.368 4.726)
        (xy 5.355 4.707)
        (xy 5.341 4.688)
        (xy 5.328 4.669)
        (xy 5.317 4.648)
        (xy 5.307 4.627)
        (xy 5.299 4.606)
        (xy 5.291 4.584)
        (xy 5.285 4.561)
        (xy 5.28 4.539)
        (xy 5.275 4.516)
        (xy 5.272 4.494)
        (xy 5.27 4.47)
        (xy 5.269 4.447)
        (xy 5.714 4.447)
        (xy 5.714 4.443)
      )

      (stroke (width 0.001) (type solid)) (fill solid) (layer "B.Paste"))
    (fp_poly
      (pts
        (xy 5.714 5.713)
        (xy 5.269 5.713)
        (xy 5.27 5.691)
        (xy 5.272 5.667)
        (xy 5.275 5.645)
        (xy 5.28 5.622)
        (xy 5.285 5.6)
        (xy 5.291 5.577)
        (xy 5.299 5.555)
        (xy 5.307 5.534)
        (xy 5.317 5.512)
        (xy 5.328 5.492)
        (xy 5.341 5.473)
        (xy 5.355 5.454)
        (xy 5.368 5.435)
        (xy 5.384 5.417)
        (xy 5.4 5.401)
        (xy 5.416 5.385)
        (xy 5.434 5.369)
        (xy 5.453 5.356)
        (xy 5.472 5.342)
        (xy 5.491 5.329)
        (xy 5.511 5.318)
        (xy 5.533 5.308)
        (xy 5.554 5.3)
        (xy 5.576 5.292)
        (xy 5.599 5.286)
        (xy 5.621 5.281)
        (xy 5.644 5.276)
        (xy 5.666 5.273)
        (xy 5.69 5.271)
        (xy 5.714 5.27)
        (xy 5.738 5.271)
        (xy 5.761 5.273)
        (xy 5.785 5.276)
        (xy 5.807 5.281)
        (xy 5.829 5.286)
        (xy 5.852 5.292)
        (xy 5.873 5.3)
        (xy 5.895 5.308)
        (xy 5.916 5.319)
        (xy 5.937 5.33)
        (xy 5.956 5.342)
        (xy 5.977 5.356)
        (xy 5.994 5.369)
        (xy 6.012 5.385)
        (xy 6.03 5.401)
        (xy 6.046 5.417)
        (xy 6.06 5.435)
        (xy 6.075 5.454)
        (xy 6.087 5.473)
        (xy 6.099 5.492)
        (xy 6.11 5.513)
        (xy 6.121 5.534)
        (xy 6.129 5.556)
        (xy 6.137 5.577)
        (xy 6.144 5.6)
        (xy 6.15 5.622)
        (xy 6.155 5.645)
        (xy 6.158 5.669)
        (xy 6.158 5.693)
        (xy 6.16 5.715)
        (xy 6.158 5.739)
        (xy 6.158 5.762)
        (xy 6.155 5.786)
        (xy 6.15 5.808)
        (xy 6.144 5.83)
        (xy 6.137 5.853)
        (xy 6.129 5.874)
        (xy 6.121 5.896)
        (xy 6.11 5.917)
        (xy 6.099 5.938)
        (xy 6.087 5.957)
        (xy 6.075 5.978)
        (xy 6.06 5.995)
        (xy 6.046 6.013)
        (xy 6.03 6.031)
        (xy 6.012 6.047)
        (xy 5.994 6.061)
        (xy 5.977 6.076)
        (xy 5.956 6.088)
        (xy 5.937 6.1)
        (xy 5.916 6.111)
        (xy 5.895 6.122)
        (xy 5.873 6.13)
        (xy 5.852 6.138)
        (xy 5.829 6.145)
        (xy 5.807 6.151)
        (xy 5.785 6.156)
        (xy 5.761 6.159)
        (xy 5.738 6.159)
        (xy 5.714 6.161)
        (xy 5.69 6.159)
        (xy 5.666 6.159)
        (xy 5.644 6.156)
        (xy 5.621 6.151)
        (xy 5.599 6.145)
        (xy 5.576 6.138)
        (xy 5.554 6.132)
        (xy 5.533 6.122)
        (xy 5.511 6.112)
        (xy 5.491 6.101)
        (xy 5.472 6.088)
        (xy 5.453 6.076)
        (xy 5.434 6.061)
        (xy 5.416 6.047)
        (xy 5.4 6.031)
        (xy 5.384 6.013)
        (xy 5.368 5.997)
        (xy 5.355 5.978)
        (xy 5.341 5.959)
        (xy 5.328 5.938)
        (xy 5.317 5.919)
        (xy 5.307 5.898)
        (xy 5.299 5.875)
        (xy 5.291 5.853)
        (xy 5.285 5.832)
        (xy 5.28 5.81)
        (xy 5.275 5.786)
        (xy 5.272 5.763)
        (xy 5.27 5.739)
        (xy 5.269 5.718)
        (xy 5.714 5.718)
        (xy 5.714 5.713)
      )

      (stroke (width 0.001) (type solid)) (fill solid) (layer "B.Paste"))
    (fp_poly
      (pts
        (xy 6.985 -5.717)
        (xy 6.539 -5.717)
        (xy 6.541 -5.738)
        (xy 6.541 -5.762)
        (xy 6.544 -5.785)
        (xy 6.549 -5.809)
        (xy 6.554 -5.831)
        (xy 6.562 -5.852)
        (xy 6.568 -5.874)
        (xy 6.578 -5.897)
        (xy 6.587 -5.918)
        (xy 6.599 -5.937)
        (xy 6.611 -5.958)
        (xy 6.624 -5.977)
        (xy 6.639 -5.996)
        (xy 6.653 -6.012)
        (xy 6.669 -6.03)
        (xy 6.687 -6.046)
        (xy 6.703 -6.06)
        (xy 6.722 -6.075)
        (xy 6.741 -6.087)
        (xy 6.761 -6.1)
        (xy 6.781 -6.111)
        (xy 6.802 -6.121)
        (xy 6.825 -6.131)
        (xy 6.847 -6.137)
        (xy 6.868 -6.144)
        (xy 6.89 -6.15)
        (xy 6.913 -6.155)
        (xy 6.937 -6.158)
        (xy 6.961 -6.158)
        (xy 6.985 -6.16)
        (xy 7.007 -6.158)
        (xy 7.031 -6.158)
        (xy 7.054 -6.155)
        (xy 7.078 -6.15)
        (xy 7.099 -6.144)
        (xy 7.123 -6.137)
        (xy 7.143 -6.129)
        (xy 7.166 -6.121)
        (xy 7.187 -6.11)
        (xy 7.206 -6.099)
        (xy 7.227 -6.087)
        (xy 7.246 -6.075)
        (xy 7.264 -6.06)
        (xy 7.283 -6.046)
        (xy 7.299 -6.03)
        (xy 7.315 -6.012)
        (xy 7.331 -5.994)
        (xy 7.344 -5.977)
        (xy 7.357 -5.956)
        (xy 7.369 -5.937)
        (xy 7.381 -5.916)
        (xy 7.392 -5.895)
        (xy 7.4 -5.873)
        (xy 7.408 -5.852)
        (xy 7.414 -5.829)
        (xy 7.419 -5.807)
        (xy 7.424 -5.785)
        (xy 7.427 -5.761)
        (xy 7.429 -5.738)
        (xy 7.429 -5.714)
        (xy 7.429 -5.692)
        (xy 7.427 -5.668)
        (xy 7.424 -5.644)
        (xy 7.419 -5.621)
        (xy 7.414 -5.599)
        (xy 7.408 -5.576)
        (xy 7.4 -5.555)
        (xy 7.392 -5.533)
        (xy 7.381 -5.512)
        (xy 7.369 -5.491)
        (xy 7.357 -5.472)
        (xy 7.344 -5.453)
        (xy 7.331 -5.434)
        (xy 7.315 -5.416)
        (xy 7.299 -5.4)
        (xy 7.283 -5.384)
        (xy 7.264 -5.368)
        (xy 7.246 -5.355)
        (xy 7.227 -5.341)
        (xy 7.206 -5.329)
        (xy 7.187 -5.318)
        (xy 7.166 -5.307)
        (xy 7.143 -5.299)
        (xy 7.123 -5.291)
        (xy 7.099 -5.285)
        (xy 7.078 -5.28)
        (xy 7.054 -5.275)
        (xy 7.031 -5.272)
        (xy 7.007 -5.27)
        (xy 6.985 -5.269)
        (xy 6.961 -5.27)
        (xy 6.937 -5.272)
        (xy 6.913 -5.275)
        (xy 6.89 -5.28)
        (xy 6.868 -5.285)
        (xy 6.847 -5.291)
        (xy 6.825 -5.299)
        (xy 6.802 -5.307)
        (xy 6.781 -5.317)
        (xy 6.761 -5.328)
        (xy 6.741 -5.341)
        (xy 6.722 -5.355)
        (xy 6.703 -5.368)
        (xy 6.687 -5.384)
        (xy 6.669 -5.4)
        (xy 6.653 -5.416)
        (xy 6.639 -5.434)
        (xy 6.624 -5.453)
        (xy 6.611 -5.472)
        (xy 6.599 -5.491)
        (xy 6.587 -5.511)
        (xy 6.578 -5.533)
        (xy 6.568 -5.554)
        (xy 6.562 -5.576)
        (xy 6.554 -5.599)
        (xy 6.549 -5.621)
        (xy 6.544 -5.644)
        (xy 6.541 -5.666)
        (xy 6.541 -5.69)
        (xy 6.539 -5.712)
        (xy 6.985 -5.712)
        (xy 6.985 -5.717)
      )

      (stroke (width 0.001) (type solid)) (fill solid) (layer "B.Paste"))
    (fp_poly
      (pts
        (xy 6.985 -3.177)
        (xy 6.539 -3.177)
        (xy 6.541 -3.198)
        (xy 6.541 -3.222)
        (xy 6.544 -3.245)
        (xy 6.549 -3.269)
        (xy 6.554 -3.29)
        (xy 6.562 -3.313)
        (xy 6.568 -3.334)
        (xy 6.578 -3.357)
        (xy 6.587 -3.378)
        (xy 6.599 -3.398)
        (xy 6.611 -3.418)
        (xy 6.624 -3.436)
        (xy 6.639 -3.455)
        (xy 6.653 -3.472)
        (xy 6.669 -3.49)
        (xy 6.687 -3.505)
        (xy 6.703 -3.52)
        (xy 6.722 -3.535)
        (xy 6.741 -3.547)
        (xy 6.761 -3.56)
        (xy 6.781 -3.571)
        (xy 6.802 -3.581)
        (xy 6.825 -3.591)
        (xy 6.847 -3.597)
        (xy 6.868 -3.604)
        (xy 6.89 -3.609)
        (xy 6.913 -3.615)
        (xy 6.937 -3.617)
        (xy 6.961 -3.619)
        (xy 6.985 -3.62)
        (xy 7.007 -3.619)
        (xy 7.031 -3.617)
        (xy 7.054 -3.615)
        (xy 7.078 -3.609)
        (xy 7.099 -3.604)
        (xy 7.123 -3.597)
        (xy 7.143 -3.589)
        (xy 7.166 -3.581)
        (xy 7.187 -3.571)
        (xy 7.206 -3.559)
        (xy 7.227 -3.547)
        (xy 7.246 -3.535)
        (xy 7.264 -3.52)
        (xy 7.283 -3.505)
        (xy 7.299 -3.49)
        (xy 7.315 -3.472)
        (xy 7.331 -3.454)
        (xy 7.344 -3.436)
        (xy 7.357 -3.416)
        (xy 7.369 -3.396)
        (xy 7.381 -3.376)
        (xy 7.392 -3.355)
        (xy 7.4 -3.334)
        (xy 7.408 -3.313)
        (xy 7.414 -3.289)
        (xy 7.419 -3.267)
        (xy 7.424 -3.245)
        (xy 7.427 -3.221)
        (xy 7.429 -3.197)
        (xy 7.429 -3.174)
        (xy 7.429 -3.152)
        (xy 7.427 -3.128)
        (xy 7.424 -3.104)
        (xy 7.419 -3.081)
        (xy 7.414 -3.059)
        (xy 7.408 -3.036)
        (xy 7.4 -3.015)
        (xy 7.392 -2.994)
        (xy 7.381 -2.972)
        (xy 7.369 -2.951)
        (xy 7.357 -2.932)
        (xy 7.344 -2.912)
        (xy 7.331 -2.894)
        (xy 7.315 -2.876)
        (xy 7.299 -2.859)
        (xy 7.283 -2.843)
        (xy 7.264 -2.829)
        (xy 7.246 -2.814)
        (xy 7.227 -2.801)
        (xy 7.206 -2.789)
        (xy 7.187 -2.778)
        (xy 7.166 -2.767)
        (xy 7.143 -2.759)
        (xy 7.123 -2.751)
        (xy 7.099 -2.745)
        (xy 7.078 -2.74)
        (xy 7.054 -2.734)
        (xy 7.031 -2.732)
        (xy 7.007 -2.73)
        (xy 6.985 -2.729)
        (xy 6.961 -2.73)
        (xy 6.937 -2.732)
        (xy 6.913 -2.734)
        (xy 6.89 -2.74)
        (xy 6.868 -2.745)
        (xy 6.847 -2.751)
        (xy 6.825 -2.758)
        (xy 6.802 -2.767)
        (xy 6.781 -2.777)
        (xy 6.761 -2.789)
        (xy 6.741 -2.801)
        (xy 6.722 -2.814)
        (xy 6.703 -2.829)
        (xy 6.687 -2.843)
        (xy 6.669 -2.859)
        (xy 6.653 -2.876)
        (xy 6.639 -2.894)
        (xy 6.624 -2.912)
        (xy 6.611 -2.931)
        (xy 6.599 -2.951)
        (xy 6.587 -2.971)
        (xy 6.578 -2.992)
        (xy 6.568 -3.015)
        (xy 6.562 -3.036)
        (xy 6.554 -3.059)
        (xy 6.549 -3.08)
        (xy 6.544 -3.104)
        (xy 6.541 -3.126)
        (xy 6.541 -3.15)
        (xy 6.539 -3.172)
        (xy 6.985 -3.172)
        (xy 6.985 -3.177)
      )

      (stroke (width 0.001) (type solid)) (fill solid) (layer "B.Paste"))
    (fp_poly
      (pts
        (xy 6.985 1.903)
        (xy 6.539 1.903)
        (xy 6.541 1.881)
        (xy 6.541 1.857)
        (xy 6.544 1.835)
        (xy 6.549 1.811)
        (xy 6.554 1.789)
        (xy 6.562 1.767)
        (xy 6.568 1.746)
        (xy 6.578 1.724)
        (xy 6.587 1.702)
        (xy 6.599 1.682)
        (xy 6.611 1.662)
        (xy 6.624 1.643)
        (xy 6.639 1.625)
        (xy 6.653 1.607)
        (xy 6.669 1.591)
        (xy 6.687 1.575)
        (xy 6.703 1.559)
        (xy 6.722 1.545)
        (xy 6.741 1.532)
        (xy 6.761 1.519)
        (xy 6.781 1.508)
        (xy 6.802 1.498)
        (xy 6.825 1.49)
        (xy 6.847 1.482)
        (xy 6.868 1.476)
        (xy 6.89 1.47)
        (xy 6.913 1.466)
        (xy 6.937 1.462)
        (xy 6.961 1.462)
        (xy 6.985 1.46)
        (xy 7.007 1.462)
        (xy 7.031 1.462)
        (xy 7.054 1.466)
        (xy 7.078 1.47)
        (xy 7.099 1.476)
        (xy 7.123 1.482)
        (xy 7.143 1.49)
        (xy 7.166 1.498)
        (xy 7.187 1.509)
        (xy 7.206 1.52)
        (xy 7.227 1.532)
        (xy 7.246 1.545)
        (xy 7.264 1.559)
        (xy 7.283 1.575)
        (xy 7.299 1.591)
        (xy 7.315 1.607)
        (xy 7.331 1.625)
        (xy 7.344 1.643)
        (xy 7.357 1.663)
        (xy 7.369 1.682)
        (xy 7.381 1.704)
        (xy 7.392 1.724)
        (xy 7.4 1.746)
        (xy 7.408 1.767)
        (xy 7.414 1.79)
        (xy 7.419 1.813)
        (xy 7.424 1.835)
        (xy 7.427 1.859)
        (xy 7.429 1.882)
        (xy 7.429 1.905)
        (xy 7.429 1.928)
        (xy 7.427 1.952)
        (xy 7.424 1.976)
        (xy 7.419 1.998)
        (xy 7.414 2.02)
        (xy 7.408 2.044)
        (xy 7.4 2.065)
        (xy 7.392 2.086)
        (xy 7.381 2.108)
        (xy 7.369 2.127)
        (xy 7.357 2.147)
        (xy 7.344 2.167)
        (xy 7.331 2.186)
        (xy 7.315 2.203)
        (xy 7.299 2.221)
        (xy 7.283 2.237)
        (xy 7.264 2.251)
        (xy 7.246 2.266)
        (xy 7.227 2.278)
        (xy 7.206 2.29)
        (xy 7.187 2.302)
        (xy 7.166 2.312)
        (xy 7.143 2.32)
        (xy 7.123 2.328)
        (xy 7.099 2.335)
        (xy 7.078 2.34)
        (xy 7.054 2.346)
        (xy 7.031 2.348)
        (xy 7.007 2.35)
        (xy 6.985 2.351)
        (xy 6.961 2.35)
        (xy 6.937 2.348)
        (xy 6.913 2.346)
        (xy 6.89 2.34)
        (xy 6.868 2.335)
        (xy 6.847 2.328)
        (xy 6.825 2.322)
        (xy 6.802 2.312)
        (xy 6.781 2.302)
        (xy 6.761 2.291)
        (xy 6.741 2.278)
        (xy 6.722 2.266)
        (xy 6.703 2.251)
        (xy 6.687 2.237)
        (xy 6.669 2.221)
        (xy 6.653 2.203)
        (xy 6.639 2.186)
        (xy 6.624 2.167)
        (xy 6.611 2.149)
        (xy 6.599 2.129)
        (xy 6.587 2.109)
        (xy 6.578 2.088)
        (xy 6.568 2.065)
        (xy 6.562 2.044)
        (xy 6.554 2.021)
        (xy 6.549 2)
        (xy 6.544 1.976)
        (xy 6.541 1.954)
        (xy 6.541 1.93)
        (xy 6.539 1.907)
        (xy 6.985 1.907)
        (xy 6.985 1.903)
      )

      (stroke (width 0.001) (type solid)) (fill solid) (layer "B.Paste"))
    (fp_poly
      (pts
        (xy 6.985 3.173)
        (xy 6.539 3.173)
        (xy 6.541 3.151)
        (xy 6.541 3.127)
        (xy 6.544 3.105)
        (xy 6.549 3.081)
        (xy 6.554 3.06)
        (xy 6.562 3.037)
        (xy 6.568 3.016)
        (xy 6.578 2.993)
        (xy 6.587 2.972)
        (xy 6.599 2.952)
        (xy 6.611 2.932)
        (xy 6.624 2.913)
        (xy 6.639 2.895)
        (xy 6.653 2.877)
        (xy 6.669 2.86)
        (xy 6.687 2.844)
        (xy 6.703 2.83)
        (xy 6.722 2.815)
        (xy 6.741 2.802)
        (xy 6.761 2.79)
        (xy 6.781 2.778)
        (xy 6.802 2.768)
        (xy 6.825 2.759)
        (xy 6.847 2.752)
        (xy 6.868 2.746)
        (xy 6.89 2.741)
        (xy 6.913 2.735)
        (xy 6.937 2.733)
        (xy 6.961 2.731)
        (xy 6.985 2.73)
        (xy 7.007 2.731)
        (xy 7.031 2.733)
        (xy 7.054 2.735)
        (xy 7.078 2.741)
        (xy 7.099 2.746)
        (xy 7.123 2.752)
        (xy 7.143 2.76)
        (xy 7.166 2.768)
        (xy 7.187 2.779)
        (xy 7.206 2.79)
        (xy 7.227 2.802)
        (xy 7.246 2.815)
        (xy 7.264 2.83)
        (xy 7.283 2.844)
        (xy 7.299 2.86)
        (xy 7.315 2.877)
        (xy 7.331 2.895)
        (xy 7.344 2.913)
        (xy 7.357 2.933)
        (xy 7.369 2.952)
        (xy 7.381 2.973)
        (xy 7.392 2.995)
        (xy 7.4 3.016)
        (xy 7.408 3.037)
        (xy 7.414 3.06)
        (xy 7.419 3.082)
        (xy 7.424 3.105)
        (xy 7.427 3.129)
        (xy 7.429 3.153)
        (xy 7.429 3.175)
        (xy 7.429 3.198)
        (xy 7.427 3.222)
        (xy 7.424 3.246)
        (xy 7.419 3.268)
        (xy 7.414 3.29)
        (xy 7.408 3.314)
        (xy 7.4 3.335)
        (xy 7.392 3.356)
        (xy 7.381 3.377)
        (xy 7.369 3.397)
        (xy 7.357 3.417)
        (xy 7.344 3.437)
        (xy 7.331 3.455)
        (xy 7.315 3.473)
        (xy 7.299 3.491)
        (xy 7.283 3.506)
        (xy 7.264 3.521)
        (xy 7.246 3.536)
        (xy 7.227 3.548)
        (xy 7.206 3.56)
        (xy 7.187 3.572)
        (xy 7.166 3.582)
        (xy 7.143 3.59)
        (xy 7.123 3.598)
        (xy 7.099 3.605)
        (xy 7.078 3.61)
        (xy 7.054 3.616)
        (xy 7.031 3.618)
        (xy 7.007 3.62)
        (xy 6.985 3.621)
        (xy 6.961 3.62)
        (xy 6.937 3.618)
        (xy 6.913 3.616)
        (xy 6.89 3.61)
        (xy 6.868 3.605)
        (xy 6.847 3.598)
        (xy 6.825 3.592)
        (xy 6.802 3.582)
        (xy 6.781 3.572)
        (xy 6.761 3.561)
        (xy 6.741 3.548)
        (xy 6.722 3.536)
        (xy 6.703 3.521)
        (xy 6.687 3.506)
        (xy 6.669 3.491)
        (xy 6.653 3.473)
        (xy 6.639 3.456)
        (xy 6.624 3.437)
        (xy 6.611 3.419)
        (xy 6.599 3.399)
        (xy 6.587 3.379)
        (xy 6.578 3.358)
        (xy 6.568 3.335)
        (xy 6.562 3.314)
        (xy 6.554 3.291)
        (xy 6.549 3.27)
        (xy 6.544 3.246)
        (xy 6.541 3.223)
        (xy 6.541 3.199)
        (xy 6.539 3.178)
        (xy 6.985 3.178)
        (xy 6.985 3.173)
      )

      (stroke (width 0.001) (type solid)) (fill solid) (layer "B.Paste"))
    (fp_poly
      (pts
        (xy 6.985 4.443)
        (xy 6.539 4.443)
        (xy 6.541 4.422)
        (xy 6.541 4.398)
        (xy 6.544 4.374)
        (xy 6.549 4.351)
        (xy 6.554 4.329)
        (xy 6.562 4.308)
        (xy 6.568 4.286)
        (xy 6.578 4.263)
        (xy 6.587 4.242)
        (xy 6.599 4.223)
        (xy 6.611 4.202)
        (xy 6.624 4.183)
        (xy 6.639 4.164)
        (xy 6.653 4.148)
        (xy 6.669 4.13)
        (xy 6.687 4.114)
        (xy 6.703 4.1)
        (xy 6.722 4.085)
        (xy 6.741 4.072)
        (xy 6.761 4.06)
        (xy 6.781 4.048)
        (xy 6.802 4.039)
        (xy 6.825 4.029)
        (xy 6.847 4.023)
        (xy 6.868 4.015)
        (xy 6.89 4.01)
        (xy 6.913 4.005)
        (xy 6.937 4.002)
        (xy 6.961 4.002)
        (xy 6.985 4)
        (xy 7.007 4.002)
        (xy 7.031 4.002)
        (xy 7.054 4.005)
        (xy 7.078 4.01)
        (xy 7.099 4.015)
        (xy 7.123 4.023)
        (xy 7.143 4.031)
        (xy 7.166 4.039)
        (xy 7.187 4.05)
        (xy 7.206 4.06)
        (xy 7.227 4.072)
        (xy 7.246 4.085)
        (xy 7.264 4.1)
        (xy 7.283 4.114)
        (xy 7.299 4.13)
        (xy 7.315 4.148)
        (xy 7.331 4.165)
        (xy 7.344 4.183)
        (xy 7.357 4.204)
        (xy 7.369 4.223)
        (xy 7.381 4.244)
        (xy 7.392 4.265)
        (xy 7.4 4.286)
        (xy 7.408 4.308)
        (xy 7.414 4.33)
        (xy 7.419 4.353)
        (xy 7.424 4.375)
        (xy 7.427 4.398)
        (xy 7.429 4.422)
        (xy 7.429 4.446)
        (xy 7.429 4.468)
        (xy 7.427 4.492)
        (xy 7.424 4.515)
        (xy 7.419 4.539)
        (xy 7.414 4.56)
        (xy 7.408 4.584)
        (xy 7.4 4.604)
        (xy 7.392 4.627)
        (xy 7.381 4.648)
        (xy 7.369 4.669)
        (xy 7.357 4.688)
        (xy 7.344 4.707)
        (xy 7.331 4.725)
        (xy 7.315 4.744)
        (xy 7.299 4.76)
        (xy 7.283 4.776)
        (xy 7.264 4.792)
        (xy 7.246 4.805)
        (xy 7.227 4.818)
        (xy 7.206 4.83)
        (xy 7.187 4.842)
        (xy 7.166 4.853)
        (xy 7.143 4.861)
        (xy 7.123 4.869)
        (xy 7.099 4.875)
        (xy 7.078 4.88)
        (xy 7.054 4.885)
        (xy 7.031 4.888)
        (xy 7.007 4.89)
        (xy 6.985 4.89)
        (xy 6.961 4.89)
        (xy 6.937 4.888)
        (xy 6.913 4.885)
        (xy 6.89 4.88)
        (xy 6.868 4.875)
        (xy 6.847 4.869)
        (xy 6.825 4.861)
        (xy 6.802 4.853)
        (xy 6.781 4.842)
        (xy 6.761 4.832)
        (xy 6.741 4.818)
        (xy 6.722 4.805)
        (xy 6.703 4.792)
        (xy 6.687 4.776)
        (xy 6.669 4.76)
        (xy 6.653 4.744)
        (xy 6.639 4.726)
        (xy 6.624 4.707)
        (xy 6.611 4.688)
        (xy 6.599 4.669)
        (xy 6.587 4.648)
        (xy 6.578 4.627)
        (xy 6.568 4.606)
        (xy 6.562 4.584)
        (xy 6.554 4.561)
        (xy 6.549 4.539)
        (xy 6.544 4.516)
        (xy 6.541 4.494)
        (xy 6.541 4.47)
        (xy 6.539 4.447)
        (xy 6.985 4.447)
        (xy 6.985 4.443)
      )

      (stroke (width 0.001) (type solid)) (fill solid) (layer "B.Paste"))
    (fp_poly
      (pts
        (xy 6.985 5.713)
        (xy 6.539 5.713)
        (xy 6.541 5.691)
        (xy 6.541 5.667)
        (xy 6.544 5.645)
        (xy 6.549 5.622)
        (xy 6.554 5.6)
        (xy 6.562 5.577)
        (xy 6.568 5.555)
        (xy 6.578 5.534)
        (xy 6.587 5.512)
        (xy 6.599 5.492)
        (xy 6.611 5.473)
        (xy 6.624 5.454)
        (xy 6.639 5.435)
        (xy 6.653 5.417)
        (xy 6.669 5.401)
        (xy 6.687 5.385)
        (xy 6.703 5.369)
        (xy 6.722 5.356)
        (xy 6.741 5.342)
        (xy 6.761 5.329)
        (xy 6.781 5.318)
        (xy 6.802 5.308)
        (xy 6.825 5.3)
        (xy 6.847 5.292)
        (xy 6.868 5.286)
        (xy 6.89 5.281)
        (xy 6.913 5.276)
        (xy 6.937 5.273)
        (xy 6.961 5.271)
        (xy 6.985 5.27)
        (xy 7.007 5.271)
        (xy 7.031 5.273)
        (xy 7.054 5.276)
        (xy 7.078 5.281)
        (xy 7.099 5.286)
        (xy 7.123 5.292)
        (xy 7.143 5.3)
        (xy 7.166 5.308)
        (xy 7.187 5.319)
        (xy 7.206 5.33)
        (xy 7.227 5.342)
        (xy 7.246 5.356)
        (xy 7.264 5.369)
        (xy 7.283 5.385)
        (xy 7.299 5.401)
        (xy 7.315 5.417)
        (xy 7.331 5.435)
        (xy 7.344 5.454)
        (xy 7.357 5.473)
        (xy 7.369 5.492)
        (xy 7.381 5.513)
        (xy 7.392 5.534)
        (xy 7.4 5.556)
        (xy 7.408 5.577)
        (xy 7.414 5.6)
        (xy 7.419 5.622)
        (xy 7.424 5.645)
        (xy 7.427 5.669)
        (xy 7.429 5.693)
        (xy 7.429 5.715)
        (xy 7.429 5.739)
        (xy 7.427 5.762)
        (xy 7.424 5.786)
        (xy 7.419 5.808)
        (xy 7.414 5.83)
        (xy 7.408 5.853)
        (xy 7.4 5.874)
        (xy 7.392 5.896)
        (xy 7.381 5.917)
        (xy 7.369 5.938)
        (xy 7.357 5.957)
        (xy 7.344 5.978)
        (xy 7.331 5.995)
        (xy 7.315 6.013)
        (xy 7.299 6.031)
        (xy 7.283 6.047)
        (xy 7.264 6.061)
        (xy 7.246 6.076)
        (xy 7.227 6.088)
        (xy 7.206 6.1)
        (xy 7.187 6.111)
        (xy 7.166 6.122)
        (xy 7.143 6.13)
        (xy 7.123 6.138)
        (xy 7.099 6.145)
        (xy 7.078 6.151)
        (xy 7.054 6.156)
        (xy 7.031 6.159)
        (xy 7.007 6.159)
        (xy 6.985 6.161)
        (xy 6.961 6.159)
        (xy 6.937 6.159)
        (xy 6.913 6.156)
        (xy 6.89 6.151)
        (xy 6.868 6.145)
        (xy 6.847 6.138)
        (xy 6.825 6.132)
        (xy 6.802 6.122)
        (xy 6.781 6.112)
        (xy 6.761 6.101)
        (xy 6.741 6.088)
        (xy 6.722 6.076)
        (xy 6.703 6.061)
        (xy 6.687 6.047)
        (xy 6.669 6.031)
        (xy 6.653 6.013)
        (xy 6.639 5.997)
        (xy 6.624 5.978)
        (xy 6.611 5.959)
        (xy 6.599 5.938)
        (xy 6.587 5.919)
        (xy 6.578 5.898)
        (xy 6.568 5.875)
        (xy 6.562 5.853)
        (xy 6.554 5.832)
        (xy 6.549 5.81)
        (xy 6.544 5.786)
        (xy 6.541 5.763)
        (xy 6.541 5.739)
        (xy 6.539 5.718)
        (xy 6.985 5.718)
        (xy 6.985 5.713)
      )

      (stroke (width 0.001) (type solid)) (fill solid) (layer "B.Paste"))
    (fp_poly
      (pts
        (xy 8.255 -5.717)
        (xy 7.809 -5.717)
        (xy 7.81 -5.738)
        (xy 7.812 -5.762)
        (xy 7.815 -5.785)
        (xy 7.82 -5.809)
        (xy 7.825 -5.831)
        (xy 7.831 -5.852)
        (xy 7.839 -5.874)
        (xy 7.847 -5.897)
        (xy 7.857 -5.918)
        (xy 7.868 -5.937)
        (xy 7.881 -5.958)
        (xy 7.894 -5.977)
        (xy 7.908 -5.996)
        (xy 7.924 -6.012)
        (xy 7.94 -6.03)
        (xy 7.956 -6.046)
        (xy 7.974 -6.06)
        (xy 7.993 -6.075)
        (xy 8.012 -6.087)
        (xy 8.031 -6.1)
        (xy 8.051 -6.111)
        (xy 8.073 -6.121)
        (xy 8.095 -6.131)
        (xy 8.117 -6.137)
        (xy 8.138 -6.144)
        (xy 8.16 -6.15)
        (xy 8.183 -6.155)
        (xy 8.207 -6.158)
        (xy 8.23 -6.158)
        (xy 8.255 -6.16)
        (xy 8.278 -6.158)
        (xy 8.301 -6.158)
        (xy 8.324 -6.155)
        (xy 8.348 -6.15)
        (xy 8.369 -6.144)
        (xy 8.393 -6.137)
        (xy 8.413 -6.129)
        (xy 8.435 -6.121)
        (xy 8.457 -6.11)
        (xy 8.477 -6.099)
        (xy 8.496 -6.087)
        (xy 8.516 -6.075)
        (xy 8.534 -6.06)
        (xy 8.553 -6.046)
        (xy 8.57 -6.03)
        (xy 8.586 -6.012)
        (xy 8.601 -5.994)
        (xy 8.615 -5.977)
        (xy 8.627 -5.956)
        (xy 8.64 -5.937)
        (xy 8.65 -5.916)
        (xy 8.662 -5.895)
        (xy 8.669 -5.873)
        (xy 8.678 -5.852)
        (xy 8.685 -5.829)
        (xy 8.689 -5.807)
        (xy 8.695 -5.785)
        (xy 8.698 -5.761)
        (xy 8.698 -5.738)
        (xy 8.699 -5.714)
        (xy 8.698 -5.692)
        (xy 8.698 -5.668)
        (xy 8.695 -5.644)
        (xy 8.689 -5.621)
        (xy 8.685 -5.599)
        (xy 8.678 -5.576)
        (xy 8.669 -5.555)
        (xy 8.662 -5.533)
        (xy 8.65 -5.512)
        (xy 8.64 -5.491)
        (xy 8.627 -5.472)
        (xy 8.615 -5.453)
        (xy 8.601 -5.434)
        (xy 8.586 -5.416)
        (xy 8.57 -5.4)
        (xy 8.553 -5.384)
        (xy 8.534 -5.368)
        (xy 8.516 -5.355)
        (xy 8.496 -5.341)
        (xy 8.477 -5.329)
        (xy 8.457 -5.318)
        (xy 8.435 -5.307)
        (xy 8.413 -5.299)
        (xy 8.393 -5.291)
        (xy 8.369 -5.285)
        (xy 8.348 -5.28)
        (xy 8.324 -5.275)
        (xy 8.301 -5.272)
        (xy 8.278 -5.27)
        (xy 8.255 -5.269)
        (xy 8.23 -5.27)
        (xy 8.207 -5.272)
        (xy 8.183 -5.275)
        (xy 8.16 -5.28)
        (xy 8.138 -5.285)
        (xy 8.117 -5.291)
        (xy 8.095 -5.299)
        (xy 8.073 -5.307)
        (xy 8.051 -5.317)
        (xy 8.031 -5.328)
        (xy 8.012 -5.341)
        (xy 7.993 -5.355)
        (xy 7.974 -5.368)
        (xy 7.956 -5.384)
        (xy 7.94 -5.4)
        (xy 7.924 -5.416)
        (xy 7.908 -5.434)
        (xy 7.894 -5.453)
        (xy 7.881 -5.472)
        (xy 7.868 -5.491)
        (xy 7.857 -5.511)
        (xy 7.847 -5.533)
        (xy 7.839 -5.554)
        (xy 7.831 -5.576)
        (xy 7.825 -5.599)
        (xy 7.82 -5.621)
        (xy 7.815 -5.644)
        (xy 7.812 -5.666)
        (xy 7.81 -5.69)
        (xy 7.809 -5.712)
        (xy 8.255 -5.712)
        (xy 8.255 -5.717)
      )

      (stroke (width 0.001) (type solid)) (fill solid) (layer "B.Paste"))
    (fp_poly
      (pts
        (xy 8.255 -3.177)
        (xy 7.809 -3.177)
        (xy 7.81 -3.198)
        (xy 7.812 -3.222)
        (xy 7.815 -3.245)
        (xy 7.82 -3.269)
        (xy 7.825 -3.29)
        (xy 7.831 -3.313)
        (xy 7.839 -3.334)
        (xy 7.847 -3.357)
        (xy 7.857 -3.378)
        (xy 7.868 -3.398)
        (xy 7.881 -3.418)
        (xy 7.894 -3.436)
        (xy 7.908 -3.455)
        (xy 7.924 -3.472)
        (xy 7.94 -3.49)
        (xy 7.956 -3.505)
        (xy 7.974 -3.52)
        (xy 7.993 -3.535)
        (xy 8.012 -3.547)
        (xy 8.031 -3.56)
        (xy 8.051 -3.571)
        (xy 8.073 -3.581)
        (xy 8.095 -3.591)
        (xy 8.117 -3.597)
        (xy 8.138 -3.604)
        (xy 8.16 -3.609)
        (xy 8.183 -3.615)
        (xy 8.207 -3.617)
        (xy 8.23 -3.619)
        (xy 8.255 -3.62)
        (xy 8.278 -3.619)
        (xy 8.301 -3.617)
        (xy 8.324 -3.615)
        (xy 8.348 -3.609)
        (xy 8.369 -3.604)
        (xy 8.393 -3.597)
        (xy 8.413 -3.589)
        (xy 8.435 -3.581)
        (xy 8.457 -3.571)
        (xy 8.477 -3.559)
        (xy 8.496 -3.547)
        (xy 8.516 -3.535)
        (xy 8.534 -3.52)
        (xy 8.553 -3.505)
        (xy 8.57 -3.49)
        (xy 8.586 -3.472)
        (xy 8.601 -3.454)
        (xy 8.615 -3.436)
        (xy 8.627 -3.416)
        (xy 8.64 -3.398)
        (xy 8.65 -3.376)
        (xy 8.662 -3.355)
        (xy 8.669 -3.334)
        (xy 8.678 -3.313)
        (xy 8.685 -3.289)
        (xy 8.689 -3.267)
        (xy 8.695 -3.245)
        (xy 8.698 -3.221)
        (xy 8.698 -3.197)
        (xy 8.699 -3.174)
        (xy 8.698 -3.152)
        (xy 8.698 -3.128)
        (xy 8.695 -3.104)
        (xy 8.689 -3.081)
        (xy 8.685 -3.059)
        (xy 8.678 -3.036)
        (xy 8.669 -3.015)
        (xy 8.662 -2.994)
        (xy 8.65 -2.972)
        (xy 8.64 -2.951)
        (xy 8.627 -2.932)
        (xy 8.615 -2.912)
        (xy 8.601 -2.894)
        (xy 8.586 -2.876)
        (xy 8.57 -2.859)
        (xy 8.553 -2.843)
        (xy 8.534 -2.829)
        (xy 8.516 -2.814)
        (xy 8.496 -2.801)
        (xy 8.477 -2.789)
        (xy 8.457 -2.778)
        (xy 8.435 -2.767)
        (xy 8.413 -2.759)
        (xy 8.393 -2.751)
        (xy 8.369 -2.745)
        (xy 8.348 -2.74)
        (xy 8.324 -2.734)
        (xy 8.301 -2.732)
        (xy 8.278 -2.73)
        (xy 8.255 -2.729)
        (xy 8.23 -2.73)
        (xy 8.207 -2.732)
        (xy 8.183 -2.734)
        (xy 8.16 -2.74)
        (xy 8.138 -2.745)
        (xy 8.117 -2.751)
        (xy 8.095 -2.758)
        (xy 8.073 -2.767)
        (xy 8.051 -2.777)
        (xy 8.031 -2.789)
        (xy 8.012 -2.801)
        (xy 7.993 -2.814)
        (xy 7.974 -2.829)
        (xy 7.956 -2.843)
        (xy 7.94 -2.859)
        (xy 7.924 -2.876)
        (xy 7.908 -2.894)
        (xy 7.894 -2.912)
        (xy 7.881 -2.931)
        (xy 7.868 -2.951)
        (xy 7.857 -2.971)
        (xy 7.847 -2.992)
        (xy 7.839 -3.015)
        (xy 7.831 -3.036)
        (xy 7.825 -3.059)
        (xy 7.82 -3.08)
        (xy 7.815 -3.104)
        (xy 7.812 -3.126)
        (xy 7.81 -3.15)
        (xy 7.809 -3.172)
        (xy 8.255 -3.172)
        (xy 8.255 -3.177)
      )

      (stroke (width 0.001) (type solid)) (fill solid) (layer "B.Paste"))
    (fp_poly
      (pts
        (xy 8.255 1.903)
        (xy 7.809 1.903)
        (xy 7.81 1.881)
        (xy 7.812 1.857)
        (xy 7.815 1.835)
        (xy 7.82 1.811)
        (xy 7.825 1.789)
        (xy 7.831 1.767)
        (xy 7.839 1.746)
        (xy 7.847 1.724)
        (xy 7.857 1.702)
        (xy 7.868 1.682)
        (xy 7.881 1.662)
        (xy 7.894 1.643)
        (xy 7.908 1.625)
        (xy 7.924 1.607)
        (xy 7.94 1.591)
        (xy 7.956 1.575)
        (xy 7.974 1.559)
        (xy 7.993 1.545)
        (xy 8.012 1.532)
        (xy 8.031 1.519)
        (xy 8.051 1.508)
        (xy 8.073 1.498)
        (xy 8.095 1.49)
        (xy 8.117 1.482)
        (xy 8.138 1.476)
        (xy 8.16 1.47)
        (xy 8.183 1.466)
        (xy 8.207 1.462)
        (xy 8.23 1.462)
        (xy 8.255 1.46)
        (xy 8.278 1.462)
        (xy 8.301 1.462)
        (xy 8.324 1.466)
        (xy 8.348 1.47)
        (xy 8.369 1.476)
        (xy 8.393 1.482)
        (xy 8.413 1.49)
        (xy 8.435 1.498)
        (xy 8.457 1.509)
        (xy 8.477 1.52)
        (xy 8.496 1.532)
        (xy 8.516 1.545)
        (xy 8.534 1.559)
        (xy 8.553 1.575)
        (xy 8.57 1.591)
        (xy 8.586 1.607)
        (xy 8.601 1.625)
        (xy 8.615 1.643)
        (xy 8.627 1.663)
        (xy 8.64 1.682)
        (xy 8.65 1.704)
        (xy 8.662 1.724)
        (xy 8.669 1.746)
        (xy 8.678 1.767)
        (xy 8.685 1.79)
        (xy 8.689 1.813)
        (xy 8.695 1.835)
        (xy 8.698 1.859)
        (xy 8.698 1.882)
        (xy 8.699 1.905)
        (xy 8.698 1.928)
        (xy 8.698 1.952)
        (xy 8.695 1.976)
        (xy 8.689 1.998)
        (xy 8.685 2.02)
        (xy 8.678 2.044)
        (xy 8.669 2.065)
        (xy 8.662 2.086)
        (xy 8.65 2.108)
        (xy 8.64 2.129)
        (xy 8.627 2.147)
        (xy 8.615 2.167)
        (xy 8.601 2.186)
        (xy 8.586 2.203)
        (xy 8.57 2.221)
        (xy 8.553 2.237)
        (xy 8.534 2.251)
        (xy 8.516 2.266)
        (xy 8.496 2.278)
        (xy 8.477 2.29)
        (xy 8.457 2.302)
        (xy 8.435 2.312)
        (xy 8.413 2.32)
        (xy 8.393 2.328)
        (xy 8.369 2.335)
        (xy 8.348 2.34)
        (xy 8.324 2.346)
        (xy 8.301 2.348)
        (xy 8.278 2.35)
        (xy 8.255 2.351)
        (xy 8.23 2.35)
        (xy 8.207 2.348)
        (xy 8.183 2.346)
        (xy 8.16 2.34)
        (xy 8.138 2.335)
        (xy 8.117 2.328)
        (xy 8.095 2.322)
        (xy 8.073 2.312)
        (xy 8.051 2.302)
        (xy 8.031 2.291)
        (xy 8.012 2.278)
        (xy 7.993 2.266)
        (xy 7.974 2.251)
        (xy 7.956 2.237)
        (xy 7.94 2.221)
        (xy 7.924 2.203)
        (xy 7.908 2.186)
        (xy 7.894 2.167)
        (xy 7.881 2.149)
        (xy 7.868 2.129)
        (xy 7.857 2.109)
        (xy 7.847 2.088)
        (xy 7.839 2.065)
        (xy 7.831 2.044)
        (xy 7.825 2.021)
        (xy 7.82 2)
        (xy 7.815 1.976)
        (xy 7.812 1.954)
        (xy 7.81 1.93)
        (xy 7.809 1.907)
        (xy 8.255 1.907)
        (xy 8.255 1.903)
      )

      (stroke (width 0.001) (type solid)) (fill solid) (layer "B.Paste"))
    (fp_poly
      (pts
        (xy 8.255 3.173)
        (xy 7.809 3.173)
        (xy 7.81 3.151)
        (xy 7.812 3.127)
        (xy 7.815 3.105)
        (xy 7.82 3.081)
        (xy 7.825 3.06)
        (xy 7.831 3.037)
        (xy 7.839 3.016)
        (xy 7.847 2.993)
        (xy 7.857 2.972)
        (xy 7.868 2.952)
        (xy 7.881 2.932)
        (xy 7.894 2.913)
        (xy 7.908 2.895)
        (xy 7.924 2.877)
        (xy 7.94 2.86)
        (xy 7.956 2.844)
        (xy 7.974 2.83)
        (xy 7.993 2.815)
        (xy 8.012 2.802)
        (xy 8.031 2.79)
        (xy 8.051 2.778)
        (xy 8.073 2.768)
        (xy 8.095 2.759)
        (xy 8.117 2.752)
        (xy 8.138 2.746)
        (xy 8.16 2.741)
        (xy 8.183 2.735)
        (xy 8.207 2.733)
        (xy 8.23 2.731)
        (xy 8.255 2.73)
        (xy 8.278 2.731)
        (xy 8.301 2.733)
        (xy 8.324 2.735)
        (xy 8.348 2.741)
        (xy 8.369 2.746)
        (xy 8.393 2.752)
        (xy 8.413 2.76)
        (xy 8.435 2.768)
        (xy 8.457 2.779)
        (xy 8.477 2.79)
        (xy 8.496 2.802)
        (xy 8.516 2.815)
        (xy 8.534 2.83)
        (xy 8.553 2.844)
        (xy 8.57 2.86)
        (xy 8.586 2.877)
        (xy 8.601 2.895)
        (xy 8.615 2.913)
        (xy 8.627 2.933)
        (xy 8.64 2.952)
        (xy 8.65 2.973)
        (xy 8.662 2.995)
        (xy 8.669 3.016)
        (xy 8.678 3.037)
        (xy 8.685 3.06)
        (xy 8.689 3.082)
        (xy 8.695 3.105)
        (xy 8.698 3.129)
        (xy 8.698 3.153)
        (xy 8.699 3.175)
        (xy 8.698 3.198)
        (xy 8.698 3.222)
        (xy 8.695 3.246)
        (xy 8.689 3.268)
        (xy 8.685 3.29)
        (xy 8.678 3.314)
        (xy 8.669 3.335)
        (xy 8.662 3.356)
        (xy 8.65 3.377)
        (xy 8.64 3.399)
        (xy 8.627 3.417)
        (xy 8.615 3.437)
        (xy 8.601 3.455)
        (xy 8.586 3.473)
        (xy 8.57 3.491)
        (xy 8.553 3.506)
        (xy 8.534 3.521)
        (xy 8.516 3.536)
        (xy 8.496 3.548)
        (xy 8.477 3.56)
        (xy 8.457 3.572)
        (xy 8.435 3.582)
        (xy 8.413 3.59)
        (xy 8.393 3.598)
        (xy 8.369 3.605)
        (xy 8.348 3.61)
        (xy 8.324 3.616)
        (xy 8.301 3.618)
        (xy 8.278 3.62)
        (xy 8.255 3.621)
        (xy 8.23 3.62)
        (xy 8.207 3.618)
        (xy 8.183 3.616)
        (xy 8.16 3.61)
        (xy 8.138 3.605)
        (xy 8.117 3.598)
        (xy 8.095 3.592)
        (xy 8.073 3.582)
        (xy 8.051 3.572)
        (xy 8.031 3.561)
        (xy 8.012 3.548)
        (xy 7.993 3.536)
        (xy 7.974 3.521)
        (xy 7.956 3.506)
        (xy 7.94 3.491)
        (xy 7.924 3.473)
        (xy 7.908 3.456)
        (xy 7.894 3.437)
        (xy 7.881 3.419)
        (xy 7.868 3.399)
        (xy 7.857 3.379)
        (xy 7.847 3.358)
        (xy 7.839 3.335)
        (xy 7.831 3.314)
        (xy 7.825 3.291)
        (xy 7.82 3.27)
        (xy 7.815 3.246)
        (xy 7.812 3.223)
        (xy 7.81 3.199)
        (xy 7.809 3.178)
        (xy 8.255 3.178)
        (xy 8.255 3.173)
      )

      (stroke (width 0.001) (type solid)) (fill solid) (layer "B.Paste"))
    (fp_poly
      (pts
        (xy 8.255 4.443)
        (xy 7.809 4.443)
        (xy 7.81 4.422)
        (xy 7.812 4.398)
        (xy 7.815 4.374)
        (xy 7.82 4.351)
        (xy 7.825 4.329)
        (xy 7.831 4.308)
        (xy 7.839 4.286)
        (xy 7.847 4.263)
        (xy 7.857 4.242)
        (xy 7.868 4.223)
        (xy 7.881 4.202)
        (xy 7.894 4.183)
        (xy 7.908 4.164)
        (xy 7.924 4.148)
        (xy 7.94 4.13)
        (xy 7.956 4.114)
        (xy 7.974 4.1)
        (xy 7.993 4.085)
        (xy 8.012 4.072)
        (xy 8.031 4.06)
        (xy 8.051 4.048)
        (xy 8.073 4.039)
        (xy 8.095 4.029)
        (xy 8.117 4.023)
        (xy 8.138 4.015)
        (xy 8.16 4.01)
        (xy 8.183 4.005)
        (xy 8.207 4.002)
        (xy 8.23 4.002)
        (xy 8.255 4)
        (xy 8.278 4.002)
        (xy 8.301 4.002)
        (xy 8.324 4.005)
        (xy 8.348 4.01)
        (xy 8.369 4.015)
        (xy 8.393 4.023)
        (xy 8.413 4.031)
        (xy 8.435 4.039)
        (xy 8.457 4.05)
        (xy 8.477 4.06)
        (xy 8.496 4.072)
        (xy 8.516 4.085)
        (xy 8.534 4.1)
        (xy 8.553 4.114)
        (xy 8.57 4.13)
        (xy 8.586 4.148)
        (xy 8.601 4.165)
        (xy 8.615 4.183)
        (xy 8.627 4.204)
        (xy 8.64 4.223)
        (xy 8.65 4.244)
        (xy 8.662 4.265)
        (xy 8.669 4.286)
        (xy 8.678 4.308)
        (xy 8.685 4.33)
        (xy 8.689 4.353)
        (xy 8.695 4.375)
        (xy 8.698 4.398)
        (xy 8.698 4.422)
        (xy 8.699 4.446)
        (xy 8.698 4.468)
        (xy 8.698 4.492)
        (xy 8.695 4.515)
        (xy 8.689 4.539)
        (xy 8.685 4.56)
        (xy 8.678 4.584)
        (xy 8.669 4.604)
        (xy 8.662 4.627)
        (xy 8.65 4.648)
        (xy 8.64 4.669)
        (xy 8.627 4.688)
        (xy 8.615 4.707)
        (xy 8.601 4.725)
        (xy 8.586 4.744)
        (xy 8.57 4.76)
        (xy 8.553 4.776)
        (xy 8.534 4.792)
        (xy 8.516 4.805)
        (xy 8.496 4.818)
        (xy 8.477 4.83)
        (xy 8.457 4.842)
        (xy 8.435 4.853)
        (xy 8.413 4.861)
        (xy 8.393 4.869)
        (xy 8.369 4.875)
        (xy 8.348 4.88)
        (xy 8.324 4.885)
        (xy 8.301 4.888)
        (xy 8.278 4.89)
        (xy 8.255 4.89)
        (xy 8.23 4.89)
        (xy 8.207 4.888)
        (xy 8.183 4.885)
        (xy 8.16 4.88)
        (xy 8.138 4.875)
        (xy 8.117 4.869)
        (xy 8.095 4.861)
        (xy 8.073 4.853)
        (xy 8.051 4.842)
        (xy 8.031 4.832)
        (xy 8.012 4.818)
        (xy 7.993 4.805)
        (xy 7.974 4.792)
        (xy 7.956 4.776)
        (xy 7.94 4.76)
        (xy 7.924 4.744)
        (xy 7.908 4.726)
        (xy 7.894 4.707)
        (xy 7.881 4.688)
        (xy 7.868 4.669)
        (xy 7.857 4.648)
        (xy 7.847 4.627)
        (xy 7.839 4.606)
        (xy 7.831 4.584)
        (xy 7.825 4.561)
        (xy 7.82 4.539)
        (xy 7.815 4.516)
        (xy 7.812 4.494)
        (xy 7.81 4.47)
        (xy 7.809 4.447)
        (xy 8.255 4.447)
        (xy 8.255 4.443)
      )

      (stroke (width 0.001) (type solid)) (fill solid) (layer "B.Paste"))
    (fp_poly
      (pts
        (xy 8.255 5.713)
        (xy 7.809 5.713)
        (xy 7.81 5.691)
        (xy 7.812 5.667)
        (xy 7.815 5.645)
        (xy 7.82 5.622)
        (xy 7.825 5.6)
        (xy 7.831 5.577)
        (xy 7.839 5.555)
        (xy 7.847 5.534)
        (xy 7.857 5.512)
        (xy 7.868 5.492)
        (xy 7.881 5.473)
        (xy 7.894 5.454)
        (xy 7.908 5.435)
        (xy 7.924 5.417)
        (xy 7.94 5.401)
        (xy 7.956 5.385)
        (xy 7.974 5.369)
        (xy 7.993 5.356)
        (xy 8.012 5.342)
        (xy 8.031 5.329)
        (xy 8.051 5.318)
        (xy 8.073 5.308)
        (xy 8.095 5.3)
        (xy 8.117 5.292)
        (xy 8.138 5.286)
        (xy 8.16 5.281)
        (xy 8.183 5.276)
        (xy 8.207 5.273)
        (xy 8.23 5.271)
        (xy 8.255 5.27)
        (xy 8.278 5.271)
        (xy 8.301 5.273)
        (xy 8.324 5.276)
        (xy 8.348 5.281)
        (xy 8.369 5.286)
        (xy 8.393 5.292)
        (xy 8.413 5.3)
        (xy 8.435 5.308)
        (xy 8.457 5.319)
        (xy 8.477 5.33)
        (xy 8.496 5.342)
        (xy 8.516 5.356)
        (xy 8.534 5.369)
        (xy 8.553 5.385)
        (xy 8.57 5.401)
        (xy 8.586 5.417)
        (xy 8.601 5.435)
        (xy 8.615 5.454)
        (xy 8.627 5.473)
        (xy 8.64 5.492)
        (xy 8.65 5.513)
        (xy 8.662 5.534)
        (xy 8.669 5.556)
        (xy 8.678 5.577)
        (xy 8.685 5.6)
        (xy 8.689 5.622)
        (xy 8.695 5.645)
        (xy 8.698 5.669)
        (xy 8.698 5.693)
        (xy 8.699 5.715)
        (xy 8.698 5.739)
        (xy 8.698 5.762)
        (xy 8.695 5.786)
        (xy 8.689 5.808)
        (xy 8.685 5.83)
        (xy 8.678 5.853)
        (xy 8.669 5.874)
        (xy 8.662 5.896)
        (xy 8.65 5.917)
        (xy 8.64 5.938)
        (xy 8.627 5.957)
        (xy 8.615 5.978)
        (xy 8.601 5.995)
        (xy 8.586 6.013)
        (xy 8.57 6.031)
        (xy 8.553 6.047)
        (xy 8.534 6.061)
        (xy 8.516 6.076)
        (xy 8.496 6.088)
        (xy 8.477 6.1)
        (xy 8.457 6.111)
        (xy 8.435 6.122)
        (xy 8.413 6.13)
        (xy 8.393 6.138)
        (xy 8.369 6.145)
        (xy 8.348 6.151)
        (xy 8.324 6.156)
        (xy 8.301 6.159)
        (xy 8.278 6.159)
        (xy 8.255 6.161)
        (xy 8.23 6.159)
        (xy 8.207 6.159)
        (xy 8.183 6.156)
        (xy 8.16 6.151)
        (xy 8.138 6.145)
        (xy 8.117 6.138)
        (xy 8.095 6.132)
        (xy 8.073 6.122)
        (xy 8.051 6.112)
        (xy 8.031 6.101)
        (xy 8.012 6.088)
        (xy 7.993 6.076)
        (xy 7.974 6.061)
        (xy 7.956 6.047)
        (xy 7.94 6.031)
        (xy 7.924 6.013)
        (xy 7.908 5.997)
        (xy 7.894 5.978)
        (xy 7.881 5.959)
        (xy 7.868 5.938)
        (xy 7.857 5.919)
        (xy 7.847 5.898)
        (xy 7.839 5.875)
        (xy 7.831 5.853)
        (xy 7.825 5.832)
        (xy 7.82 5.81)
        (xy 7.815 5.786)
        (xy 7.812 5.763)
        (xy 7.81 5.739)
        (xy 7.809 5.718)
        (xy 8.255 5.718)
        (xy 8.255 5.713)
      )

      (stroke (width 0.001) (type solid)) (fill solid) (layer "B.Paste"))
    (fp_poly
      (pts
        (xy 9.525 -5.717)
        (xy 9.079 -5.717)
        (xy 9.08 -5.738)
        (xy 9.082 -5.762)
        (xy 9.085 -5.785)
        (xy 9.089 -5.809)
        (xy 9.095 -5.831)
        (xy 9.102 -5.852)
        (xy 9.108 -5.874)
        (xy 9.118 -5.897)
        (xy 9.127 -5.918)
        (xy 9.138 -5.937)
        (xy 9.151 -5.958)
        (xy 9.164 -5.977)
        (xy 9.179 -5.996)
        (xy 9.194 -6.012)
        (xy 9.21 -6.03)
        (xy 9.227 -6.046)
        (xy 9.243 -6.06)
        (xy 9.262 -6.075)
        (xy 9.281 -6.087)
        (xy 9.301 -6.1)
        (xy 9.321 -6.111)
        (xy 9.342 -6.121)
        (xy 9.365 -6.131)
        (xy 9.387 -6.137)
        (xy 9.409 -6.144)
        (xy 9.43 -6.15)
        (xy 9.454 -6.155)
        (xy 9.477 -6.158)
        (xy 9.5 -6.158)
        (xy 9.525 -6.16)
        (xy 9.547 -6.158)
        (xy 9.571 -6.158)
        (xy 9.595 -6.155)
        (xy 9.618 -6.15)
        (xy 9.64 -6.144)
        (xy 9.663 -6.137)
        (xy 9.683 -6.129)
        (xy 9.705 -6.121)
        (xy 9.727 -6.11)
        (xy 9.747 -6.099)
        (xy 9.766 -6.087)
        (xy 9.787 -6.075)
        (xy 9.804 -6.06)
        (xy 9.823 -6.046)
        (xy 9.839 -6.03)
        (xy 9.855 -6.012)
        (xy 9.871 -5.994)
        (xy 9.884 -5.977)
        (xy 9.897 -5.956)
        (xy 9.909 -5.937)
        (xy 9.92 -5.916)
        (xy 9.932 -5.895)
        (xy 9.939 -5.873)
        (xy 9.948 -5.852)
        (xy 9.954 -5.829)
        (xy 9.96 -5.807)
        (xy 9.964 -5.785)
        (xy 9.967 -5.761)
        (xy 9.968 -5.738)
        (xy 9.97 -5.714)
        (xy 9.968 -5.692)
        (xy 9.967 -5.668)
        (xy 9.964 -5.644)
        (xy 9.96 -5.621)
        (xy 9.954 -5.599)
        (xy 9.948 -5.576)
        (xy 9.939 -5.555)
        (xy 9.932 -5.533)
        (xy 9.92 -5.512)
        (xy 9.909 -5.491)
        (xy 9.897 -5.472)
        (xy 9.884 -5.453)
        (xy 9.871 -5.434)
        (xy 9.855 -5.416)
        (xy 9.839 -5.4)
        (xy 9.823 -5.384)
        (xy 9.804 -5.368)
        (xy 9.787 -5.355)
        (xy 9.766 -5.341)
        (xy 9.747 -5.329)
        (xy 9.727 -5.318)
        (xy 9.705 -5.307)
        (xy 9.683 -5.299)
        (xy 9.663 -5.291)
        (xy 9.64 -5.285)
        (xy 9.618 -5.28)
        (xy 9.595 -5.275)
        (xy 9.571 -5.272)
        (xy 9.547 -5.27)
        (xy 9.525 -5.269)
        (xy 9.5 -5.27)
        (xy 9.477 -5.272)
        (xy 9.454 -5.275)
        (xy 9.43 -5.28)
        (xy 9.409 -5.285)
        (xy 9.387 -5.291)
        (xy 9.365 -5.299)
        (xy 9.342 -5.307)
        (xy 9.321 -5.317)
        (xy 9.301 -5.328)
        (xy 9.281 -5.341)
        (xy 9.262 -5.355)
        (xy 9.243 -5.368)
        (xy 9.227 -5.384)
        (xy 9.21 -5.4)
        (xy 9.194 -5.416)
        (xy 9.179 -5.434)
        (xy 9.164 -5.453)
        (xy 9.151 -5.472)
        (xy 9.138 -5.491)
        (xy 9.127 -5.511)
        (xy 9.118 -5.533)
        (xy 9.108 -5.554)
        (xy 9.102 -5.576)
        (xy 9.095 -5.599)
        (xy 9.089 -5.621)
        (xy 9.085 -5.644)
        (xy 9.082 -5.666)
        (xy 9.08 -5.69)
        (xy 9.079 -5.712)
        (xy 9.525 -5.712)
        (xy 9.525 -5.717)
      )

      (stroke (width 0.001) (type solid)) (fill solid) (layer "B.Paste"))
    (fp_poly
      (pts
        (xy 9.525 -3.177)
        (xy 9.079 -3.177)
        (xy 9.08 -3.198)
        (xy 9.082 -3.222)
        (xy 9.085 -3.245)
        (xy 9.089 -3.269)
        (xy 9.095 -3.29)
        (xy 9.102 -3.313)
        (xy 9.108 -3.334)
        (xy 9.118 -3.357)
        (xy 9.127 -3.378)
        (xy 9.138 -3.398)
        (xy 9.151 -3.418)
        (xy 9.164 -3.436)
        (xy 9.179 -3.455)
        (xy 9.194 -3.472)
        (xy 9.21 -3.49)
        (xy 9.227 -3.505)
        (xy 9.243 -3.52)
        (xy 9.262 -3.535)
        (xy 9.281 -3.547)
        (xy 9.301 -3.56)
        (xy 9.321 -3.571)
        (xy 9.342 -3.581)
        (xy 9.365 -3.591)
        (xy 9.387 -3.597)
        (xy 9.409 -3.604)
        (xy 9.43 -3.609)
        (xy 9.454 -3.615)
        (xy 9.477 -3.617)
        (xy 9.5 -3.619)
        (xy 9.525 -3.62)
        (xy 9.547 -3.619)
        (xy 9.571 -3.617)
        (xy 9.595 -3.615)
        (xy 9.618 -3.609)
        (xy 9.64 -3.604)
        (xy 9.663 -3.597)
        (xy 9.683 -3.589)
        (xy 9.705 -3.581)
        (xy 9.727 -3.571)
        (xy 9.747 -3.559)
        (xy 9.766 -3.547)
        (xy 9.787 -3.535)
        (xy 9.804 -3.52)
        (xy 9.823 -3.505)
        (xy 9.839 -3.49)
        (xy 9.855 -3.472)
        (xy 9.871 -3.454)
        (xy 9.884 -3.436)
        (xy 9.897 -3.416)
        (xy 9.909 -3.396)
        (xy 9.92 -3.376)
        (xy 9.932 -3.355)
        (xy 9.939 -3.334)
        (xy 9.948 -3.313)
        (xy 9.954 -3.289)
        (xy 9.96 -3.267)
        (xy 9.964 -3.245)
        (xy 9.967 -3.221)
        (xy 9.968 -3.197)
        (xy 9.97 -3.174)
        (xy 9.968 -3.152)
        (xy 9.967 -3.128)
        (xy 9.964 -3.104)
        (xy 9.96 -3.081)
        (xy 9.954 -3.059)
        (xy 9.948 -3.036)
        (xy 9.939 -3.015)
        (xy 9.932 -2.994)
        (xy 9.92 -2.972)
        (xy 9.909 -2.951)
        (xy 9.897 -2.932)
        (xy 9.884 -2.912)
        (xy 9.871 -2.894)
        (xy 9.855 -2.876)
        (xy 9.839 -2.859)
        (xy 9.823 -2.843)
        (xy 9.804 -2.829)
        (xy 9.787 -2.814)
        (xy 9.766 -2.801)
        (xy 9.747 -2.789)
        (xy 9.727 -2.778)
        (xy 9.705 -2.767)
        (xy 9.683 -2.759)
        (xy 9.663 -2.751)
        (xy 9.64 -2.745)
        (xy 9.618 -2.74)
        (xy 9.595 -2.734)
        (xy 9.571 -2.732)
        (xy 9.547 -2.73)
        (xy 9.525 -2.729)
        (xy 9.5 -2.73)
        (xy 9.477 -2.732)
        (xy 9.454 -2.734)
        (xy 9.43 -2.74)
        (xy 9.409 -2.745)
        (xy 9.387 -2.751)
        (xy 9.365 -2.758)
        (xy 9.342 -2.767)
        (xy 9.321 -2.777)
        (xy 9.301 -2.789)
        (xy 9.281 -2.801)
        (xy 9.262 -2.814)
        (xy 9.243 -2.829)
        (xy 9.227 -2.843)
        (xy 9.21 -2.859)
        (xy 9.194 -2.876)
        (xy 9.179 -2.894)
        (xy 9.164 -2.912)
        (xy 9.151 -2.931)
        (xy 9.138 -2.951)
        (xy 9.127 -2.971)
        (xy 9.118 -2.992)
        (xy 9.108 -3.015)
        (xy 9.102 -3.036)
        (xy 9.095 -3.059)
        (xy 9.089 -3.08)
        (xy 9.085 -3.104)
        (xy 9.082 -3.126)
        (xy 9.08 -3.15)
        (xy 9.079 -3.172)
        (xy 9.525 -3.172)
        (xy 9.525 -3.177)
      )

      (stroke (width 0.001) (type solid)) (fill solid) (layer "B.Paste"))
    (fp_poly
      (pts
        (xy 9.525 1.903)
        (xy 9.079 1.903)
        (xy 9.08 1.881)
        (xy 9.082 1.857)
        (xy 9.085 1.835)
        (xy 9.089 1.811)
        (xy 9.095 1.789)
        (xy 9.102 1.767)
        (xy 9.108 1.746)
        (xy 9.118 1.724)
        (xy 9.127 1.702)
        (xy 9.138 1.682)
        (xy 9.151 1.662)
        (xy 9.164 1.643)
        (xy 9.179 1.625)
        (xy 9.194 1.607)
        (xy 9.21 1.591)
        (xy 9.227 1.575)
        (xy 9.243 1.559)
        (xy 9.262 1.545)
        (xy 9.281 1.532)
        (xy 9.301 1.519)
        (xy 9.321 1.508)
        (xy 9.342 1.498)
        (xy 9.365 1.49)
        (xy 9.387 1.482)
        (xy 9.409 1.476)
        (xy 9.43 1.47)
        (xy 9.454 1.466)
        (xy 9.477 1.462)
        (xy 9.5 1.462)
        (xy 9.525 1.46)
        (xy 9.547 1.462)
        (xy 9.571 1.462)
        (xy 9.595 1.466)
        (xy 9.618 1.47)
        (xy 9.64 1.476)
        (xy 9.663 1.482)
        (xy 9.683 1.49)
        (xy 9.705 1.498)
        (xy 9.727 1.509)
        (xy 9.747 1.52)
        (xy 9.766 1.532)
        (xy 9.787 1.545)
        (xy 9.804 1.559)
        (xy 9.823 1.575)
        (xy 9.839 1.591)
        (xy 9.855 1.607)
        (xy 9.871 1.625)
        (xy 9.884 1.643)
        (xy 9.897 1.663)
        (xy 9.909 1.684)
        (xy 9.92 1.704)
        (xy 9.932 1.724)
        (xy 9.939 1.746)
        (xy 9.948 1.767)
        (xy 9.954 1.79)
        (xy 9.96 1.813)
        (xy 9.964 1.835)
        (xy 9.967 1.859)
        (xy 9.968 1.882)
        (xy 9.97 1.905)
        (xy 9.968 1.928)
        (xy 9.967 1.952)
        (xy 9.964 1.976)
        (xy 9.96 1.998)
        (xy 9.954 2.02)
        (xy 9.948 2.044)
        (xy 9.939 2.065)
        (xy 9.932 2.086)
        (xy 9.92 2.108)
        (xy 9.909 2.127)
        (xy 9.897 2.147)
        (xy 9.884 2.167)
        (xy 9.871 2.186)
        (xy 9.855 2.203)
        (xy 9.839 2.221)
        (xy 9.823 2.237)
        (xy 9.804 2.251)
        (xy 9.787 2.266)
        (xy 9.766 2.278)
        (xy 9.747 2.29)
        (xy 9.727 2.302)
        (xy 9.705 2.312)
        (xy 9.683 2.32)
        (xy 9.663 2.328)
        (xy 9.64 2.335)
        (xy 9.618 2.34)
        (xy 9.595 2.346)
        (xy 9.571 2.348)
        (xy 9.547 2.35)
        (xy 9.525 2.351)
        (xy 9.5 2.35)
        (xy 9.477 2.348)
        (xy 9.454 2.346)
        (xy 9.43 2.34)
        (xy 9.409 2.335)
        (xy 9.387 2.328)
        (xy 9.365 2.322)
        (xy 9.342 2.312)
        (xy 9.321 2.302)
        (xy 9.301 2.291)
        (xy 9.281 2.278)
        (xy 9.262 2.266)
        (xy 9.243 2.251)
        (xy 9.227 2.237)
        (xy 9.21 2.221)
        (xy 9.194 2.203)
        (xy 9.179 2.186)
        (xy 9.164 2.167)
        (xy 9.151 2.149)
        (xy 9.138 2.129)
        (xy 9.127 2.109)
        (xy 9.118 2.088)
        (xy 9.108 2.065)
        (xy 9.102 2.044)
        (xy 9.095 2.021)
        (xy 9.089 2)
        (xy 9.085 1.976)
        (xy 9.082 1.954)
        (xy 9.08 1.93)
        (xy 9.079 1.907)
        (xy 9.525 1.907)
        (xy 9.525 1.903)
      )

      (stroke (width 0.001) (type solid)) (fill solid) (layer "B.Paste"))
    (fp_poly
      (pts
        (xy 9.525 3.173)
        (xy 9.079 3.173)
        (xy 9.08 3.151)
        (xy 9.082 3.127)
        (xy 9.085 3.105)
        (xy 9.089 3.081)
        (xy 9.095 3.06)
        (xy 9.102 3.037)
        (xy 9.108 3.016)
        (xy 9.118 2.993)
        (xy 9.127 2.972)
        (xy 9.138 2.952)
        (xy 9.151 2.932)
        (xy 9.164 2.913)
        (xy 9.179 2.895)
        (xy 9.194 2.877)
        (xy 9.21 2.86)
        (xy 9.227 2.844)
        (xy 9.243 2.83)
        (xy 9.262 2.815)
        (xy 9.281 2.802)
        (xy 9.301 2.79)
        (xy 9.321 2.778)
        (xy 9.342 2.768)
        (xy 9.365 2.759)
        (xy 9.387 2.752)
        (xy 9.409 2.746)
        (xy 9.43 2.741)
        (xy 9.454 2.735)
        (xy 9.477 2.733)
        (xy 9.5 2.731)
        (xy 9.525 2.73)
        (xy 9.547 2.731)
        (xy 9.571 2.733)
        (xy 9.595 2.735)
        (xy 9.618 2.741)
        (xy 9.64 2.746)
        (xy 9.663 2.752)
        (xy 9.683 2.76)
        (xy 9.705 2.768)
        (xy 9.727 2.779)
        (xy 9.747 2.79)
        (xy 9.766 2.802)
        (xy 9.787 2.815)
        (xy 9.804 2.83)
        (xy 9.823 2.844)
        (xy 9.839 2.86)
        (xy 9.855 2.877)
        (xy 9.871 2.895)
        (xy 9.884 2.913)
        (xy 9.897 2.933)
        (xy 9.909 2.952)
        (xy 9.92 2.973)
        (xy 9.932 2.995)
        (xy 9.939 3.016)
        (xy 9.948 3.037)
        (xy 9.954 3.06)
        (xy 9.96 3.082)
        (xy 9.964 3.105)
        (xy 9.967 3.129)
        (xy 9.968 3.153)
        (xy 9.97 3.175)
        (xy 9.968 3.198)
        (xy 9.967 3.222)
        (xy 9.964 3.246)
        (xy 9.96 3.268)
        (xy 9.954 3.29)
        (xy 9.948 3.314)
        (xy 9.939 3.335)
        (xy 9.932 3.356)
        (xy 9.92 3.377)
        (xy 9.909 3.397)
        (xy 9.897 3.417)
        (xy 9.884 3.437)
        (xy 9.871 3.455)
        (xy 9.855 3.473)
        (xy 9.839 3.491)
        (xy 9.823 3.506)
        (xy 9.804 3.521)
        (xy 9.787 3.536)
        (xy 9.766 3.548)
        (xy 9.747 3.56)
        (xy 9.727 3.572)
        (xy 9.705 3.582)
        (xy 9.683 3.59)
        (xy 9.663 3.598)
        (xy 9.64 3.605)
        (xy 9.618 3.61)
        (xy 9.595 3.616)
        (xy 9.571 3.618)
        (xy 9.547 3.62)
        (xy 9.525 3.621)
        (xy 9.5 3.62)
        (xy 9.477 3.618)
        (xy 9.454 3.616)
        (xy 9.43 3.61)
        (xy 9.409 3.605)
        (xy 9.387 3.598)
        (xy 9.365 3.592)
        (xy 9.342 3.582)
        (xy 9.321 3.572)
        (xy 9.301 3.561)
        (xy 9.281 3.548)
        (xy 9.262 3.536)
        (xy 9.243 3.521)
        (xy 9.227 3.506)
        (xy 9.21 3.491)
        (xy 9.194 3.473)
        (xy 9.179 3.456)
        (xy 9.164 3.437)
        (xy 9.151 3.419)
        (xy 9.138 3.399)
        (xy 9.127 3.379)
        (xy 9.118 3.358)
        (xy 9.108 3.335)
        (xy 9.102 3.314)
        (xy 9.095 3.291)
        (xy 9.089 3.27)
        (xy 9.085 3.246)
        (xy 9.082 3.223)
        (xy 9.08 3.199)
        (xy 9.079 3.178)
        (xy 9.525 3.178)
        (xy 9.525 3.173)
      )

      (stroke (width 0.001) (type solid)) (fill solid) (layer "B.Paste"))
    (fp_poly
      (pts
        (xy 9.525 4.443)
        (xy 9.079 4.443)
        (xy 9.08 4.422)
        (xy 9.082 4.398)
        (xy 9.085 4.374)
        (xy 9.089 4.351)
        (xy 9.095 4.329)
        (xy 9.102 4.308)
        (xy 9.108 4.286)
        (xy 9.118 4.263)
        (xy 9.127 4.242)
        (xy 9.138 4.223)
        (xy 9.151 4.202)
        (xy 9.164 4.183)
        (xy 9.179 4.164)
        (xy 9.194 4.148)
        (xy 9.21 4.13)
        (xy 9.227 4.114)
        (xy 9.243 4.1)
        (xy 9.262 4.085)
        (xy 9.281 4.072)
        (xy 9.301 4.06)
        (xy 9.321 4.048)
        (xy 9.342 4.039)
        (xy 9.365 4.029)
        (xy 9.387 4.023)
        (xy 9.409 4.015)
        (xy 9.43 4.01)
        (xy 9.454 4.005)
        (xy 9.477 4.002)
        (xy 9.5 4.002)
        (xy 9.525 4)
        (xy 9.547 4.002)
        (xy 9.571 4.002)
        (xy 9.595 4.005)
        (xy 9.618 4.01)
        (xy 9.64 4.015)
        (xy 9.663 4.023)
        (xy 9.683 4.031)
        (xy 9.705 4.039)
        (xy 9.727 4.05)
        (xy 9.747 4.06)
        (xy 9.766 4.072)
        (xy 9.787 4.085)
        (xy 9.804 4.1)
        (xy 9.823 4.114)
        (xy 9.839 4.13)
        (xy 9.855 4.148)
        (xy 9.871 4.165)
        (xy 9.884 4.183)
        (xy 9.897 4.204)
        (xy 9.909 4.223)
        (xy 9.92 4.244)
        (xy 9.932 4.265)
        (xy 9.939 4.286)
        (xy 9.948 4.308)
        (xy 9.954 4.33)
        (xy 9.96 4.353)
        (xy 9.964 4.375)
        (xy 9.967 4.398)
        (xy 9.968 4.422)
        (xy 9.97 4.446)
        (xy 9.968 4.468)
        (xy 9.967 4.492)
        (xy 9.964 4.515)
        (xy 9.96 4.539)
        (xy 9.954 4.56)
        (xy 9.948 4.584)
        (xy 9.939 4.604)
        (xy 9.932 4.627)
        (xy 9.92 4.648)
        (xy 9.909 4.669)
        (xy 9.897 4.688)
        (xy 9.884 4.707)
        (xy 9.871 4.725)
        (xy 9.855 4.744)
        (xy 9.839 4.76)
        (xy 9.823 4.776)
        (xy 9.804 4.792)
        (xy 9.787 4.805)
        (xy 9.766 4.818)
        (xy 9.747 4.83)
        (xy 9.727 4.842)
        (xy 9.705 4.853)
        (xy 9.683 4.861)
        (xy 9.663 4.869)
        (xy 9.64 4.875)
        (xy 9.618 4.88)
        (xy 9.595 4.885)
        (xy 9.571 4.888)
        (xy 9.547 4.89)
        (xy 9.525 4.89)
        (xy 9.5 4.89)
        (xy 9.477 4.888)
        (xy 9.454 4.885)
        (xy 9.43 4.88)
        (xy 9.409 4.875)
        (xy 9.387 4.869)
        (xy 9.365 4.861)
        (xy 9.342 4.853)
        (xy 9.321 4.842)
        (xy 9.301 4.832)
        (xy 9.281 4.818)
        (xy 9.262 4.805)
        (xy 9.243 4.792)
        (xy 9.227 4.776)
        (xy 9.21 4.76)
        (xy 9.194 4.744)
        (xy 9.179 4.726)
        (xy 9.164 4.707)
        (xy 9.151 4.688)
        (xy 9.138 4.669)
        (xy 9.127 4.648)
        (xy 9.118 4.627)
        (xy 9.108 4.606)
        (xy 9.102 4.584)
        (xy 9.095 4.561)
        (xy 9.089 4.539)
        (xy 9.085 4.516)
        (xy 9.082 4.494)
        (xy 9.08 4.47)
        (xy 9.079 4.447)
        (xy 9.525 4.447)
        (xy 9.525 4.443)
      )

      (stroke (width 0.001) (type solid)) (fill solid) (layer "B.Paste"))
    (fp_poly
      (pts
        (xy 9.525 5.713)
        (xy 9.079 5.713)
        (xy 9.08 5.691)
        (xy 9.082 5.667)
        (xy 9.085 5.645)
        (xy 9.089 5.622)
        (xy 9.095 5.6)
        (xy 9.102 5.577)
        (xy 9.108 5.555)
        (xy 9.118 5.534)
        (xy 9.127 5.512)
        (xy 9.138 5.492)
        (xy 9.151 5.473)
        (xy 9.164 5.454)
        (xy 9.179 5.435)
        (xy 9.194 5.417)
        (xy 9.21 5.401)
        (xy 9.227 5.385)
        (xy 9.243 5.369)
        (xy 9.262 5.356)
        (xy 9.281 5.342)
        (xy 9.301 5.329)
        (xy 9.321 5.318)
        (xy 9.342 5.308)
        (xy 9.365 5.3)
        (xy 9.387 5.292)
        (xy 9.409 5.286)
        (xy 9.43 5.281)
        (xy 9.454 5.276)
        (xy 9.477 5.273)
        (xy 9.5 5.271)
        (xy 9.525 5.27)
        (xy 9.547 5.271)
        (xy 9.571 5.273)
        (xy 9.595 5.276)
        (xy 9.618 5.281)
        (xy 9.64 5.286)
        (xy 9.663 5.292)
        (xy 9.683 5.3)
        (xy 9.705 5.308)
        (xy 9.727 5.319)
        (xy 9.747 5.33)
        (xy 9.766 5.342)
        (xy 9.787 5.356)
        (xy 9.804 5.369)
        (xy 9.823 5.385)
        (xy 9.839 5.401)
        (xy 9.855 5.417)
        (xy 9.871 5.435)
        (xy 9.884 5.454)
        (xy 9.897 5.473)
        (xy 9.909 5.492)
        (xy 9.92 5.513)
        (xy 9.932 5.534)
        (xy 9.939 5.556)
        (xy 9.948 5.577)
        (xy 9.954 5.6)
        (xy 9.96 5.622)
        (xy 9.964 5.645)
        (xy 9.967 5.669)
        (xy 9.968 5.693)
        (xy 9.97 5.715)
        (xy 9.968 5.739)
        (xy 9.967 5.762)
        (xy 9.964 5.786)
        (xy 9.96 5.808)
        (xy 9.954 5.83)
        (xy 9.948 5.853)
        (xy 9.939 5.874)
        (xy 9.932 5.896)
        (xy 9.92 5.917)
        (xy 9.909 5.938)
        (xy 9.897 5.957)
        (xy 9.884 5.978)
        (xy 9.871 5.995)
        (xy 9.855 6.013)
        (xy 9.839 6.031)
        (xy 9.823 6.047)
        (xy 9.804 6.061)
        (xy 9.787 6.076)
        (xy 9.766 6.088)
        (xy 9.747 6.1)
        (xy 9.727 6.111)
        (xy 9.705 6.122)
        (xy 9.683 6.13)
        (xy 9.663 6.138)
        (xy 9.64 6.145)
        (xy 9.618 6.151)
        (xy 9.595 6.156)
        (xy 9.571 6.159)
        (xy 9.547 6.159)
        (xy 9.525 6.161)
        (xy 9.5 6.159)
        (xy 9.477 6.159)
        (xy 9.454 6.156)
        (xy 9.43 6.151)
        (xy 9.409 6.145)
        (xy 9.387 6.138)
        (xy 9.365 6.132)
        (xy 9.342 6.122)
        (xy 9.321 6.112)
        (xy 9.301 6.101)
        (xy 9.281 6.088)
        (xy 9.262 6.076)
        (xy 9.243 6.061)
        (xy 9.227 6.047)
        (xy 9.21 6.031)
        (xy 9.194 6.013)
        (xy 9.179 5.997)
        (xy 9.164 5.978)
        (xy 9.151 5.959)
        (xy 9.138 5.938)
        (xy 9.127 5.919)
        (xy 9.118 5.898)
        (xy 9.108 5.875)
        (xy 9.102 5.853)
        (xy 9.095 5.832)
        (xy 9.089 5.81)
        (xy 9.085 5.786)
        (xy 9.082 5.763)
        (xy 9.08 5.739)
        (xy 9.079 5.718)
        (xy 9.525 5.718)
        (xy 9.525 5.713)
      )

      (stroke (width 0.001) (type solid)) (fill solid) (layer "B.Paste"))
    (fp_poly
      (pts
        (xy 10.794 -5.717)
        (xy 10.349 -5.717)
        (xy 10.351 -5.738)
        (xy 10.352 -5.762)
        (xy 10.355 -5.785)
        (xy 10.359 -5.809)
        (xy 10.364 -5.831)
        (xy 10.371 -5.852)
        (xy 10.378 -5.874)
        (xy 10.387 -5.897)
        (xy 10.397 -5.918)
        (xy 10.409 -5.937)
        (xy 10.422 -5.958)
        (xy 10.435 -5.977)
        (xy 10.448 -5.996)
        (xy 10.464 -6.012)
        (xy 10.48 -6.03)
        (xy 10.496 -6.046)
        (xy 10.513 -6.06)
        (xy 10.532 -6.075)
        (xy 10.551 -6.087)
        (xy 10.571 -6.1)
        (xy 10.592 -6.111)
        (xy 10.612 -6.121)
        (xy 10.634 -6.131)
        (xy 10.656 -6.137)
        (xy 10.679 -6.144)
        (xy 10.701 -6.15)
        (xy 10.723 -6.155)
        (xy 10.746 -6.158)
        (xy 10.771 -6.158)
        (xy 10.794 -6.16)
        (xy 10.817 -6.158)
        (xy 10.842 -6.158)
        (xy 10.864 -6.155)
        (xy 10.887 -6.15)
        (xy 10.909 -6.144)
        (xy 10.932 -6.137)
        (xy 10.954 -6.129)
        (xy 10.976 -6.121)
        (xy 10.996 -6.11)
        (xy 11.018 -6.099)
        (xy 11.037 -6.087)
        (xy 11.057 -6.075)
        (xy 11.074 -6.06)
        (xy 11.092 -6.046)
        (xy 11.109 -6.03)
        (xy 11.125 -6.012)
        (xy 11.14 -5.994)
        (xy 11.154 -5.977)
        (xy 11.167 -5.956)
        (xy 11.179 -5.937)
        (xy 11.191 -5.916)
        (xy 11.201 -5.895)
        (xy 11.21 -5.873)
        (xy 11.217 -5.852)
        (xy 11.224 -5.829)
        (xy 11.23 -5.807)
        (xy 11.234 -5.785)
        (xy 11.237 -5.761)
        (xy 11.239 -5.738)
        (xy 11.239 -5.714)
        (xy 11.239 -5.692)
        (xy 11.237 -5.668)
        (xy 11.234 -5.644)
        (xy 11.23 -5.621)
        (xy 11.224 -5.599)
        (xy 11.217 -5.576)
        (xy 11.21 -5.555)
        (xy 11.201 -5.533)
        (xy 11.191 -5.512)
        (xy 11.179 -5.491)
        (xy 11.167 -5.472)
        (xy 11.154 -5.453)
        (xy 11.14 -5.434)
        (xy 11.125 -5.416)
        (xy 11.109 -5.4)
        (xy 11.092 -5.384)
        (xy 11.074 -5.368)
        (xy 11.057 -5.355)
        (xy 11.037 -5.341)
        (xy 11.018 -5.329)
        (xy 10.996 -5.318)
        (xy 10.976 -5.307)
        (xy 10.954 -5.299)
        (xy 10.932 -5.291)
        (xy 10.909 -5.285)
        (xy 10.887 -5.28)
        (xy 10.864 -5.275)
        (xy 10.842 -5.272)
        (xy 10.817 -5.27)
        (xy 10.794 -5.269)
        (xy 10.771 -5.27)
        (xy 10.746 -5.272)
        (xy 10.723 -5.275)
        (xy 10.701 -5.28)
        (xy 10.679 -5.285)
        (xy 10.656 -5.291)
        (xy 10.634 -5.299)
        (xy 10.612 -5.307)
        (xy 10.592 -5.317)
        (xy 10.571 -5.328)
        (xy 10.551 -5.341)
        (xy 10.532 -5.355)
        (xy 10.513 -5.368)
        (xy 10.496 -5.384)
        (xy 10.48 -5.4)
        (xy 10.464 -5.416)
        (xy 10.448 -5.434)
        (xy 10.435 -5.453)
        (xy 10.422 -5.472)
        (xy 10.409 -5.491)
        (xy 10.397 -5.511)
        (xy 10.387 -5.533)
        (xy 10.378 -5.554)
        (xy 10.371 -5.576)
        (xy 10.364 -5.599)
        (xy 10.359 -5.621)
        (xy 10.355 -5.644)
        (xy 10.352 -5.666)
        (xy 10.351 -5.69)
        (xy 10.349 -5.712)
        (xy 10.794 -5.712)
        (xy 10.794 -5.717)
      )

      (stroke (width 0.001) (type solid)) (fill solid) (layer "B.Paste"))
    (fp_poly
      (pts
        (xy 10.794 -3.177)
        (xy 10.349 -3.177)
        (xy 10.351 -3.198)
        (xy 10.352 -3.222)
        (xy 10.355 -3.245)
        (xy 10.359 -3.269)
        (xy 10.364 -3.29)
        (xy 10.371 -3.313)
        (xy 10.378 -3.334)
        (xy 10.387 -3.357)
        (xy 10.397 -3.378)
        (xy 10.409 -3.398)
        (xy 10.422 -3.418)
        (xy 10.435 -3.436)
        (xy 10.448 -3.455)
        (xy 10.464 -3.472)
        (xy 10.48 -3.49)
        (xy 10.496 -3.505)
        (xy 10.513 -3.52)
        (xy 10.532 -3.535)
        (xy 10.551 -3.547)
        (xy 10.571 -3.56)
        (xy 10.592 -3.571)
        (xy 10.612 -3.581)
        (xy 10.634 -3.591)
        (xy 10.656 -3.597)
        (xy 10.679 -3.604)
        (xy 10.701 -3.609)
        (xy 10.723 -3.615)
        (xy 10.746 -3.617)
        (xy 10.771 -3.619)
        (xy 10.794 -3.62)
        (xy 10.817 -3.619)
        (xy 10.842 -3.617)
        (xy 10.864 -3.615)
        (xy 10.887 -3.609)
        (xy 10.909 -3.604)
        (xy 10.932 -3.597)
        (xy 10.954 -3.589)
        (xy 10.976 -3.581)
        (xy 10.996 -3.571)
        (xy 11.018 -3.559)
        (xy 11.037 -3.547)
        (xy 11.057 -3.535)
        (xy 11.074 -3.52)
        (xy 11.092 -3.505)
        (xy 11.109 -3.49)
        (xy 11.125 -3.472)
        (xy 11.14 -3.454)
        (xy 11.154 -3.436)
        (xy 11.167 -3.416)
        (xy 11.179 -3.396)
        (xy 11.191 -3.376)
        (xy 11.201 -3.355)
        (xy 11.21 -3.334)
        (xy 11.217 -3.313)
        (xy 11.224 -3.289)
        (xy 11.23 -3.267)
        (xy 11.234 -3.245)
        (xy 11.237 -3.221)
        (xy 11.239 -3.197)
        (xy 11.239 -3.174)
        (xy 11.239 -3.152)
        (xy 11.237 -3.128)
        (xy 11.234 -3.104)
        (xy 11.23 -3.081)
        (xy 11.224 -3.059)
        (xy 11.217 -3.036)
        (xy 11.21 -3.015)
        (xy 11.201 -2.994)
        (xy 11.191 -2.972)
        (xy 11.179 -2.951)
        (xy 11.167 -2.932)
        (xy 11.154 -2.912)
        (xy 11.14 -2.894)
        (xy 11.125 -2.876)
        (xy 11.109 -2.859)
        (xy 11.092 -2.843)
        (xy 11.074 -2.829)
        (xy 11.057 -2.814)
        (xy 11.037 -2.801)
        (xy 11.018 -2.789)
        (xy 10.996 -2.778)
        (xy 10.976 -2.767)
        (xy 10.954 -2.759)
        (xy 10.932 -2.751)
        (xy 10.909 -2.745)
        (xy 10.887 -2.74)
        (xy 10.864 -2.734)
        (xy 10.842 -2.732)
        (xy 10.817 -2.73)
        (xy 10.794 -2.729)
        (xy 10.771 -2.73)
        (xy 10.746 -2.732)
        (xy 10.723 -2.734)
        (xy 10.701 -2.74)
        (xy 10.679 -2.745)
        (xy 10.656 -2.751)
        (xy 10.634 -2.758)
        (xy 10.612 -2.767)
        (xy 10.592 -2.777)
        (xy 10.571 -2.789)
        (xy 10.551 -2.801)
        (xy 10.532 -2.814)
        (xy 10.513 -2.829)
        (xy 10.496 -2.843)
        (xy 10.48 -2.859)
        (xy 10.464 -2.876)
        (xy 10.448 -2.894)
        (xy 10.435 -2.912)
        (xy 10.422 -2.931)
        (xy 10.409 -2.951)
        (xy 10.397 -2.971)
        (xy 10.387 -2.992)
        (xy 10.378 -3.015)
        (xy 10.371 -3.036)
        (xy 10.364 -3.059)
        (xy 10.359 -3.08)
        (xy 10.355 -3.104)
        (xy 10.352 -3.126)
        (xy 10.351 -3.15)
        (xy 10.349 -3.172)
        (xy 10.794 -3.172)
        (xy 10.794 -3.177)
      )

      (stroke (width 0.001) (type solid)) (fill solid) (layer "B.Paste"))
    (fp_poly
      (pts
        (xy 10.794 1.903)
        (xy 10.349 1.903)
        (xy 10.351 1.881)
        (xy 10.352 1.857)
        (xy 10.355 1.835)
        (xy 10.359 1.811)
        (xy 10.364 1.789)
        (xy 10.371 1.767)
        (xy 10.378 1.746)
        (xy 10.387 1.724)
        (xy 10.397 1.702)
        (xy 10.409 1.682)
        (xy 10.422 1.662)
        (xy 10.435 1.643)
        (xy 10.448 1.625)
        (xy 10.464 1.607)
        (xy 10.48 1.591)
        (xy 10.496 1.575)
        (xy 10.513 1.559)
        (xy 10.532 1.545)
        (xy 10.551 1.532)
        (xy 10.571 1.519)
        (xy 10.592 1.508)
        (xy 10.612 1.498)
        (xy 10.634 1.49)
        (xy 10.656 1.482)
        (xy 10.679 1.476)
        (xy 10.701 1.47)
        (xy 10.723 1.466)
        (xy 10.746 1.462)
        (xy 10.771 1.462)
        (xy 10.794 1.46)
        (xy 10.817 1.462)
        (xy 10.842 1.462)
        (xy 10.864 1.466)
        (xy 10.887 1.47)
        (xy 10.909 1.476)
        (xy 10.932 1.482)
        (xy 10.954 1.49)
        (xy 10.976 1.498)
        (xy 10.996 1.509)
        (xy 11.018 1.52)
        (xy 11.037 1.532)
        (xy 11.057 1.545)
        (xy 11.074 1.559)
        (xy 11.092 1.575)
        (xy 11.109 1.591)
        (xy 11.125 1.607)
        (xy 11.14 1.625)
        (xy 11.154 1.643)
        (xy 11.167 1.663)
        (xy 11.179 1.684)
        (xy 11.191 1.704)
        (xy 11.201 1.724)
        (xy 11.21 1.746)
        (xy 11.217 1.767)
        (xy 11.224 1.79)
        (xy 11.23 1.813)
        (xy 11.234 1.835)
        (xy 11.237 1.859)
        (xy 11.239 1.882)
        (xy 11.239 1.905)
        (xy 11.239 1.928)
        (xy 11.237 1.952)
        (xy 11.234 1.976)
        (xy 11.23 1.998)
        (xy 11.224 2.02)
        (xy 11.217 2.044)
        (xy 11.21 2.065)
        (xy 11.201 2.086)
        (xy 11.191 2.108)
        (xy 11.179 2.127)
        (xy 11.167 2.147)
        (xy 11.154 2.167)
        (xy 11.14 2.186)
        (xy 11.125 2.203)
        (xy 11.109 2.221)
        (xy 11.092 2.237)
        (xy 11.074 2.251)
        (xy 11.057 2.266)
        (xy 11.037 2.278)
        (xy 11.018 2.29)
        (xy 10.996 2.302)
        (xy 10.976 2.312)
        (xy 10.954 2.32)
        (xy 10.932 2.328)
        (xy 10.909 2.335)
        (xy 10.887 2.34)
        (xy 10.864 2.346)
        (xy 10.842 2.348)
        (xy 10.817 2.35)
        (xy 10.794 2.351)
        (xy 10.771 2.35)
        (xy 10.746 2.348)
        (xy 10.723 2.346)
        (xy 10.701 2.34)
        (xy 10.679 2.335)
        (xy 10.656 2.328)
        (xy 10.634 2.322)
        (xy 10.612 2.312)
        (xy 10.592 2.302)
        (xy 10.571 2.291)
        (xy 10.551 2.278)
        (xy 10.532 2.266)
        (xy 10.513 2.251)
        (xy 10.496 2.237)
        (xy 10.48 2.221)
        (xy 10.464 2.203)
        (xy 10.448 2.186)
        (xy 10.435 2.167)
        (xy 10.422 2.149)
        (xy 10.409 2.129)
        (xy 10.397 2.109)
        (xy 10.387 2.088)
        (xy 10.378 2.065)
        (xy 10.371 2.044)
        (xy 10.364 2.021)
        (xy 10.359 2)
        (xy 10.355 1.976)
        (xy 10.352 1.954)
        (xy 10.351 1.93)
        (xy 10.349 1.907)
        (xy 10.794 1.907)
        (xy 10.794 1.903)
      )

      (stroke (width 0.001) (type solid)) (fill solid) (layer "B.Paste"))
    (fp_poly
      (pts
        (xy 10.794 3.173)
        (xy 10.349 3.173)
        (xy 10.351 3.151)
        (xy 10.352 3.127)
        (xy 10.355 3.105)
        (xy 10.359 3.081)
        (xy 10.364 3.06)
        (xy 10.371 3.037)
        (xy 10.378 3.016)
        (xy 10.387 2.993)
        (xy 10.397 2.972)
        (xy 10.409 2.952)
        (xy 10.422 2.932)
        (xy 10.435 2.913)
        (xy 10.448 2.895)
        (xy 10.464 2.877)
        (xy 10.48 2.86)
        (xy 10.496 2.844)
        (xy 10.513 2.83)
        (xy 10.532 2.815)
        (xy 10.551 2.802)
        (xy 10.571 2.79)
        (xy 10.592 2.778)
        (xy 10.612 2.768)
        (xy 10.634 2.759)
        (xy 10.656 2.752)
        (xy 10.679 2.746)
        (xy 10.701 2.741)
        (xy 10.723 2.735)
        (xy 10.746 2.733)
        (xy 10.771 2.731)
        (xy 10.794 2.73)
        (xy 10.817 2.731)
        (xy 10.842 2.733)
        (xy 10.864 2.735)
        (xy 10.887 2.741)
        (xy 10.909 2.746)
        (xy 10.932 2.752)
        (xy 10.954 2.76)
        (xy 10.976 2.768)
        (xy 10.996 2.779)
        (xy 11.018 2.79)
        (xy 11.037 2.802)
        (xy 11.057 2.815)
        (xy 11.074 2.83)
        (xy 11.092 2.844)
        (xy 11.109 2.86)
        (xy 11.125 2.877)
        (xy 11.14 2.895)
        (xy 11.154 2.913)
        (xy 11.167 2.933)
        (xy 11.179 2.952)
        (xy 11.191 2.973)
        (xy 11.201 2.995)
        (xy 11.21 3.016)
        (xy 11.217 3.037)
        (xy 11.224 3.06)
        (xy 11.23 3.082)
        (xy 11.234 3.105)
        (xy 11.237 3.129)
        (xy 11.239 3.153)
        (xy 11.239 3.175)
        (xy 11.239 3.198)
        (xy 11.237 3.222)
        (xy 11.234 3.246)
        (xy 11.23 3.268)
        (xy 11.224 3.29)
        (xy 11.217 3.314)
        (xy 11.21 3.335)
        (xy 11.201 3.356)
        (xy 11.191 3.377)
        (xy 11.179 3.397)
        (xy 11.167 3.417)
        (xy 11.154 3.437)
        (xy 11.14 3.455)
        (xy 11.125 3.473)
        (xy 11.109 3.491)
        (xy 11.092 3.506)
        (xy 11.074 3.521)
        (xy 11.057 3.536)
        (xy 11.037 3.548)
        (xy 11.018 3.56)
        (xy 10.996 3.572)
        (xy 10.976 3.582)
        (xy 10.954 3.59)
        (xy 10.932 3.598)
        (xy 10.909 3.605)
        (xy 10.887 3.61)
        (xy 10.864 3.616)
        (xy 10.842 3.618)
        (xy 10.817 3.62)
        (xy 10.794 3.621)
        (xy 10.771 3.62)
        (xy 10.746 3.618)
        (xy 10.723 3.616)
        (xy 10.701 3.61)
        (xy 10.679 3.605)
        (xy 10.656 3.598)
        (xy 10.634 3.592)
        (xy 10.612 3.582)
        (xy 10.592 3.572)
        (xy 10.571 3.561)
        (xy 10.551 3.548)
        (xy 10.532 3.536)
        (xy 10.513 3.521)
        (xy 10.496 3.506)
        (xy 10.48 3.491)
        (xy 10.464 3.473)
        (xy 10.448 3.456)
        (xy 10.435 3.437)
        (xy 10.422 3.419)
        (xy 10.409 3.399)
        (xy 10.397 3.379)
        (xy 10.387 3.358)
        (xy 10.378 3.335)
        (xy 10.371 3.314)
        (xy 10.364 3.291)
        (xy 10.359 3.27)
        (xy 10.355 3.246)
        (xy 10.352 3.223)
        (xy 10.351 3.199)
        (xy 10.349 3.178)
        (xy 10.794 3.178)
        (xy 10.794 3.173)
      )

      (stroke (width 0.001) (type solid)) (fill solid) (layer "B.Paste"))
    (fp_poly
      (pts
        (xy 10.794 4.443)
        (xy 10.349 4.443)
        (xy 10.351 4.422)
        (xy 10.352 4.398)
        (xy 10.355 4.374)
        (xy 10.359 4.351)
        (xy 10.364 4.329)
        (xy 10.371 4.308)
        (xy 10.378 4.286)
        (xy 10.387 4.263)
        (xy 10.397 4.242)
        (xy 10.409 4.223)
        (xy 10.422 4.202)
        (xy 10.435 4.183)
        (xy 10.448 4.164)
        (xy 10.464 4.148)
        (xy 10.48 4.13)
        (xy 10.496 4.114)
        (xy 10.513 4.1)
        (xy 10.532 4.085)
        (xy 10.551 4.072)
        (xy 10.571 4.06)
        (xy 10.592 4.048)
        (xy 10.612 4.039)
        (xy 10.634 4.029)
        (xy 10.656 4.023)
        (xy 10.679 4.015)
        (xy 10.701 4.01)
        (xy 10.723 4.005)
        (xy 10.746 4.002)
        (xy 10.771 4.002)
        (xy 10.794 4)
        (xy 10.817 4.002)
        (xy 10.842 4.002)
        (xy 10.864 4.005)
        (xy 10.887 4.01)
        (xy 10.909 4.015)
        (xy 10.932 4.023)
        (xy 10.954 4.031)
        (xy 10.976 4.039)
        (xy 10.996 4.05)
        (xy 11.018 4.06)
        (xy 11.037 4.072)
        (xy 11.057 4.085)
        (xy 11.074 4.1)
        (xy 11.092 4.114)
        (xy 11.109 4.13)
        (xy 11.125 4.148)
        (xy 11.14 4.165)
        (xy 11.154 4.183)
        (xy 11.167 4.204)
        (xy 11.179 4.223)
        (xy 11.191 4.244)
        (xy 11.201 4.265)
        (xy 11.21 4.286)
        (xy 11.217 4.308)
        (xy 11.224 4.33)
        (xy 11.23 4.353)
        (xy 11.234 4.375)
        (xy 11.237 4.398)
        (xy 11.239 4.422)
        (xy 11.239 4.446)
        (xy 11.239 4.468)
        (xy 11.237 4.492)
        (xy 11.234 4.515)
        (xy 11.23 4.539)
        (xy 11.224 4.56)
        (xy 11.217 4.584)
        (xy 11.21 4.604)
        (xy 11.201 4.627)
        (xy 11.191 4.648)
        (xy 11.179 4.669)
        (xy 11.167 4.688)
        (xy 11.154 4.707)
        (xy 11.14 4.725)
        (xy 11.125 4.744)
        (xy 11.109 4.76)
        (xy 11.092 4.776)
        (xy 11.074 4.792)
        (xy 11.057 4.805)
        (xy 11.037 4.818)
        (xy 11.018 4.83)
        (xy 10.996 4.842)
        (xy 10.976 4.853)
        (xy 10.954 4.861)
        (xy 10.932 4.869)
        (xy 10.909 4.875)
        (xy 10.887 4.88)
        (xy 10.864 4.885)
        (xy 10.842 4.888)
        (xy 10.817 4.89)
        (xy 10.794 4.89)
        (xy 10.771 4.89)
        (xy 10.746 4.888)
        (xy 10.723 4.885)
        (xy 10.701 4.88)
        (xy 10.679 4.875)
        (xy 10.656 4.869)
        (xy 10.634 4.861)
        (xy 10.612 4.853)
        (xy 10.592 4.842)
        (xy 10.571 4.832)
        (xy 10.551 4.818)
        (xy 10.532 4.805)
        (xy 10.513 4.792)
        (xy 10.496 4.776)
        (xy 10.48 4.76)
        (xy 10.464 4.744)
        (xy 10.448 4.726)
        (xy 10.435 4.707)
        (xy 10.422 4.688)
        (xy 10.409 4.669)
        (xy 10.397 4.648)
        (xy 10.387 4.627)
        (xy 10.378 4.606)
        (xy 10.371 4.584)
        (xy 10.364 4.561)
        (xy 10.359 4.539)
        (xy 10.355 4.516)
        (xy 10.352 4.494)
        (xy 10.351 4.47)
        (xy 10.349 4.447)
        (xy 10.794 4.447)
        (xy 10.794 4.443)
      )

      (stroke (width 0.001) (type solid)) (fill solid) (layer "B.Paste"))
    (fp_poly
      (pts
        (xy 10.794 5.713)
        (xy 10.349 5.713)
        (xy 10.351 5.691)
        (xy 10.352 5.667)
        (xy 10.355 5.645)
        (xy 10.359 5.622)
        (xy 10.364 5.6)
        (xy 10.371 5.577)
        (xy 10.378 5.555)
        (xy 10.387 5.534)
        (xy 10.397 5.512)
        (xy 10.409 5.492)
        (xy 10.422 5.473)
        (xy 10.435 5.454)
        (xy 10.448 5.435)
        (xy 10.464 5.417)
        (xy 10.48 5.401)
        (xy 10.496 5.385)
        (xy 10.513 5.369)
        (xy 10.532 5.356)
        (xy 10.551 5.342)
        (xy 10.571 5.329)
        (xy 10.592 5.318)
        (xy 10.612 5.308)
        (xy 10.634 5.3)
        (xy 10.656 5.292)
        (xy 10.679 5.286)
        (xy 10.701 5.281)
        (xy 10.723 5.276)
        (xy 10.746 5.273)
        (xy 10.771 5.271)
        (xy 10.794 5.27)
        (xy 10.817 5.271)
        (xy 10.842 5.273)
        (xy 10.864 5.276)
        (xy 10.887 5.281)
        (xy 10.909 5.286)
        (xy 10.932 5.292)
        (xy 10.954 5.3)
        (xy 10.976 5.308)
        (xy 10.996 5.319)
        (xy 11.018 5.33)
        (xy 11.037 5.342)
        (xy 11.057 5.356)
        (xy 11.074 5.369)
        (xy 11.092 5.385)
        (xy 11.109 5.401)
        (xy 11.125 5.417)
        (xy 11.14 5.435)
        (xy 11.154 5.454)
        (xy 11.167 5.473)
        (xy 11.179 5.492)
        (xy 11.191 5.513)
        (xy 11.201 5.534)
        (xy 11.21 5.556)
        (xy 11.217 5.577)
        (xy 11.224 5.6)
        (xy 11.23 5.622)
        (xy 11.234 5.645)
        (xy 11.237 5.669)
        (xy 11.239 5.693)
        (xy 11.239 5.715)
        (xy 11.239 5.739)
        (xy 11.237 5.762)
        (xy 11.234 5.786)
        (xy 11.23 5.808)
        (xy 11.224 5.83)
        (xy 11.217 5.853)
        (xy 11.21 5.874)
        (xy 11.201 5.896)
        (xy 11.191 5.917)
        (xy 11.179 5.938)
        (xy 11.167 5.957)
        (xy 11.154 5.978)
        (xy 11.14 5.995)
        (xy 11.125 6.013)
        (xy 11.109 6.031)
        (xy 11.092 6.047)
        (xy 11.074 6.061)
        (xy 11.057 6.076)
        (xy 11.037 6.088)
        (xy 11.018 6.1)
        (xy 10.996 6.111)
        (xy 10.976 6.122)
        (xy 10.954 6.13)
        (xy 10.932 6.138)
        (xy 10.909 6.145)
        (xy 10.887 6.151)
        (xy 10.864 6.156)
        (xy 10.842 6.159)
        (xy 10.817 6.159)
        (xy 10.794 6.161)
        (xy 10.771 6.159)
        (xy 10.746 6.159)
        (xy 10.723 6.156)
        (xy 10.701 6.151)
        (xy 10.679 6.145)
        (xy 10.656 6.138)
        (xy 10.634 6.132)
        (xy 10.612 6.122)
        (xy 10.592 6.112)
        (xy 10.571 6.101)
        (xy 10.551 6.088)
        (xy 10.532 6.076)
        (xy 10.513 6.061)
        (xy 10.496 6.047)
        (xy 10.48 6.031)
        (xy 10.464 6.013)
        (xy 10.448 5.997)
        (xy 10.435 5.978)
        (xy 10.422 5.959)
        (xy 10.409 5.938)
        (xy 10.397 5.919)
        (xy 10.387 5.898)
        (xy 10.378 5.875)
        (xy 10.371 5.853)
        (xy 10.364 5.832)
        (xy 10.359 5.81)
        (xy 10.355 5.786)
        (xy 10.352 5.763)
        (xy 10.351 5.739)
        (xy 10.349 5.718)
        (xy 10.794 5.718)
        (xy 10.794 5.713)
      )

      (stroke (width 0.001) (type solid)) (fill solid) (layer "B.Paste"))
    (fp_poly
      (pts
        (xy 12.064 -5.717)
        (xy 11.619 -5.717)
        (xy 11.621 -5.738)
        (xy 11.621 -5.762)
        (xy 11.624 -5.785)
        (xy 11.63 -5.809)
        (xy 11.634 -5.831)
        (xy 11.641 -5.852)
        (xy 11.648 -5.874)
        (xy 11.657 -5.897)
        (xy 11.667 -5.918)
        (xy 11.679 -5.937)
        (xy 11.691 -5.958)
        (xy 11.704 -5.977)
        (xy 11.718 -5.996)
        (xy 11.733 -6.012)
        (xy 11.749 -6.03)
        (xy 11.766 -6.046)
        (xy 11.784 -6.06)
        (xy 11.803 -6.075)
        (xy 11.821 -6.087)
        (xy 11.842 -6.1)
        (xy 11.861 -6.111)
        (xy 11.882 -6.121)
        (xy 11.904 -6.131)
        (xy 11.926 -6.137)
        (xy 11.948 -6.144)
        (xy 11.97 -6.15)
        (xy 11.993 -6.155)
        (xy 12.016 -6.158)
        (xy 12.041 -6.158)
        (xy 12.064 -6.16)
        (xy 12.087 -6.158)
        (xy 12.111 -6.158)
        (xy 12.134 -6.155)
        (xy 12.157 -6.15)
        (xy 12.179 -6.144)
        (xy 12.202 -6.137)
        (xy 12.223 -6.129)
        (xy 12.246 -6.121)
        (xy 12.266 -6.11)
        (xy 12.287 -6.099)
        (xy 12.307 -6.087)
        (xy 12.326 -6.075)
        (xy 12.345 -6.06)
        (xy 12.362 -6.046)
        (xy 12.38 -6.03)
        (xy 12.396 -6.012)
        (xy 12.41 -5.994)
        (xy 12.425 -5.977)
        (xy 12.438 -5.956)
        (xy 12.449 -5.937)
        (xy 12.461 -5.916)
        (xy 12.471 -5.895)
        (xy 12.48 -5.873)
        (xy 12.487 -5.852)
        (xy 12.494 -5.829)
        (xy 12.499 -5.807)
        (xy 12.505 -5.785)
        (xy 12.507 -5.761)
        (xy 12.509 -5.738)
        (xy 12.509 -5.714)
        (xy 12.509 -5.692)
        (xy 12.507 -5.668)
        (xy 12.505 -5.644)
        (xy 12.499 -5.621)
        (xy 12.494 -5.599)
        (xy 12.487 -5.576)
        (xy 12.48 -5.555)
        (xy 12.471 -5.533)
        (xy 12.461 -5.512)
        (xy 12.449 -5.491)
        (xy 12.438 -5.472)
        (xy 12.425 -5.453)
        (xy 12.41 -5.434)
        (xy 12.396 -5.416)
        (xy 12.38 -5.4)
        (xy 12.362 -5.384)
        (xy 12.345 -5.368)
        (xy 12.326 -5.355)
        (xy 12.307 -5.341)
        (xy 12.287 -5.329)
        (xy 12.266 -5.318)
        (xy 12.246 -5.307)
        (xy 12.223 -5.299)
        (xy 12.202 -5.291)
        (xy 12.179 -5.285)
        (xy 12.157 -5.28)
        (xy 12.134 -5.275)
        (xy 12.111 -5.272)
        (xy 12.087 -5.27)
        (xy 12.064 -5.269)
        (xy 12.041 -5.27)
        (xy 12.016 -5.272)
        (xy 11.993 -5.275)
        (xy 11.97 -5.28)
        (xy 11.948 -5.285)
        (xy 11.926 -5.291)
        (xy 11.904 -5.299)
        (xy 11.882 -5.307)
        (xy 11.861 -5.317)
        (xy 11.842 -5.328)
        (xy 11.821 -5.341)
        (xy 11.803 -5.355)
        (xy 11.784 -5.368)
        (xy 11.766 -5.384)
        (xy 11.749 -5.4)
        (xy 11.733 -5.416)
        (xy 11.718 -5.434)
        (xy 11.704 -5.453)
        (xy 11.691 -5.472)
        (xy 11.679 -5.491)
        (xy 11.667 -5.511)
        (xy 11.657 -5.533)
        (xy 11.648 -5.554)
        (xy 11.641 -5.576)
        (xy 11.634 -5.599)
        (xy 11.63 -5.621)
        (xy 11.624 -5.644)
        (xy 11.621 -5.666)
        (xy 11.621 -5.69)
        (xy 11.619 -5.712)
        (xy 12.064 -5.712)
        (xy 12.064 -5.717)
      )

      (stroke (width 0.001) (type solid)) (fill solid) (layer "B.Paste"))
    (fp_poly
      (pts
        (xy 12.064 -3.177)
        (xy 11.619 -3.177)
        (xy 11.621 -3.198)
        (xy 11.621 -3.222)
        (xy 11.624 -3.245)
        (xy 11.63 -3.269)
        (xy 11.634 -3.29)
        (xy 11.641 -3.313)
        (xy 11.648 -3.334)
        (xy 11.657 -3.357)
        (xy 11.667 -3.378)
        (xy 11.679 -3.398)
        (xy 11.691 -3.418)
        (xy 11.704 -3.436)
        (xy 11.718 -3.455)
        (xy 11.733 -3.472)
        (xy 11.749 -3.49)
        (xy 11.766 -3.505)
        (xy 11.784 -3.52)
        (xy 11.803 -3.535)
        (xy 11.821 -3.547)
        (xy 11.842 -3.56)
        (xy 11.861 -3.571)
        (xy 11.882 -3.581)
        (xy 11.904 -3.591)
        (xy 11.926 -3.597)
        (xy 11.948 -3.604)
        (xy 11.97 -3.609)
        (xy 11.993 -3.615)
        (xy 12.016 -3.617)
        (xy 12.041 -3.619)
        (xy 12.064 -3.62)
        (xy 12.087 -3.619)
        (xy 12.111 -3.617)
        (xy 12.134 -3.615)
        (xy 12.157 -3.609)
        (xy 12.179 -3.604)
        (xy 12.202 -3.597)
        (xy 12.223 -3.589)
        (xy 12.246 -3.581)
        (xy 12.266 -3.571)
        (xy 12.287 -3.559)
        (xy 12.307 -3.547)
        (xy 12.326 -3.535)
        (xy 12.345 -3.52)
        (xy 12.362 -3.505)
        (xy 12.38 -3.49)
        (xy 12.396 -3.472)
        (xy 12.41 -3.454)
        (xy 12.425 -3.436)
        (xy 12.438 -3.416)
        (xy 12.449 -3.396)
        (xy 12.461 -3.376)
        (xy 12.471 -3.355)
        (xy 12.48 -3.334)
        (xy 12.487 -3.313)
        (xy 12.494 -3.289)
        (xy 12.499 -3.267)
        (xy 12.505 -3.245)
        (xy 12.507 -3.221)
        (xy 12.509 -3.197)
        (xy 12.509 -3.174)
        (xy 12.509 -3.152)
        (xy 12.507 -3.128)
        (xy 12.505 -3.104)
        (xy 12.499 -3.081)
        (xy 12.494 -3.059)
        (xy 12.487 -3.036)
        (xy 12.48 -3.015)
        (xy 12.471 -2.994)
        (xy 12.461 -2.972)
        (xy 12.449 -2.951)
        (xy 12.438 -2.932)
        (xy 12.425 -2.912)
        (xy 12.41 -2.894)
        (xy 12.396 -2.876)
        (xy 12.38 -2.859)
        (xy 12.362 -2.843)
        (xy 12.345 -2.829)
        (xy 12.326 -2.814)
        (xy 12.307 -2.801)
        (xy 12.287 -2.789)
        (xy 12.266 -2.778)
        (xy 12.246 -2.767)
        (xy 12.223 -2.759)
        (xy 12.202 -2.751)
        (xy 12.179 -2.745)
        (xy 12.157 -2.74)
        (xy 12.134 -2.734)
        (xy 12.111 -2.732)
        (xy 12.087 -2.73)
        (xy 12.064 -2.729)
        (xy 12.041 -2.73)
        (xy 12.016 -2.732)
        (xy 11.993 -2.734)
        (xy 11.97 -2.74)
        (xy 11.948 -2.745)
        (xy 11.926 -2.751)
        (xy 11.904 -2.758)
        (xy 11.882 -2.767)
        (xy 11.861 -2.777)
        (xy 11.842 -2.789)
        (xy 11.821 -2.801)
        (xy 11.803 -2.814)
        (xy 11.784 -2.829)
        (xy 11.766 -2.843)
        (xy 11.749 -2.859)
        (xy 11.733 -2.876)
        (xy 11.718 -2.894)
        (xy 11.704 -2.912)
        (xy 11.691 -2.931)
        (xy 11.679 -2.951)
        (xy 11.667 -2.971)
        (xy 11.657 -2.992)
        (xy 11.648 -3.015)
        (xy 11.641 -3.036)
        (xy 11.634 -3.059)
        (xy 11.63 -3.08)
        (xy 11.624 -3.104)
        (xy 11.621 -3.126)
        (xy 11.621 -3.15)
        (xy 11.619 -3.172)
        (xy 12.064 -3.172)
        (xy 12.064 -3.177)
      )

      (stroke (width 0.001) (type solid)) (fill solid) (layer "B.Paste"))
    (fp_poly
      (pts
        (xy 12.064 1.903)
        (xy 11.619 1.903)
        (xy 11.621 1.881)
        (xy 11.621 1.857)
        (xy 11.624 1.835)
        (xy 11.63 1.811)
        (xy 11.634 1.789)
        (xy 11.641 1.767)
        (xy 11.648 1.746)
        (xy 11.657 1.724)
        (xy 11.667 1.702)
        (xy 11.679 1.682)
        (xy 11.691 1.662)
        (xy 11.704 1.643)
        (xy 11.718 1.625)
        (xy 11.733 1.607)
        (xy 11.749 1.591)
        (xy 11.766 1.575)
        (xy 11.784 1.559)
        (xy 11.803 1.545)
        (xy 11.821 1.532)
        (xy 11.842 1.519)
        (xy 11.861 1.508)
        (xy 11.882 1.498)
        (xy 11.904 1.49)
        (xy 11.926 1.482)
        (xy 11.948 1.476)
        (xy 11.97 1.47)
        (xy 11.993 1.466)
        (xy 12.016 1.462)
        (xy 12.041 1.462)
        (xy 12.064 1.46)
        (xy 12.087 1.462)
        (xy 12.111 1.462)
        (xy 12.134 1.466)
        (xy 12.157 1.47)
        (xy 12.179 1.476)
        (xy 12.202 1.482)
        (xy 12.223 1.49)
        (xy 12.246 1.498)
        (xy 12.266 1.509)
        (xy 12.287 1.52)
        (xy 12.307 1.532)
        (xy 12.326 1.545)
        (xy 12.345 1.559)
        (xy 12.362 1.575)
        (xy 12.38 1.591)
        (xy 12.396 1.607)
        (xy 12.41 1.625)
        (xy 12.425 1.643)
        (xy 12.438 1.663)
        (xy 12.449 1.684)
        (xy 12.461 1.704)
        (xy 12.471 1.724)
        (xy 12.48 1.746)
        (xy 12.487 1.767)
        (xy 12.494 1.79)
        (xy 12.499 1.813)
        (xy 12.505 1.835)
        (xy 12.507 1.859)
        (xy 12.509 1.882)
        (xy 12.509 1.905)
        (xy 12.509 1.928)
        (xy 12.507 1.952)
        (xy 12.505 1.976)
        (xy 12.499 1.998)
        (xy 12.494 2.02)
        (xy 12.487 2.044)
        (xy 12.48 2.065)
        (xy 12.471 2.086)
        (xy 12.461 2.108)
        (xy 12.449 2.127)
        (xy 12.438 2.147)
        (xy 12.425 2.167)
        (xy 12.41 2.186)
        (xy 12.396 2.203)
        (xy 12.38 2.221)
        (xy 12.362 2.237)
        (xy 12.345 2.251)
        (xy 12.326 2.266)
        (xy 12.307 2.278)
        (xy 12.287 2.29)
        (xy 12.266 2.302)
        (xy 12.246 2.312)
        (xy 12.223 2.32)
        (xy 12.202 2.328)
        (xy 12.179 2.335)
        (xy 12.157 2.34)
        (xy 12.134 2.346)
        (xy 12.111 2.348)
        (xy 12.087 2.35)
        (xy 12.064 2.351)
        (xy 12.041 2.35)
        (xy 12.016 2.348)
        (xy 11.993 2.346)
        (xy 11.97 2.34)
        (xy 11.948 2.335)
        (xy 11.926 2.328)
        (xy 11.904 2.322)
        (xy 11.882 2.312)
        (xy 11.861 2.302)
        (xy 11.842 2.291)
        (xy 11.821 2.278)
        (xy 11.803 2.266)
        (xy 11.784 2.251)
        (xy 11.766 2.237)
        (xy 11.749 2.221)
        (xy 11.733 2.203)
        (xy 11.718 2.186)
        (xy 11.704 2.167)
        (xy 11.691 2.149)
        (xy 11.679 2.129)
        (xy 11.667 2.109)
        (xy 11.657 2.088)
        (xy 11.648 2.065)
        (xy 11.641 2.044)
        (xy 11.634 2.021)
        (xy 11.63 2)
        (xy 11.624 1.976)
        (xy 11.621 1.954)
        (xy 11.621 1.93)
        (xy 11.619 1.907)
        (xy 12.064 1.907)
        (xy 12.064 1.903)
      )

      (stroke (width 0.001) (type solid)) (fill solid) (layer "B.Paste"))
    (fp_poly
      (pts
        (xy 12.064 3.173)
        (xy 11.619 3.173)
        (xy 11.621 3.151)
        (xy 11.621 3.127)
        (xy 11.624 3.105)
        (xy 11.63 3.081)
        (xy 11.634 3.06)
        (xy 11.641 3.037)
        (xy 11.648 3.016)
        (xy 11.657 2.993)
        (xy 11.667 2.972)
        (xy 11.679 2.952)
        (xy 11.691 2.932)
        (xy 11.704 2.913)
        (xy 11.718 2.895)
        (xy 11.733 2.877)
        (xy 11.749 2.86)
        (xy 11.766 2.844)
        (xy 11.784 2.83)
        (xy 11.803 2.815)
        (xy 11.821 2.802)
        (xy 11.842 2.79)
        (xy 11.861 2.778)
        (xy 11.882 2.768)
        (xy 11.904 2.759)
        (xy 11.926 2.752)
        (xy 11.948 2.746)
        (xy 11.97 2.741)
        (xy 11.993 2.735)
        (xy 12.016 2.733)
        (xy 12.041 2.731)
        (xy 12.064 2.73)
        (xy 12.087 2.731)
        (xy 12.111 2.733)
        (xy 12.134 2.735)
        (xy 12.157 2.741)
        (xy 12.179 2.746)
        (xy 12.202 2.752)
        (xy 12.223 2.76)
        (xy 12.246 2.768)
        (xy 12.266 2.779)
        (xy 12.287 2.79)
        (xy 12.307 2.802)
        (xy 12.326 2.815)
        (xy 12.345 2.83)
        (xy 12.362 2.844)
        (xy 12.38 2.86)
        (xy 12.396 2.877)
        (xy 12.41 2.895)
        (xy 12.425 2.913)
        (xy 12.438 2.933)
        (xy 12.449 2.952)
        (xy 12.461 2.973)
        (xy 12.471 2.995)
        (xy 12.48 3.016)
        (xy 12.487 3.037)
        (xy 12.494 3.06)
        (xy 12.499 3.082)
        (xy 12.505 3.105)
        (xy 12.507 3.129)
        (xy 12.509 3.153)
        (xy 12.509 3.175)
        (xy 12.509 3.198)
        (xy 12.507 3.222)
        (xy 12.505 3.246)
        (xy 12.499 3.268)
        (xy 12.494 3.29)
        (xy 12.487 3.314)
        (xy 12.48 3.335)
        (xy 12.471 3.356)
        (xy 12.461 3.377)
        (xy 12.449 3.397)
        (xy 12.438 3.417)
        (xy 12.425 3.437)
        (xy 12.41 3.455)
        (xy 12.396 3.473)
        (xy 12.38 3.491)
        (xy 12.362 3.506)
        (xy 12.345 3.521)
        (xy 12.326 3.536)
        (xy 12.307 3.548)
        (xy 12.287 3.56)
        (xy 12.266 3.572)
        (xy 12.246 3.582)
        (xy 12.223 3.59)
        (xy 12.202 3.598)
        (xy 12.179 3.605)
        (xy 12.157 3.61)
        (xy 12.134 3.616)
        (xy 12.111 3.618)
        (xy 12.087 3.62)
        (xy 12.064 3.621)
        (xy 12.041 3.62)
        (xy 12.016 3.618)
        (xy 11.993 3.616)
        (xy 11.97 3.61)
        (xy 11.948 3.605)
        (xy 11.926 3.598)
        (xy 11.904 3.592)
        (xy 11.882 3.582)
        (xy 11.861 3.572)
        (xy 11.842 3.561)
        (xy 11.821 3.548)
        (xy 11.803 3.536)
        (xy 11.784 3.521)
        (xy 11.766 3.506)
        (xy 11.749 3.491)
        (xy 11.733 3.473)
        (xy 11.718 3.456)
        (xy 11.704 3.437)
        (xy 11.691 3.419)
        (xy 11.679 3.399)
        (xy 11.667 3.379)
        (xy 11.657 3.358)
        (xy 11.648 3.335)
        (xy 11.641 3.314)
        (xy 11.634 3.291)
        (xy 11.63 3.27)
        (xy 11.624 3.246)
        (xy 11.621 3.223)
        (xy 11.621 3.199)
        (xy 11.619 3.178)
        (xy 12.064 3.178)
        (xy 12.064 3.173)
      )

      (stroke (width 0.001) (type solid)) (fill solid) (layer "B.Paste"))
    (fp_poly
      (pts
        (xy 12.064 4.443)
        (xy 11.619 4.443)
        (xy 11.621 4.422)
        (xy 11.621 4.398)
        (xy 11.624 4.374)
        (xy 11.63 4.351)
        (xy 11.634 4.329)
        (xy 11.641 4.308)
        (xy 11.648 4.286)
        (xy 11.657 4.263)
        (xy 11.667 4.242)
        (xy 11.679 4.223)
        (xy 11.691 4.202)
        (xy 11.704 4.183)
        (xy 11.718 4.164)
        (xy 11.733 4.148)
        (xy 11.749 4.13)
        (xy 11.766 4.114)
        (xy 11.784 4.1)
        (xy 11.803 4.085)
        (xy 11.821 4.072)
        (xy 11.842 4.06)
        (xy 11.861 4.048)
        (xy 11.882 4.039)
        (xy 11.904 4.029)
        (xy 11.926 4.023)
        (xy 11.948 4.015)
        (xy 11.97 4.01)
        (xy 11.993 4.005)
        (xy 12.016 4.002)
        (xy 12.041 4.002)
        (xy 12.064 4)
        (xy 12.087 4.002)
        (xy 12.111 4.002)
        (xy 12.134 4.005)
        (xy 12.157 4.01)
        (xy 12.179 4.015)
        (xy 12.202 4.023)
        (xy 12.223 4.031)
        (xy 12.246 4.039)
        (xy 12.266 4.05)
        (xy 12.287 4.06)
        (xy 12.307 4.072)
        (xy 12.326 4.085)
        (xy 12.345 4.1)
        (xy 12.362 4.114)
        (xy 12.38 4.13)
        (xy 12.396 4.148)
        (xy 12.41 4.165)
        (xy 12.425 4.183)
        (xy 12.438 4.204)
        (xy 12.449 4.223)
        (xy 12.461 4.244)
        (xy 12.471 4.265)
        (xy 12.48 4.286)
        (xy 12.487 4.308)
        (xy 12.494 4.33)
        (xy 12.499 4.353)
        (xy 12.505 4.375)
        (xy 12.507 4.398)
        (xy 12.509 4.422)
        (xy 12.509 4.446)
        (xy 12.509 4.468)
        (xy 12.507 4.492)
        (xy 12.505 4.515)
        (xy 12.499 4.539)
        (xy 12.494 4.56)
        (xy 12.487 4.584)
        (xy 12.48 4.604)
        (xy 12.471 4.627)
        (xy 12.461 4.648)
        (xy 12.449 4.669)
        (xy 12.438 4.688)
        (xy 12.425 4.707)
        (xy 12.41 4.725)
        (xy 12.396 4.744)
        (xy 12.38 4.76)
        (xy 12.362 4.776)
        (xy 12.345 4.792)
        (xy 12.326 4.805)
        (xy 12.307 4.818)
        (xy 12.287 4.83)
        (xy 12.266 4.842)
        (xy 12.246 4.853)
        (xy 12.223 4.861)
        (xy 12.202 4.869)
        (xy 12.179 4.875)
        (xy 12.157 4.88)
        (xy 12.134 4.885)
        (xy 12.111 4.888)
        (xy 12.087 4.89)
        (xy 12.064 4.89)
        (xy 12.041 4.89)
        (xy 12.016 4.888)
        (xy 11.993 4.885)
        (xy 11.97 4.88)
        (xy 11.948 4.875)
        (xy 11.926 4.869)
        (xy 11.904 4.861)
        (xy 11.882 4.853)
        (xy 11.861 4.842)
        (xy 11.842 4.832)
        (xy 11.821 4.818)
        (xy 11.803 4.805)
        (xy 11.784 4.792)
        (xy 11.766 4.776)
        (xy 11.749 4.76)
        (xy 11.733 4.744)
        (xy 11.718 4.726)
        (xy 11.704 4.707)
        (xy 11.691 4.688)
        (xy 11.679 4.669)
        (xy 11.667 4.648)
        (xy 11.657 4.627)
        (xy 11.648 4.606)
        (xy 11.641 4.584)
        (xy 11.634 4.561)
        (xy 11.63 4.539)
        (xy 11.624 4.516)
        (xy 11.621 4.494)
        (xy 11.621 4.47)
        (xy 11.619 4.447)
        (xy 12.064 4.447)
        (xy 12.064 4.443)
      )

      (stroke (width 0.001) (type solid)) (fill solid) (layer "B.Paste"))
    (fp_poly
      (pts
        (xy 12.064 5.713)
        (xy 11.619 5.713)
        (xy 11.621 5.691)
        (xy 11.621 5.667)
        (xy 11.624 5.645)
        (xy 11.63 5.622)
        (xy 11.634 5.6)
        (xy 11.641 5.577)
        (xy 11.648 5.555)
        (xy 11.657 5.534)
        (xy 11.667 5.512)
        (xy 11.679 5.492)
        (xy 11.691 5.473)
        (xy 11.704 5.454)
        (xy 11.718 5.435)
        (xy 11.733 5.417)
        (xy 11.749 5.401)
        (xy 11.766 5.385)
        (xy 11.784 5.369)
        (xy 11.803 5.356)
        (xy 11.821 5.342)
        (xy 11.842 5.329)
        (xy 11.861 5.318)
        (xy 11.882 5.308)
        (xy 11.904 5.3)
        (xy 11.926 5.292)
        (xy 11.948 5.286)
        (xy 11.97 5.281)
        (xy 11.993 5.276)
        (xy 12.016 5.273)
        (xy 12.041 5.271)
        (xy 12.064 5.27)
        (xy 12.087 5.271)
        (xy 12.111 5.273)
        (xy 12.134 5.276)
        (xy 12.157 5.281)
        (xy 12.179 5.286)
        (xy 12.202 5.292)
        (xy 12.223 5.3)
        (xy 12.246 5.308)
        (xy 12.266 5.319)
        (xy 12.287 5.33)
        (xy 12.307 5.342)
        (xy 12.326 5.356)
        (xy 12.345 5.369)
        (xy 12.362 5.385)
        (xy 12.38 5.401)
        (xy 12.396 5.417)
        (xy 12.41 5.435)
        (xy 12.425 5.454)
        (xy 12.438 5.473)
        (xy 12.449 5.492)
        (xy 12.461 5.513)
        (xy 12.471 5.534)
        (xy 12.48 5.556)
        (xy 12.487 5.577)
        (xy 12.494 5.6)
        (xy 12.499 5.622)
        (xy 12.505 5.645)
        (xy 12.507 5.669)
        (xy 12.509 5.693)
        (xy 12.509 5.715)
        (xy 12.509 5.739)
        (xy 12.507 5.762)
        (xy 12.505 5.786)
        (xy 12.499 5.808)
        (xy 12.494 5.83)
        (xy 12.487 5.853)
        (xy 12.48 5.874)
        (xy 12.471 5.896)
        (xy 12.461 5.917)
        (xy 12.449 5.938)
        (xy 12.438 5.957)
        (xy 12.425 5.978)
        (xy 12.41 5.995)
        (xy 12.396 6.013)
        (xy 12.38 6.031)
        (xy 12.362 6.047)
        (xy 12.345 6.061)
        (xy 12.326 6.076)
        (xy 12.307 6.088)
        (xy 12.287 6.1)
        (xy 12.266 6.111)
        (xy 12.246 6.122)
        (xy 12.223 6.13)
        (xy 12.202 6.138)
        (xy 12.179 6.145)
        (xy 12.157 6.151)
        (xy 12.134 6.156)
        (xy 12.111 6.159)
        (xy 12.087 6.159)
        (xy 12.064 6.161)
        (xy 12.041 6.159)
        (xy 12.016 6.159)
        (xy 11.993 6.156)
        (xy 11.97 6.151)
        (xy 11.948 6.145)
        (xy 11.926 6.138)
        (xy 11.904 6.132)
        (xy 11.882 6.122)
        (xy 11.861 6.112)
        (xy 11.842 6.101)
        (xy 11.821 6.088)
        (xy 11.803 6.076)
        (xy 11.784 6.061)
        (xy 11.766 6.047)
        (xy 11.749 6.031)
        (xy 11.733 6.013)
        (xy 11.718 5.997)
        (xy 11.704 5.978)
        (xy 11.691 5.959)
        (xy 11.679 5.938)
        (xy 11.667 5.919)
        (xy 11.657 5.898)
        (xy 11.648 5.875)
        (xy 11.641 5.853)
        (xy 11.634 5.832)
        (xy 11.63 5.81)
        (xy 11.624 5.786)
        (xy 11.621 5.763)
        (xy 11.621 5.739)
        (xy 11.619 5.718)
        (xy 12.064 5.718)
        (xy 12.064 5.713)
      )

      (stroke (width 0.001) (type solid)) (fill solid) (layer "B.Paste"))
    (fp_poly
      (pts
        (xy 13.335 -5.717)
        (xy 12.89 -5.717)
        (xy 12.89 -5.738)
        (xy 12.891 -5.762)
        (xy 12.894 -5.785)
        (xy 12.9 -5.809)
        (xy 12.904 -5.831)
        (xy 12.912 -5.852)
        (xy 12.919 -5.874)
        (xy 12.928 -5.897)
        (xy 12.938 -5.918)
        (xy 12.948 -5.937)
        (xy 12.961 -5.958)
        (xy 12.974 -5.977)
        (xy 12.989 -5.996)
        (xy 13.003 -6.012)
        (xy 13.019 -6.03)
        (xy 13.037 -6.046)
        (xy 13.053 -6.06)
        (xy 13.073 -6.075)
        (xy 13.092 -6.087)
        (xy 13.111 -6.1)
        (xy 13.131 -6.111)
        (xy 13.153 -6.121)
        (xy 13.175 -6.131)
        (xy 13.196 -6.137)
        (xy 13.218 -6.144)
        (xy 13.24 -6.15)
        (xy 13.263 -6.155)
        (xy 13.287 -6.158)
        (xy 13.31 -6.158)
        (xy 13.335 -6.16)
        (xy 13.358 -6.158)
        (xy 13.381 -6.158)
        (xy 13.404 -6.155)
        (xy 13.428 -6.15)
        (xy 13.449 -6.144)
        (xy 13.473 -6.137)
        (xy 13.493 -6.129)
        (xy 13.515 -6.121)
        (xy 13.537 -6.11)
        (xy 13.557 -6.099)
        (xy 13.576 -6.087)
        (xy 13.596 -6.075)
        (xy 13.614 -6.06)
        (xy 13.632 -6.046)
        (xy 13.65 -6.03)
        (xy 13.666 -6.012)
        (xy 13.68 -5.994)
        (xy 13.694 -5.977)
        (xy 13.707 -5.956)
        (xy 13.72 -5.937)
        (xy 13.73 -5.916)
        (xy 13.742 -5.895)
        (xy 13.749 -5.873)
        (xy 13.757 -5.852)
        (xy 13.765 -5.829)
        (xy 13.769 -5.807)
        (xy 13.775 -5.785)
        (xy 13.778 -5.761)
        (xy 13.778 -5.738)
        (xy 13.779 -5.714)
        (xy 13.778 -5.692)
        (xy 13.778 -5.668)
        (xy 13.775 -5.644)
        (xy 13.769 -5.621)
        (xy 13.765 -5.599)
        (xy 13.757 -5.576)
        (xy 13.749 -5.555)
        (xy 13.742 -5.533)
        (xy 13.73 -5.512)
        (xy 13.72 -5.491)
        (xy 13.707 -5.472)
        (xy 13.694 -5.453)
        (xy 13.68 -5.434)
        (xy 13.666 -5.416)
        (xy 13.65 -5.4)
        (xy 13.632 -5.384)
        (xy 13.614 -5.368)
        (xy 13.596 -5.355)
        (xy 13.576 -5.341)
        (xy 13.557 -5.329)
        (xy 13.537 -5.318)
        (xy 13.515 -5.307)
        (xy 13.493 -5.299)
        (xy 13.473 -5.291)
        (xy 13.449 -5.285)
        (xy 13.428 -5.28)
        (xy 13.404 -5.275)
        (xy 13.381 -5.272)
        (xy 13.358 -5.27)
        (xy 13.335 -5.269)
        (xy 13.31 -5.27)
        (xy 13.287 -5.272)
        (xy 13.263 -5.275)
        (xy 13.24 -5.28)
        (xy 13.218 -5.285)
        (xy 13.196 -5.291)
        (xy 13.175 -5.299)
        (xy 13.153 -5.307)
        (xy 13.131 -5.317)
        (xy 13.111 -5.328)
        (xy 13.092 -5.341)
        (xy 13.073 -5.355)
        (xy 13.053 -5.368)
        (xy 13.037 -5.384)
        (xy 13.019 -5.4)
        (xy 13.003 -5.416)
        (xy 12.989 -5.434)
        (xy 12.974 -5.453)
        (xy 12.961 -5.472)
        (xy 12.948 -5.491)
        (xy 12.938 -5.511)
        (xy 12.928 -5.533)
        (xy 12.919 -5.554)
        (xy 12.912 -5.576)
        (xy 12.904 -5.599)
        (xy 12.9 -5.621)
        (xy 12.894 -5.644)
        (xy 12.891 -5.666)
        (xy 12.89 -5.69)
        (xy 12.89 -5.712)
        (xy 13.335 -5.712)
        (xy 13.335 -5.717)
      )

      (stroke (width 0.001) (type solid)) (fill solid) (layer "B.Paste"))
    (fp_poly
      (pts
        (xy 13.335 -3.177)
        (xy 12.89 -3.177)
        (xy 12.89 -3.198)
        (xy 12.891 -3.222)
        (xy 12.894 -3.245)
        (xy 12.9 -3.269)
        (xy 12.904 -3.29)
        (xy 12.912 -3.313)
        (xy 12.919 -3.334)
        (xy 12.928 -3.357)
        (xy 12.938 -3.378)
        (xy 12.948 -3.398)
        (xy 12.961 -3.418)
        (xy 12.974 -3.436)
        (xy 12.989 -3.455)
        (xy 13.003 -3.472)
        (xy 13.019 -3.49)
        (xy 13.037 -3.505)
        (xy 13.053 -3.52)
        (xy 13.073 -3.535)
        (xy 13.092 -3.547)
        (xy 13.111 -3.56)
        (xy 13.131 -3.571)
        (xy 13.153 -3.581)
        (xy 13.175 -3.591)
        (xy 13.196 -3.597)
        (xy 13.218 -3.604)
        (xy 13.24 -3.609)
        (xy 13.263 -3.615)
        (xy 13.287 -3.617)
        (xy 13.31 -3.619)
        (xy 13.335 -3.62)
        (xy 13.358 -3.619)
        (xy 13.381 -3.617)
        (xy 13.404 -3.615)
        (xy 13.428 -3.609)
        (xy 13.449 -3.604)
        (xy 13.473 -3.597)
        (xy 13.493 -3.589)
        (xy 13.515 -3.581)
        (xy 13.537 -3.571)
        (xy 13.557 -3.559)
        (xy 13.576 -3.547)
        (xy 13.596 -3.535)
        (xy 13.614 -3.52)
        (xy 13.632 -3.505)
        (xy 13.65 -3.49)
        (xy 13.666 -3.472)
        (xy 13.68 -3.454)
        (xy 13.694 -3.436)
        (xy 13.707 -3.416)
        (xy 13.72 -3.398)
        (xy 13.73 -3.376)
        (xy 13.742 -3.355)
        (xy 13.749 -3.334)
        (xy 13.757 -3.313)
        (xy 13.765 -3.289)
        (xy 13.769 -3.267)
        (xy 13.775 -3.245)
        (xy 13.778 -3.221)
        (xy 13.778 -3.197)
        (xy 13.779 -3.174)
        (xy 13.778 -3.152)
        (xy 13.778 -3.128)
        (xy 13.775 -3.104)
        (xy 13.769 -3.081)
        (xy 13.765 -3.059)
        (xy 13.757 -3.036)
        (xy 13.749 -3.015)
        (xy 13.742 -2.994)
        (xy 13.73 -2.972)
        (xy 13.72 -2.951)
        (xy 13.707 -2.932)
        (xy 13.694 -2.912)
        (xy 13.68 -2.894)
        (xy 13.666 -2.876)
        (xy 13.65 -2.859)
        (xy 13.632 -2.843)
        (xy 13.614 -2.829)
        (xy 13.596 -2.814)
        (xy 13.576 -2.801)
        (xy 13.557 -2.789)
        (xy 13.537 -2.778)
        (xy 13.515 -2.767)
        (xy 13.493 -2.759)
        (xy 13.473 -2.751)
        (xy 13.449 -2.745)
        (xy 13.428 -2.74)
        (xy 13.404 -2.734)
        (xy 13.381 -2.732)
        (xy 13.358 -2.73)
        (xy 13.335 -2.729)
        (xy 13.31 -2.73)
        (xy 13.287 -2.732)
        (xy 13.263 -2.734)
        (xy 13.24 -2.74)
        (xy 13.218 -2.745)
        (xy 13.196 -2.751)
        (xy 13.175 -2.758)
        (xy 13.153 -2.767)
        (xy 13.131 -2.777)
        (xy 13.111 -2.789)
        (xy 13.092 -2.801)
        (xy 13.073 -2.814)
        (xy 13.053 -2.829)
        (xy 13.037 -2.843)
        (xy 13.019 -2.859)
        (xy 13.003 -2.876)
        (xy 12.989 -2.894)
        (xy 12.974 -2.912)
        (xy 12.961 -2.931)
        (xy 12.948 -2.951)
        (xy 12.938 -2.971)
        (xy 12.928 -2.992)
        (xy 12.919 -3.015)
        (xy 12.912 -3.036)
        (xy 12.904 -3.059)
        (xy 12.9 -3.08)
        (xy 12.894 -3.104)
        (xy 12.891 -3.126)
        (xy 12.89 -3.15)
        (xy 12.89 -3.172)
        (xy 13.335 -3.172)
        (xy 13.335 -3.177)
      )

      (stroke (width 0.001) (type solid)) (fill solid) (layer "B.Paste"))
    (fp_poly
      (pts
        (xy 13.335 1.903)
        (xy 12.89 1.903)
        (xy 12.89 1.881)
        (xy 12.891 1.857)
        (xy 12.894 1.835)
        (xy 12.9 1.811)
        (xy 12.904 1.789)
        (xy 12.912 1.767)
        (xy 12.919 1.746)
        (xy 12.928 1.724)
        (xy 12.938 1.702)
        (xy 12.948 1.682)
        (xy 12.961 1.662)
        (xy 12.974 1.643)
        (xy 12.989 1.625)
        (xy 13.003 1.607)
        (xy 13.019 1.591)
        (xy 13.037 1.575)
        (xy 13.053 1.559)
        (xy 13.073 1.545)
        (xy 13.092 1.532)
        (xy 13.111 1.519)
        (xy 13.131 1.508)
        (xy 13.153 1.498)
        (xy 13.175 1.49)
        (xy 13.196 1.482)
        (xy 13.218 1.476)
        (xy 13.24 1.47)
        (xy 13.263 1.466)
        (xy 13.287 1.462)
        (xy 13.31 1.462)
        (xy 13.335 1.46)
        (xy 13.358 1.462)
        (xy 13.381 1.462)
        (xy 13.404 1.466)
        (xy 13.428 1.47)
        (xy 13.449 1.476)
        (xy 13.473 1.482)
        (xy 13.493 1.49)
        (xy 13.515 1.498)
        (xy 13.537 1.509)
        (xy 13.557 1.52)
        (xy 13.576 1.532)
        (xy 13.596 1.545)
        (xy 13.614 1.559)
        (xy 13.632 1.575)
        (xy 13.65 1.591)
        (xy 13.666 1.607)
        (xy 13.68 1.625)
        (xy 13.694 1.643)
        (xy 13.707 1.663)
        (xy 13.72 1.682)
        (xy 13.73 1.704)
        (xy 13.742 1.724)
        (xy 13.749 1.746)
        (xy 13.757 1.767)
        (xy 13.765 1.79)
        (xy 13.769 1.813)
        (xy 13.775 1.835)
        (xy 13.778 1.859)
        (xy 13.778 1.882)
        (xy 13.779 1.905)
        (xy 13.778 1.928)
        (xy 13.778 1.952)
        (xy 13.775 1.976)
        (xy 13.769 1.998)
        (xy 13.765 2.02)
        (xy 13.757 2.044)
        (xy 13.749 2.065)
        (xy 13.742 2.086)
        (xy 13.73 2.108)
        (xy 13.72 2.129)
        (xy 13.707 2.147)
        (xy 13.694 2.167)
        (xy 13.68 2.186)
        (xy 13.666 2.203)
        (xy 13.65 2.221)
        (xy 13.632 2.237)
        (xy 13.614 2.251)
        (xy 13.596 2.266)
        (xy 13.576 2.278)
        (xy 13.557 2.29)
        (xy 13.537 2.302)
        (xy 13.515 2.312)
        (xy 13.493 2.32)
        (xy 13.473 2.328)
        (xy 13.449 2.335)
        (xy 13.428 2.34)
        (xy 13.404 2.346)
        (xy 13.381 2.348)
        (xy 13.358 2.35)
        (xy 13.335 2.351)
        (xy 13.31 2.35)
        (xy 13.287 2.348)
        (xy 13.263 2.346)
        (xy 13.24 2.34)
        (xy 13.218 2.335)
        (xy 13.196 2.328)
        (xy 13.175 2.322)
        (xy 13.153 2.312)
        (xy 13.131 2.302)
        (xy 13.111 2.291)
        (xy 13.092 2.278)
        (xy 13.073 2.266)
        (xy 13.053 2.251)
        (xy 13.037 2.237)
        (xy 13.019 2.221)
        (xy 13.003 2.203)
        (xy 12.989 2.186)
        (xy 12.974 2.167)
        (xy 12.961 2.149)
        (xy 12.948 2.129)
        (xy 12.938 2.109)
        (xy 12.928 2.088)
        (xy 12.919 2.065)
        (xy 12.912 2.044)
        (xy 12.904 2.021)
        (xy 12.9 2)
        (xy 12.894 1.976)
        (xy 12.891 1.954)
        (xy 12.89 1.93)
        (xy 12.89 1.907)
        (xy 13.335 1.907)
        (xy 13.335 1.903)
      )

      (stroke (width 0.001) (type solid)) (fill solid) (layer "B.Paste"))
    (fp_poly
      (pts
        (xy 13.335 3.173)
        (xy 12.89 3.173)
        (xy 12.89 3.151)
        (xy 12.891 3.127)
        (xy 12.894 3.105)
        (xy 12.9 3.081)
        (xy 12.904 3.06)
        (xy 12.912 3.037)
        (xy 12.919 3.016)
        (xy 12.928 2.993)
        (xy 12.938 2.972)
        (xy 12.948 2.952)
        (xy 12.961 2.932)
        (xy 12.974 2.913)
        (xy 12.989 2.895)
        (xy 13.003 2.877)
        (xy 13.019 2.86)
        (xy 13.037 2.844)
        (xy 13.053 2.83)
        (xy 13.073 2.815)
        (xy 13.092 2.802)
        (xy 13.111 2.79)
        (xy 13.131 2.778)
        (xy 13.153 2.768)
        (xy 13.175 2.759)
        (xy 13.196 2.752)
        (xy 13.218 2.746)
        (xy 13.24 2.741)
        (xy 13.263 2.735)
        (xy 13.287 2.733)
        (xy 13.31 2.731)
        (xy 13.335 2.73)
        (xy 13.358 2.731)
        (xy 13.381 2.733)
        (xy 13.404 2.735)
        (xy 13.428 2.741)
        (xy 13.449 2.746)
        (xy 13.473 2.752)
        (xy 13.493 2.76)
        (xy 13.515 2.768)
        (xy 13.537 2.779)
        (xy 13.557 2.79)
        (xy 13.576 2.802)
        (xy 13.596 2.815)
        (xy 13.614 2.83)
        (xy 13.632 2.844)
        (xy 13.65 2.86)
        (xy 13.666 2.877)
        (xy 13.68 2.895)
        (xy 13.694 2.913)
        (xy 13.707 2.933)
        (xy 13.72 2.952)
        (xy 13.73 2.973)
        (xy 13.742 2.995)
        (xy 13.749 3.016)
        (xy 13.757 3.037)
        (xy 13.765 3.06)
        (xy 13.769 3.082)
        (xy 13.775 3.105)
        (xy 13.778 3.129)
        (xy 13.778 3.153)
        (xy 13.779 3.175)
        (xy 13.778 3.198)
        (xy 13.778 3.222)
        (xy 13.775 3.246)
        (xy 13.769 3.268)
        (xy 13.765 3.29)
        (xy 13.757 3.314)
        (xy 13.749 3.335)
        (xy 13.742 3.356)
        (xy 13.73 3.377)
        (xy 13.72 3.399)
        (xy 13.707 3.417)
        (xy 13.694 3.437)
        (xy 13.68 3.455)
        (xy 13.666 3.473)
        (xy 13.65 3.491)
        (xy 13.632 3.506)
        (xy 13.614 3.521)
        (xy 13.596 3.536)
        (xy 13.576 3.548)
        (xy 13.557 3.56)
        (xy 13.537 3.572)
        (xy 13.515 3.582)
        (xy 13.493 3.59)
        (xy 13.473 3.598)
        (xy 13.449 3.605)
        (xy 13.428 3.61)
        (xy 13.404 3.616)
        (xy 13.381 3.618)
        (xy 13.358 3.62)
        (xy 13.335 3.621)
        (xy 13.31 3.62)
        (xy 13.287 3.618)
        (xy 13.263 3.616)
        (xy 13.24 3.61)
        (xy 13.218 3.605)
        (xy 13.196 3.598)
        (xy 13.175 3.592)
        (xy 13.153 3.582)
        (xy 13.131 3.572)
        (xy 13.111 3.561)
        (xy 13.092 3.548)
        (xy 13.073 3.536)
        (xy 13.053 3.521)
        (xy 13.037 3.506)
        (xy 13.019 3.491)
        (xy 13.003 3.473)
        (xy 12.989 3.456)
        (xy 12.974 3.437)
        (xy 12.961 3.419)
        (xy 12.948 3.399)
        (xy 12.938 3.379)
        (xy 12.928 3.358)
        (xy 12.919 3.335)
        (xy 12.912 3.314)
        (xy 12.904 3.291)
        (xy 12.9 3.27)
        (xy 12.894 3.246)
        (xy 12.891 3.223)
        (xy 12.89 3.199)
        (xy 12.89 3.178)
        (xy 13.335 3.178)
        (xy 13.335 3.173)
      )

      (stroke (width 0.001) (type solid)) (fill solid) (layer "B.Paste"))
    (fp_poly
      (pts
        (xy 13.335 4.443)
        (xy 12.89 4.443)
        (xy 12.89 4.422)
        (xy 12.891 4.398)
        (xy 12.894 4.374)
        (xy 12.9 4.351)
        (xy 12.904 4.329)
        (xy 12.912 4.308)
        (xy 12.919 4.286)
        (xy 12.928 4.263)
        (xy 12.938 4.242)
        (xy 12.948 4.223)
        (xy 12.961 4.202)
        (xy 12.974 4.183)
        (xy 12.989 4.164)
        (xy 13.003 4.148)
        (xy 13.019 4.13)
        (xy 13.037 4.114)
        (xy 13.053 4.1)
        (xy 13.073 4.085)
        (xy 13.092 4.072)
        (xy 13.111 4.06)
        (xy 13.131 4.048)
        (xy 13.153 4.039)
        (xy 13.175 4.029)
        (xy 13.196 4.023)
        (xy 13.218 4.015)
        (xy 13.24 4.01)
        (xy 13.263 4.005)
        (xy 13.287 4.002)
        (xy 13.31 4.002)
        (xy 13.335 4)
        (xy 13.358 4.002)
        (xy 13.381 4.002)
        (xy 13.404 4.005)
        (xy 13.428 4.01)
        (xy 13.449 4.015)
        (xy 13.473 4.023)
        (xy 13.493 4.031)
        (xy 13.515 4.039)
        (xy 13.537 4.05)
        (xy 13.557 4.06)
        (xy 13.576 4.072)
        (xy 13.596 4.085)
        (xy 13.614 4.1)
        (xy 13.632 4.114)
        (xy 13.65 4.13)
        (xy 13.666 4.148)
        (xy 13.68 4.165)
        (xy 13.694 4.183)
        (xy 13.707 4.204)
        (xy 13.72 4.223)
        (xy 13.73 4.244)
        (xy 13.742 4.265)
        (xy 13.749 4.286)
        (xy 13.757 4.308)
        (xy 13.765 4.33)
        (xy 13.769 4.353)
        (xy 13.775 4.375)
        (xy 13.778 4.398)
        (xy 13.778 4.422)
        (xy 13.779 4.446)
        (xy 13.778 4.468)
        (xy 13.778 4.492)
        (xy 13.775 4.515)
        (xy 13.769 4.539)
        (xy 13.765 4.56)
        (xy 13.757 4.584)
        (xy 13.749 4.604)
        (xy 13.742 4.627)
        (xy 13.73 4.648)
        (xy 13.72 4.669)
        (xy 13.707 4.688)
        (xy 13.694 4.707)
        (xy 13.68 4.725)
        (xy 13.666 4.744)
        (xy 13.65 4.76)
        (xy 13.632 4.776)
        (xy 13.614 4.792)
        (xy 13.596 4.805)
        (xy 13.576 4.818)
        (xy 13.557 4.83)
        (xy 13.537 4.842)
        (xy 13.515 4.853)
        (xy 13.493 4.861)
        (xy 13.473 4.869)
        (xy 13.449 4.875)
        (xy 13.428 4.88)
        (xy 13.404 4.885)
        (xy 13.381 4.888)
        (xy 13.358 4.89)
        (xy 13.335 4.89)
        (xy 13.31 4.89)
        (xy 13.287 4.888)
        (xy 13.263 4.885)
        (xy 13.24 4.88)
        (xy 13.218 4.875)
        (xy 13.196 4.869)
        (xy 13.175 4.861)
        (xy 13.153 4.853)
        (xy 13.131 4.842)
        (xy 13.111 4.832)
        (xy 13.092 4.818)
        (xy 13.073 4.805)
        (xy 13.053 4.792)
        (xy 13.037 4.776)
        (xy 13.019 4.76)
        (xy 13.003 4.744)
        (xy 12.989 4.726)
        (xy 12.974 4.707)
        (xy 12.961 4.688)
        (xy 12.948 4.669)
        (xy 12.938 4.648)
        (xy 12.928 4.627)
        (xy 12.919 4.606)
        (xy 12.912 4.584)
        (xy 12.904 4.561)
        (xy 12.9 4.539)
        (xy 12.894 4.516)
        (xy 12.891 4.494)
        (xy 12.89 4.47)
        (xy 12.89 4.447)
        (xy 13.335 4.447)
        (xy 13.335 4.443)
      )

      (stroke (width 0.001) (type solid)) (fill solid) (layer "B.Paste"))
    (fp_poly
      (pts
        (xy 13.335 5.713)
        (xy 12.89 5.713)
        (xy 12.89 5.691)
        (xy 12.891 5.667)
        (xy 12.894 5.645)
        (xy 12.9 5.622)
        (xy 12.904 5.6)
        (xy 12.912 5.577)
        (xy 12.919 5.555)
        (xy 12.928 5.534)
        (xy 12.938 5.512)
        (xy 12.948 5.492)
        (xy 12.961 5.473)
        (xy 12.974 5.454)
        (xy 12.989 5.435)
        (xy 13.003 5.417)
        (xy 13.019 5.401)
        (xy 13.037 5.385)
        (xy 13.053 5.369)
        (xy 13.073 5.356)
        (xy 13.092 5.342)
        (xy 13.111 5.329)
        (xy 13.131 5.318)
        (xy 13.153 5.308)
        (xy 13.175 5.3)
        (xy 13.196 5.292)
        (xy 13.218 5.286)
        (xy 13.24 5.281)
        (xy 13.263 5.276)
        (xy 13.287 5.273)
        (xy 13.31 5.271)
        (xy 13.335 5.27)
        (xy 13.358 5.271)
        (xy 13.381 5.273)
        (xy 13.404 5.276)
        (xy 13.428 5.281)
        (xy 13.449 5.286)
        (xy 13.473 5.292)
        (xy 13.493 5.3)
        (xy 13.515 5.308)
        (xy 13.537 5.319)
        (xy 13.557 5.33)
        (xy 13.576 5.342)
        (xy 13.596 5.356)
        (xy 13.614 5.369)
        (xy 13.632 5.385)
        (xy 13.65 5.401)
        (xy 13.666 5.417)
        (xy 13.68 5.435)
        (xy 13.694 5.454)
        (xy 13.707 5.473)
        (xy 13.72 5.492)
        (xy 13.73 5.513)
        (xy 13.742 5.534)
        (xy 13.749 5.556)
        (xy 13.757 5.577)
        (xy 13.765 5.6)
        (xy 13.769 5.622)
        (xy 13.775 5.645)
        (xy 13.778 5.669)
        (xy 13.778 5.693)
        (xy 13.779 5.715)
        (xy 13.778 5.739)
        (xy 13.778 5.762)
        (xy 13.775 5.786)
        (xy 13.769 5.808)
        (xy 13.765 5.83)
        (xy 13.757 5.853)
        (xy 13.749 5.874)
        (xy 13.742 5.896)
        (xy 13.73 5.917)
        (xy 13.72 5.938)
        (xy 13.707 5.957)
        (xy 13.694 5.978)
        (xy 13.68 5.995)
        (xy 13.666 6.013)
        (xy 13.65 6.031)
        (xy 13.632 6.047)
        (xy 13.614 6.061)
        (xy 13.596 6.076)
        (xy 13.576 6.088)
        (xy 13.557 6.1)
        (xy 13.537 6.111)
        (xy 13.515 6.122)
        (xy 13.493 6.13)
        (xy 13.473 6.138)
        (xy 13.449 6.145)
        (xy 13.428 6.151)
        (xy 13.404 6.156)
        (xy 13.381 6.159)
        (xy 13.358 6.159)
        (xy 13.335 6.161)
        (xy 13.31 6.159)
        (xy 13.287 6.159)
        (xy 13.263 6.156)
        (xy 13.24 6.151)
        (xy 13.218 6.145)
        (xy 13.196 6.138)
        (xy 13.175 6.132)
        (xy 13.153 6.122)
        (xy 13.131 6.112)
        (xy 13.111 6.101)
        (xy 13.092 6.088)
        (xy 13.073 6.076)
        (xy 13.053 6.061)
        (xy 13.037 6.047)
        (xy 13.019 6.031)
        (xy 13.003 6.013)
        (xy 12.989 5.997)
        (xy 12.974 5.978)
        (xy 12.961 5.959)
        (xy 12.948 5.938)
        (xy 12.938 5.919)
        (xy 12.928 5.898)
        (xy 12.919 5.875)
        (xy 12.912 5.853)
        (xy 12.904 5.832)
        (xy 12.9 5.81)
        (xy 12.894 5.786)
        (xy 12.891 5.763)
        (xy 12.89 5.739)
        (xy 12.89 5.718)
        (xy 13.335 5.718)
        (xy 13.335 5.713)
      )

      (stroke (width 0.001) (type solid)) (fill solid) (layer "B.Paste"))
    (fp_poly
      (pts
        (xy 14.605 -5.717)
        (xy 14.159 -5.717)
        (xy 14.16 -5.738)
        (xy 14.162 -5.762)
        (xy 14.164 -5.785)
        (xy 14.169 -5.809)
        (xy 14.175 -5.831)
        (xy 14.182 -5.852)
        (xy 14.188 -5.874)
        (xy 14.198 -5.897)
        (xy 14.207 -5.918)
        (xy 14.218 -5.937)
        (xy 14.231 -5.958)
        (xy 14.244 -5.977)
        (xy 14.259 -5.996)
        (xy 14.273 -6.012)
        (xy 14.289 -6.03)
        (xy 14.307 -6.046)
        (xy 14.323 -6.06)
        (xy 14.342 -6.075)
        (xy 14.361 -6.087)
        (xy 14.381 -6.1)
        (xy 14.401 -6.111)
        (xy 14.422 -6.121)
        (xy 14.444 -6.131)
        (xy 14.467 -6.137)
        (xy 14.489 -6.144)
        (xy 14.51 -6.15)
        (xy 14.534 -6.155)
        (xy 14.557 -6.158)
        (xy 14.58 -6.158)
        (xy 14.605 -6.16)
        (xy 14.627 -6.158)
        (xy 14.651 -6.158)
        (xy 14.675 -6.155)
        (xy 14.698 -6.15)
        (xy 14.72 -6.144)
        (xy 14.743 -6.137)
        (xy 14.763 -6.129)
        (xy 14.785 -6.121)
        (xy 14.807 -6.11)
        (xy 14.827 -6.099)
        (xy 14.846 -6.087)
        (xy 14.867 -6.075)
        (xy 14.884 -6.06)
        (xy 14.903 -6.046)
        (xy 14.919 -6.03)
        (xy 14.935 -6.012)
        (xy 14.951 -5.994)
        (xy 14.964 -5.977)
        (xy 14.977 -5.956)
        (xy 14.989 -5.937)
        (xy 15 -5.916)
        (xy 15.012 -5.895)
        (xy 15.019 -5.873)
        (xy 15.028 -5.852)
        (xy 15.034 -5.829)
        (xy 15.039 -5.807)
        (xy 15.044 -5.785)
        (xy 15.047 -5.761)
        (xy 15.048 -5.738)
        (xy 15.05 -5.714)
        (xy 15.048 -5.692)
        (xy 15.047 -5.668)
        (xy 15.044 -5.644)
        (xy 15.039 -5.621)
        (xy 15.034 -5.599)
        (xy 15.028 -5.576)
        (xy 15.019 -5.555)
        (xy 15.012 -5.533)
        (xy 15 -5.512)
        (xy 14.989 -5.491)
        (xy 14.977 -5.472)
        (xy 14.964 -5.453)
        (xy 14.951 -5.434)
        (xy 14.935 -5.416)
        (xy 14.919 -5.4)
        (xy 14.903 -5.384)
        (xy 14.884 -5.368)
        (xy 14.867 -5.355)
        (xy 14.846 -5.341)
        (xy 14.827 -5.329)
        (xy 14.807 -5.318)
        (xy 14.785 -5.307)
        (xy 14.763 -5.299)
        (xy 14.743 -5.291)
        (xy 14.72 -5.285)
        (xy 14.698 -5.28)
        (xy 14.675 -5.275)
        (xy 14.651 -5.272)
        (xy 14.627 -5.27)
        (xy 14.605 -5.269)
        (xy 14.58 -5.27)
        (xy 14.557 -5.272)
        (xy 14.534 -5.275)
        (xy 14.51 -5.28)
        (xy 14.489 -5.285)
        (xy 14.467 -5.291)
        (xy 14.444 -5.299)
        (xy 14.422 -5.307)
        (xy 14.401 -5.317)
        (xy 14.381 -5.328)
        (xy 14.361 -5.341)
        (xy 14.342 -5.355)
        (xy 14.323 -5.368)
        (xy 14.307 -5.384)
        (xy 14.289 -5.4)
        (xy 14.273 -5.416)
        (xy 14.259 -5.434)
        (xy 14.244 -5.453)
        (xy 14.231 -5.472)
        (xy 14.218 -5.491)
        (xy 14.207 -5.511)
        (xy 14.198 -5.533)
        (xy 14.188 -5.554)
        (xy 14.182 -5.576)
        (xy 14.175 -5.599)
        (xy 14.169 -5.621)
        (xy 14.164 -5.644)
        (xy 14.162 -5.666)
        (xy 14.16 -5.69)
        (xy 14.159 -5.712)
        (xy 14.605 -5.712)
        (xy 14.605 -5.717)
      )

      (stroke (width 0.001) (type solid)) (fill solid) (layer "B.Paste"))
    (fp_poly
      (pts
        (xy 14.605 -3.177)
        (xy 14.159 -3.177)
        (xy 14.16 -3.198)
        (xy 14.162 -3.222)
        (xy 14.164 -3.245)
        (xy 14.169 -3.269)
        (xy 14.175 -3.29)
        (xy 14.182 -3.313)
        (xy 14.188 -3.334)
        (xy 14.198 -3.357)
        (xy 14.207 -3.378)
        (xy 14.218 -3.398)
        (xy 14.231 -3.418)
        (xy 14.244 -3.436)
        (xy 14.259 -3.455)
        (xy 14.273 -3.472)
        (xy 14.289 -3.49)
        (xy 14.307 -3.505)
        (xy 14.323 -3.52)
        (xy 14.342 -3.535)
        (xy 14.361 -3.547)
        (xy 14.381 -3.56)
        (xy 14.401 -3.571)
        (xy 14.422 -3.581)
        (xy 14.444 -3.591)
        (xy 14.467 -3.597)
        (xy 14.489 -3.604)
        (xy 14.51 -3.609)
        (xy 14.534 -3.615)
        (xy 14.557 -3.617)
        (xy 14.58 -3.619)
        (xy 14.605 -3.62)
        (xy 14.627 -3.619)
        (xy 14.651 -3.617)
        (xy 14.675 -3.615)
        (xy 14.698 -3.609)
        (xy 14.72 -3.604)
        (xy 14.743 -3.597)
        (xy 14.763 -3.589)
        (xy 14.785 -3.581)
        (xy 14.807 -3.571)
        (xy 14.827 -3.559)
        (xy 14.846 -3.547)
        (xy 14.867 -3.535)
        (xy 14.884 -3.52)
        (xy 14.903 -3.505)
        (xy 14.919 -3.49)
        (xy 14.935 -3.472)
        (xy 14.951 -3.454)
        (xy 14.964 -3.436)
        (xy 14.977 -3.416)
        (xy 14.989 -3.396)
        (xy 15 -3.376)
        (xy 15.012 -3.355)
        (xy 15.019 -3.334)
        (xy 15.028 -3.313)
        (xy 15.034 -3.289)
        (xy 15.039 -3.267)
        (xy 15.044 -3.245)
        (xy 15.047 -3.221)
        (xy 15.048 -3.197)
        (xy 15.05 -3.174)
        (xy 15.048 -3.152)
        (xy 15.047 -3.128)
        (xy 15.044 -3.104)
        (xy 15.039 -3.081)
        (xy 15.034 -3.059)
        (xy 15.028 -3.036)
        (xy 15.019 -3.015)
        (xy 15.012 -2.994)
        (xy 15 -2.972)
        (xy 14.989 -2.951)
        (xy 14.977 -2.932)
        (xy 14.964 -2.912)
        (xy 14.951 -2.894)
        (xy 14.935 -2.876)
        (xy 14.919 -2.859)
        (xy 14.903 -2.843)
        (xy 14.884 -2.829)
        (xy 14.867 -2.814)
        (xy 14.846 -2.801)
        (xy 14.827 -2.789)
        (xy 14.807 -2.778)
        (xy 14.785 -2.767)
        (xy 14.763 -2.759)
        (xy 14.743 -2.751)
        (xy 14.72 -2.745)
        (xy 14.698 -2.74)
        (xy 14.675 -2.734)
        (xy 14.651 -2.732)
        (xy 14.627 -2.73)
        (xy 14.605 -2.729)
        (xy 14.58 -2.73)
        (xy 14.557 -2.732)
        (xy 14.534 -2.734)
        (xy 14.51 -2.74)
        (xy 14.489 -2.745)
        (xy 14.467 -2.751)
        (xy 14.444 -2.758)
        (xy 14.422 -2.767)
        (xy 14.401 -2.777)
        (xy 14.381 -2.789)
        (xy 14.361 -2.801)
        (xy 14.342 -2.814)
        (xy 14.323 -2.829)
        (xy 14.307 -2.843)
        (xy 14.289 -2.859)
        (xy 14.273 -2.876)
        (xy 14.259 -2.894)
        (xy 14.244 -2.912)
        (xy 14.231 -2.931)
        (xy 14.218 -2.951)
        (xy 14.207 -2.971)
        (xy 14.198 -2.992)
        (xy 14.188 -3.015)
        (xy 14.182 -3.036)
        (xy 14.175 -3.059)
        (xy 14.169 -3.08)
        (xy 14.164 -3.104)
        (xy 14.162 -3.126)
        (xy 14.16 -3.15)
        (xy 14.159 -3.172)
        (xy 14.605 -3.172)
        (xy 14.605 -3.177)
      )

      (stroke (width 0.001) (type solid)) (fill solid) (layer "B.Paste"))
    (fp_poly
      (pts
        (xy 14.605 1.903)
        (xy 14.159 1.903)
        (xy 14.16 1.881)
        (xy 14.162 1.857)
        (xy 14.164 1.835)
        (xy 14.169 1.811)
        (xy 14.175 1.789)
        (xy 14.182 1.767)
        (xy 14.188 1.746)
        (xy 14.198 1.724)
        (xy 14.207 1.702)
        (xy 14.218 1.682)
        (xy 14.231 1.662)
        (xy 14.244 1.643)
        (xy 14.259 1.625)
        (xy 14.273 1.607)
        (xy 14.289 1.591)
        (xy 14.307 1.575)
        (xy 14.323 1.559)
        (xy 14.342 1.545)
        (xy 14.361 1.532)
        (xy 14.381 1.519)
        (xy 14.401 1.508)
        (xy 14.422 1.498)
        (xy 14.444 1.49)
        (xy 14.467 1.482)
        (xy 14.489 1.476)
        (xy 14.51 1.47)
        (xy 14.534 1.466)
        (xy 14.557 1.462)
        (xy 14.58 1.462)
        (xy 14.605 1.46)
        (xy 14.627 1.462)
        (xy 14.651 1.462)
        (xy 14.675 1.466)
        (xy 14.698 1.47)
        (xy 14.72 1.476)
        (xy 14.743 1.482)
        (xy 14.763 1.49)
        (xy 14.785 1.498)
        (xy 14.807 1.509)
        (xy 14.827 1.52)
        (xy 14.846 1.532)
        (xy 14.867 1.545)
        (xy 14.884 1.559)
        (xy 14.903 1.575)
        (xy 14.919 1.591)
        (xy 14.935 1.607)
        (xy 14.951 1.625)
        (xy 14.964 1.643)
        (xy 14.977 1.663)
        (xy 14.989 1.684)
        (xy 15 1.704)
        (xy 15.012 1.724)
        (xy 15.019 1.746)
        (xy 15.028 1.767)
        (xy 15.034 1.79)
        (xy 15.039 1.813)
        (xy 15.044 1.835)
        (xy 15.047 1.859)
        (xy 15.048 1.882)
        (xy 15.05 1.905)
        (xy 15.048 1.928)
        (xy 15.047 1.952)
        (xy 15.044 1.976)
        (xy 15.039 1.998)
        (xy 15.034 2.02)
        (xy 15.028 2.044)
        (xy 15.019 2.065)
        (xy 15.012 2.086)
        (xy 15 2.108)
        (xy 14.989 2.127)
        (xy 14.977 2.147)
        (xy 14.964 2.167)
        (xy 14.951 2.186)
        (xy 14.935 2.203)
        (xy 14.919 2.221)
        (xy 14.903 2.237)
        (xy 14.884 2.251)
        (xy 14.867 2.266)
        (xy 14.846 2.278)
        (xy 14.827 2.29)
        (xy 14.807 2.302)
        (xy 14.785 2.312)
        (xy 14.763 2.32)
        (xy 14.743 2.328)
        (xy 14.72 2.335)
        (xy 14.698 2.34)
        (xy 14.675 2.346)
        (xy 14.651 2.348)
        (xy 14.627 2.35)
        (xy 14.605 2.351)
        (xy 14.58 2.35)
        (xy 14.557 2.348)
        (xy 14.534 2.346)
        (xy 14.51 2.34)
        (xy 14.489 2.335)
        (xy 14.467 2.328)
        (xy 14.444 2.322)
        (xy 14.422 2.312)
        (xy 14.401 2.302)
        (xy 14.381 2.291)
        (xy 14.361 2.278)
        (xy 14.342 2.266)
        (xy 14.323 2.251)
        (xy 14.307 2.237)
        (xy 14.289 2.221)
        (xy 14.273 2.203)
        (xy 14.259 2.186)
        (xy 14.244 2.167)
        (xy 14.231 2.149)
        (xy 14.218 2.129)
        (xy 14.207 2.109)
        (xy 14.198 2.088)
        (xy 14.188 2.065)
        (xy 14.182 2.044)
        (xy 14.175 2.021)
        (xy 14.169 2)
        (xy 14.164 1.976)
        (xy 14.162 1.954)
        (xy 14.16 1.93)
        (xy 14.159 1.907)
        (xy 14.605 1.907)
        (xy 14.605 1.903)
      )

      (stroke (width 0.001) (type solid)) (fill solid) (layer "B.Paste"))
    (fp_poly
      (pts
        (xy 14.605 3.173)
        (xy 14.159 3.173)
        (xy 14.16 3.151)
        (xy 14.162 3.127)
        (xy 14.164 3.105)
        (xy 14.169 3.081)
        (xy 14.175 3.06)
        (xy 14.182 3.037)
        (xy 14.188 3.016)
        (xy 14.198 2.993)
        (xy 14.207 2.972)
        (xy 14.218 2.952)
        (xy 14.231 2.932)
        (xy 14.244 2.913)
        (xy 14.259 2.895)
        (xy 14.273 2.877)
        (xy 14.289 2.86)
        (xy 14.307 2.844)
        (xy 14.323 2.83)
        (xy 14.342 2.815)
        (xy 14.361 2.802)
        (xy 14.381 2.79)
        (xy 14.401 2.778)
        (xy 14.422 2.768)
        (xy 14.444 2.759)
        (xy 14.467 2.752)
        (xy 14.489 2.746)
        (xy 14.51 2.741)
        (xy 14.534 2.735)
        (xy 14.557 2.733)
        (xy 14.58 2.731)
        (xy 14.605 2.73)
        (xy 14.627 2.731)
        (xy 14.651 2.733)
        (xy 14.675 2.735)
        (xy 14.698 2.741)
        (xy 14.72 2.746)
        (xy 14.743 2.752)
        (xy 14.763 2.76)
        (xy 14.785 2.768)
        (xy 14.807 2.779)
        (xy 14.827 2.79)
        (xy 14.846 2.802)
        (xy 14.867 2.815)
        (xy 14.884 2.83)
        (xy 14.903 2.844)
        (xy 14.919 2.86)
        (xy 14.935 2.877)
        (xy 14.951 2.895)
        (xy 14.964 2.913)
        (xy 14.977 2.933)
        (xy 14.989 2.952)
        (xy 15 2.973)
        (xy 15.012 2.995)
        (xy 15.019 3.016)
        (xy 15.028 3.037)
        (xy 15.034 3.06)
        (xy 15.039 3.082)
        (xy 15.044 3.105)
        (xy 15.047 3.129)
        (xy 15.048 3.153)
        (xy 15.05 3.175)
        (xy 15.048 3.198)
        (xy 15.047 3.222)
        (xy 15.044 3.246)
        (xy 15.039 3.268)
        (xy 15.034 3.29)
        (xy 15.028 3.314)
        (xy 15.019 3.335)
        (xy 15.012 3.356)
        (xy 15 3.377)
        (xy 14.989 3.397)
        (xy 14.977 3.417)
        (xy 14.964 3.437)
        (xy 14.951 3.455)
        (xy 14.935 3.473)
        (xy 14.919 3.491)
        (xy 14.903 3.506)
        (xy 14.884 3.521)
        (xy 14.867 3.536)
        (xy 14.846 3.548)
        (xy 14.827 3.56)
        (xy 14.807 3.572)
        (xy 14.785 3.582)
        (xy 14.763 3.59)
        (xy 14.743 3.598)
        (xy 14.72 3.605)
        (xy 14.698 3.61)
        (xy 14.675 3.616)
        (xy 14.651 3.618)
        (xy 14.627 3.62)
        (xy 14.605 3.621)
        (xy 14.58 3.62)
        (xy 14.557 3.618)
        (xy 14.534 3.616)
        (xy 14.51 3.61)
        (xy 14.489 3.605)
        (xy 14.467 3.598)
        (xy 14.444 3.592)
        (xy 14.422 3.582)
        (xy 14.401 3.572)
        (xy 14.381 3.561)
        (xy 14.361 3.548)
        (xy 14.342 3.536)
        (xy 14.323 3.521)
        (xy 14.307 3.506)
        (xy 14.289 3.491)
        (xy 14.273 3.473)
        (xy 14.259 3.456)
        (xy 14.244 3.437)
        (xy 14.231 3.419)
        (xy 14.218 3.399)
        (xy 14.207 3.379)
        (xy 14.198 3.358)
        (xy 14.188 3.335)
        (xy 14.182 3.314)
        (xy 14.175 3.291)
        (xy 14.169 3.27)
        (xy 14.164 3.246)
        (xy 14.162 3.223)
        (xy 14.16 3.199)
        (xy 14.159 3.178)
        (xy 14.605 3.178)
        (xy 14.605 3.173)
      )

      (stroke (width 0.001) (type solid)) (fill solid) (layer "B.Paste"))
    (fp_poly
      (pts
        (xy 14.605 4.443)
        (xy 14.159 4.443)
        (xy 14.16 4.422)
        (xy 14.162 4.398)
        (xy 14.164 4.374)
        (xy 14.169 4.351)
        (xy 14.175 4.329)
        (xy 14.182 4.308)
        (xy 14.188 4.286)
        (xy 14.198 4.263)
        (xy 14.207 4.242)
        (xy 14.218 4.223)
        (xy 14.231 4.202)
        (xy 14.244 4.183)
        (xy 14.259 4.164)
        (xy 14.273 4.148)
        (xy 14.289 4.13)
        (xy 14.307 4.114)
        (xy 14.323 4.1)
        (xy 14.342 4.085)
        (xy 14.361 4.072)
        (xy 14.381 4.06)
        (xy 14.401 4.048)
        (xy 14.422 4.039)
        (xy 14.444 4.029)
        (xy 14.467 4.023)
        (xy 14.489 4.015)
        (xy 14.51 4.01)
        (xy 14.534 4.005)
        (xy 14.557 4.002)
        (xy 14.58 4.002)
        (xy 14.605 4)
        (xy 14.627 4.002)
        (xy 14.651 4.002)
        (xy 14.675 4.005)
        (xy 14.698 4.01)
        (xy 14.72 4.015)
        (xy 14.743 4.023)
        (xy 14.763 4.031)
        (xy 14.785 4.039)
        (xy 14.807 4.05)
        (xy 14.827 4.06)
        (xy 14.846 4.072)
        (xy 14.867 4.085)
        (xy 14.884 4.1)
        (xy 14.903 4.114)
        (xy 14.919 4.13)
        (xy 14.935 4.148)
        (xy 14.951 4.165)
        (xy 14.964 4.183)
        (xy 14.977 4.204)
        (xy 14.989 4.223)
        (xy 15 4.244)
        (xy 15.012 4.265)
        (xy 15.019 4.286)
        (xy 15.028 4.308)
        (xy 15.034 4.33)
        (xy 15.039 4.353)
        (xy 15.044 4.375)
        (xy 15.047 4.398)
        (xy 15.048 4.422)
        (xy 15.05 4.446)
        (xy 15.048 4.468)
        (xy 15.047 4.492)
        (xy 15.044 4.515)
        (xy 15.039 4.539)
        (xy 15.034 4.56)
        (xy 15.028 4.584)
        (xy 15.019 4.604)
        (xy 15.012 4.627)
        (xy 15 4.648)
        (xy 14.989 4.669)
        (xy 14.977 4.688)
        (xy 14.964 4.707)
        (xy 14.951 4.725)
        (xy 14.935 4.744)
        (xy 14.919 4.76)
        (xy 14.903 4.776)
        (xy 14.884 4.792)
        (xy 14.867 4.805)
        (xy 14.846 4.818)
        (xy 14.827 4.83)
        (xy 14.807 4.842)
        (xy 14.785 4.853)
        (xy 14.763 4.861)
        (xy 14.743 4.869)
        (xy 14.72 4.875)
        (xy 14.698 4.88)
        (xy 14.675 4.885)
        (xy 14.651 4.888)
        (xy 14.627 4.89)
        (xy 14.605 4.89)
        (xy 14.58 4.89)
        (xy 14.557 4.888)
        (xy 14.534 4.885)
        (xy 14.51 4.88)
        (xy 14.489 4.875)
        (xy 14.467 4.869)
        (xy 14.444 4.861)
        (xy 14.422 4.853)
        (xy 14.401 4.842)
        (xy 14.381 4.832)
        (xy 14.361 4.818)
        (xy 14.342 4.805)
        (xy 14.323 4.792)
        (xy 14.307 4.776)
        (xy 14.289 4.76)
        (xy 14.273 4.744)
        (xy 14.259 4.726)
        (xy 14.244 4.707)
        (xy 14.231 4.688)
        (xy 14.218 4.669)
        (xy 14.207 4.648)
        (xy 14.198 4.627)
        (xy 14.188 4.606)
        (xy 14.182 4.584)
        (xy 14.175 4.561)
        (xy 14.169 4.539)
        (xy 14.164 4.516)
        (xy 14.162 4.494)
        (xy 14.16 4.47)
        (xy 14.159 4.447)
        (xy 14.605 4.447)
        (xy 14.605 4.443)
      )

      (stroke (width 0.001) (type solid)) (fill solid) (layer "B.Paste"))
    (fp_poly
      (pts
        (xy 14.605 5.713)
        (xy 14.159 5.713)
        (xy 14.16 5.691)
        (xy 14.162 5.667)
        (xy 14.164 5.645)
        (xy 14.169 5.622)
        (xy 14.175 5.6)
        (xy 14.182 5.577)
        (xy 14.188 5.555)
        (xy 14.198 5.534)
        (xy 14.207 5.512)
        (xy 14.218 5.492)
        (xy 14.231 5.473)
        (xy 14.244 5.454)
        (xy 14.259 5.435)
        (xy 14.273 5.417)
        (xy 14.289 5.401)
        (xy 14.307 5.385)
        (xy 14.323 5.369)
        (xy 14.342 5.356)
        (xy 14.361 5.342)
        (xy 14.381 5.329)
        (xy 14.401 5.318)
        (xy 14.422 5.308)
        (xy 14.444 5.3)
        (xy 14.467 5.292)
        (xy 14.489 5.286)
        (xy 14.51 5.281)
        (xy 14.534 5.276)
        (xy 14.557 5.273)
        (xy 14.58 5.271)
        (xy 14.605 5.27)
        (xy 14.627 5.271)
        (xy 14.651 5.273)
        (xy 14.675 5.276)
        (xy 14.698 5.281)
        (xy 14.72 5.286)
        (xy 14.743 5.292)
        (xy 14.763 5.3)
        (xy 14.785 5.308)
        (xy 14.807 5.319)
        (xy 14.827 5.33)
        (xy 14.846 5.342)
        (xy 14.867 5.356)
        (xy 14.884 5.369)
        (xy 14.903 5.385)
        (xy 14.919 5.401)
        (xy 14.935 5.417)
        (xy 14.951 5.435)
        (xy 14.964 5.454)
        (xy 14.977 5.473)
        (xy 14.989 5.492)
        (xy 15 5.513)
        (xy 15.012 5.534)
        (xy 15.019 5.556)
        (xy 15.028 5.577)
        (xy 15.034 5.6)
        (xy 15.039 5.622)
        (xy 15.044 5.645)
        (xy 15.047 5.669)
        (xy 15.048 5.693)
        (xy 15.05 5.715)
        (xy 15.048 5.739)
        (xy 15.047 5.762)
        (xy 15.044 5.786)
        (xy 15.039 5.808)
        (xy 15.034 5.83)
        (xy 15.028 5.853)
        (xy 15.019 5.874)
        (xy 15.012 5.896)
        (xy 15 5.917)
        (xy 14.989 5.938)
        (xy 14.977 5.957)
        (xy 14.964 5.978)
        (xy 14.951 5.995)
        (xy 14.935 6.013)
        (xy 14.919 6.031)
        (xy 14.903 6.047)
        (xy 14.884 6.061)
        (xy 14.867 6.076)
        (xy 14.846 6.088)
        (xy 14.827 6.1)
        (xy 14.807 6.111)
        (xy 14.785 6.122)
        (xy 14.763 6.13)
        (xy 14.743 6.138)
        (xy 14.72 6.145)
        (xy 14.698 6.151)
        (xy 14.675 6.156)
        (xy 14.651 6.159)
        (xy 14.627 6.159)
        (xy 14.605 6.161)
        (xy 14.58 6.159)
        (xy 14.557 6.159)
        (xy 14.534 6.156)
        (xy 14.51 6.151)
        (xy 14.489 6.145)
        (xy 14.467 6.138)
        (xy 14.444 6.132)
        (xy 14.422 6.122)
        (xy 14.401 6.112)
        (xy 14.381 6.101)
        (xy 14.361 6.088)
        (xy 14.342 6.076)
        (xy 14.323 6.061)
        (xy 14.307 6.047)
        (xy 14.289 6.031)
        (xy 14.273 6.013)
        (xy 14.259 5.997)
        (xy 14.244 5.978)
        (xy 14.231 5.959)
        (xy 14.218 5.938)
        (xy 14.207 5.919)
        (xy 14.198 5.898)
        (xy 14.188 5.875)
        (xy 14.182 5.853)
        (xy 14.175 5.832)
        (xy 14.169 5.81)
        (xy 14.164 5.786)
        (xy 14.162 5.763)
        (xy 14.16 5.739)
        (xy 14.159 5.718)
        (xy 14.605 5.718)
        (xy 14.605 5.713)
      )

      (stroke (width 0.001) (type solid)) (fill solid) (layer "B.Paste"))
    (fp_poly
      (pts
        (xy 15.874 -5.717)
        (xy 15.429 -5.717)
        (xy 15.43 -5.738)
        (xy 15.432 -5.762)
        (xy 15.435 -5.785)
        (xy 15.439 -5.809)
        (xy 15.444 -5.831)
        (xy 15.451 -5.852)
        (xy 15.458 -5.874)
        (xy 15.467 -5.897)
        (xy 15.477 -5.918)
        (xy 15.489 -5.937)
        (xy 15.502 -5.958)
        (xy 15.515 -5.977)
        (xy 15.528 -5.996)
        (xy 15.544 -6.012)
        (xy 15.56 -6.03)
        (xy 15.576 -6.046)
        (xy 15.593 -6.06)
        (xy 15.612 -6.075)
        (xy 15.631 -6.087)
        (xy 15.651 -6.1)
        (xy 15.672 -6.111)
        (xy 15.692 -6.121)
        (xy 15.714 -6.131)
        (xy 15.736 -6.137)
        (xy 15.759 -6.144)
        (xy 15.781 -6.15)
        (xy 15.803 -6.155)
        (xy 15.826 -6.158)
        (xy 15.851 -6.158)
        (xy 15.874 -6.16)
        (xy 15.897 -6.158)
        (xy 15.922 -6.158)
        (xy 15.944 -6.155)
        (xy 15.967 -6.15)
        (xy 15.989 -6.144)
        (xy 16.013 -6.137)
        (xy 16.033 -6.129)
        (xy 16.056 -6.121)
        (xy 16.077 -6.11)
        (xy 16.097 -6.099)
        (xy 16.117 -6.087)
        (xy 16.137 -6.075)
        (xy 16.155 -6.06)
        (xy 16.172 -6.046)
        (xy 16.19 -6.03)
        (xy 16.205 -6.012)
        (xy 16.22 -5.994)
        (xy 16.234 -5.977)
        (xy 16.248 -5.956)
        (xy 16.26 -5.937)
        (xy 16.271 -5.916)
        (xy 16.281 -5.895)
        (xy 16.289 -5.873)
        (xy 16.297 -5.852)
        (xy 16.304 -5.829)
        (xy 16.309 -5.807)
        (xy 16.315 -5.785)
        (xy 16.318 -5.761)
        (xy 16.318 -5.738)
        (xy 16.319 -5.714)
        (xy 16.318 -5.692)
        (xy 16.318 -5.668)
        (xy 16.315 -5.644)
        (xy 16.309 -5.621)
        (xy 16.304 -5.599)
        (xy 16.297 -5.576)
        (xy 16.289 -5.555)
        (xy 16.281 -5.533)
        (xy 16.271 -5.512)
        (xy 16.26 -5.491)
        (xy 16.248 -5.472)
        (xy 16.234 -5.453)
        (xy 16.22 -5.434)
        (xy 16.205 -5.416)
        (xy 16.19 -5.4)
        (xy 16.172 -5.384)
        (xy 16.155 -5.368)
        (xy 16.137 -5.355)
        (xy 16.117 -5.341)
        (xy 16.097 -5.329)
        (xy 16.077 -5.318)
        (xy 16.056 -5.307)
        (xy 16.033 -5.299)
        (xy 16.013 -5.291)
        (xy 15.989 -5.285)
        (xy 15.967 -5.28)
        (xy 15.944 -5.275)
        (xy 15.922 -5.272)
        (xy 15.897 -5.27)
        (xy 15.874 -5.269)
        (xy 15.851 -5.27)
        (xy 15.826 -5.272)
        (xy 15.803 -5.275)
        (xy 15.781 -5.28)
        (xy 15.759 -5.285)
        (xy 15.736 -5.291)
        (xy 15.714 -5.299)
        (xy 15.692 -5.307)
        (xy 15.672 -5.317)
        (xy 15.651 -5.328)
        (xy 15.631 -5.341)
        (xy 15.612 -5.355)
        (xy 15.593 -5.368)
        (xy 15.576 -5.384)
        (xy 15.56 -5.4)
        (xy 15.544 -5.416)
        (xy 15.528 -5.434)
        (xy 15.515 -5.453)
        (xy 15.502 -5.472)
        (xy 15.489 -5.491)
        (xy 15.477 -5.511)
        (xy 15.467 -5.533)
        (xy 15.458 -5.554)
        (xy 15.451 -5.576)
        (xy 15.444 -5.599)
        (xy 15.439 -5.621)
        (xy 15.435 -5.644)
        (xy 15.432 -5.666)
        (xy 15.43 -5.69)
        (xy 15.429 -5.712)
        (xy 15.874 -5.712)
        (xy 15.874 -5.717)
      )

      (stroke (width 0.001) (type solid)) (fill solid) (layer "B.Paste"))
    (fp_poly
      (pts
        (xy 15.874 -3.177)
        (xy 15.429 -3.177)
        (xy 15.43 -3.198)
        (xy 15.432 -3.222)
        (xy 15.435 -3.245)
        (xy 15.439 -3.269)
        (xy 15.444 -3.29)
        (xy 15.451 -3.313)
        (xy 15.458 -3.334)
        (xy 15.467 -3.357)
        (xy 15.477 -3.378)
        (xy 15.489 -3.398)
        (xy 15.502 -3.418)
        (xy 15.515 -3.436)
        (xy 15.528 -3.455)
        (xy 15.544 -3.472)
        (xy 15.56 -3.49)
        (xy 15.576 -3.505)
        (xy 15.593 -3.52)
        (xy 15.612 -3.535)
        (xy 15.631 -3.547)
        (xy 15.651 -3.56)
        (xy 15.672 -3.571)
        (xy 15.692 -3.581)
        (xy 15.714 -3.591)
        (xy 15.736 -3.597)
        (xy 15.759 -3.604)
        (xy 15.781 -3.609)
        (xy 15.803 -3.615)
        (xy 15.826 -3.617)
        (xy 15.851 -3.619)
        (xy 15.874 -3.62)
        (xy 15.897 -3.619)
        (xy 15.922 -3.617)
        (xy 15.944 -3.615)
        (xy 15.967 -3.609)
        (xy 15.989 -3.604)
        (xy 16.013 -3.597)
        (xy 16.033 -3.589)
        (xy 16.056 -3.581)
        (xy 16.077 -3.571)
        (xy 16.097 -3.559)
        (xy 16.117 -3.547)
        (xy 16.137 -3.535)
        (xy 16.155 -3.52)
        (xy 16.172 -3.505)
        (xy 16.19 -3.49)
        (xy 16.205 -3.472)
        (xy 16.22 -3.454)
        (xy 16.234 -3.436)
        (xy 16.248 -3.416)
        (xy 16.26 -3.396)
        (xy 16.271 -3.376)
        (xy 16.281 -3.355)
        (xy 16.289 -3.334)
        (xy 16.297 -3.313)
        (xy 16.304 -3.289)
        (xy 16.309 -3.267)
        (xy 16.315 -3.245)
        (xy 16.318 -3.221)
        (xy 16.318 -3.197)
        (xy 16.319 -3.174)
        (xy 16.318 -3.152)
        (xy 16.318 -3.128)
        (xy 16.315 -3.104)
        (xy 16.309 -3.081)
        (xy 16.304 -3.059)
        (xy 16.297 -3.036)
        (xy 16.289 -3.015)
        (xy 16.281 -2.994)
        (xy 16.271 -2.972)
        (xy 16.26 -2.951)
        (xy 16.248 -2.932)
        (xy 16.234 -2.912)
        (xy 16.22 -2.894)
        (xy 16.205 -2.876)
        (xy 16.19 -2.859)
        (xy 16.172 -2.843)
        (xy 16.155 -2.829)
        (xy 16.137 -2.814)
        (xy 16.117 -2.801)
        (xy 16.097 -2.789)
        (xy 16.077 -2.778)
        (xy 16.056 -2.767)
        (xy 16.033 -2.759)
        (xy 16.013 -2.751)
        (xy 15.989 -2.745)
        (xy 15.967 -2.74)
        (xy 15.944 -2.734)
        (xy 15.922 -2.732)
        (xy 15.897 -2.73)
        (xy 15.874 -2.729)
        (xy 15.851 -2.73)
        (xy 15.826 -2.732)
        (xy 15.803 -2.734)
        (xy 15.781 -2.74)
        (xy 15.759 -2.745)
        (xy 15.736 -2.751)
        (xy 15.714 -2.758)
        (xy 15.692 -2.767)
        (xy 15.672 -2.777)
        (xy 15.651 -2.789)
        (xy 15.631 -2.801)
        (xy 15.612 -2.814)
        (xy 15.593 -2.829)
        (xy 15.576 -2.843)
        (xy 15.56 -2.859)
        (xy 15.544 -2.876)
        (xy 15.528 -2.894)
        (xy 15.515 -2.912)
        (xy 15.502 -2.931)
        (xy 15.489 -2.951)
        (xy 15.477 -2.971)
        (xy 15.467 -2.992)
        (xy 15.458 -3.015)
        (xy 15.451 -3.036)
        (xy 15.444 -3.059)
        (xy 15.439 -3.08)
        (xy 15.435 -3.104)
        (xy 15.432 -3.126)
        (xy 15.43 -3.15)
        (xy 15.429 -3.172)
        (xy 15.874 -3.172)
        (xy 15.874 -3.177)
      )

      (stroke (width 0.001) (type solid)) (fill solid) (layer "B.Paste"))
    (fp_poly
      (pts
        (xy 15.874 1.903)
        (xy 15.429 1.903)
        (xy 15.43 1.881)
        (xy 15.432 1.857)
        (xy 15.435 1.835)
        (xy 15.439 1.811)
        (xy 15.444 1.789)
        (xy 15.451 1.767)
        (xy 15.458 1.746)
        (xy 15.467 1.724)
        (xy 15.477 1.702)
        (xy 15.489 1.682)
        (xy 15.502 1.662)
        (xy 15.515 1.643)
        (xy 15.528 1.625)
        (xy 15.544 1.607)
        (xy 15.56 1.591)
        (xy 15.576 1.575)
        (xy 15.593 1.559)
        (xy 15.612 1.545)
        (xy 15.631 1.532)
        (xy 15.651 1.519)
        (xy 15.672 1.508)
        (xy 15.692 1.498)
        (xy 15.714 1.49)
        (xy 15.736 1.482)
        (xy 15.759 1.476)
        (xy 15.781 1.47)
        (xy 15.803 1.466)
        (xy 15.826 1.462)
        (xy 15.851 1.462)
        (xy 15.874 1.46)
        (xy 15.897 1.462)
        (xy 15.922 1.462)
        (xy 15.944 1.466)
        (xy 15.967 1.47)
        (xy 15.989 1.476)
        (xy 16.013 1.482)
        (xy 16.033 1.49)
        (xy 16.056 1.498)
        (xy 16.077 1.509)
        (xy 16.097 1.52)
        (xy 16.117 1.532)
        (xy 16.137 1.545)
        (xy 16.155 1.559)
        (xy 16.172 1.575)
        (xy 16.19 1.591)
        (xy 16.205 1.607)
        (xy 16.22 1.625)
        (xy 16.234 1.643)
        (xy 16.248 1.663)
        (xy 16.26 1.684)
        (xy 16.271 1.704)
        (xy 16.281 1.724)
        (xy 16.289 1.746)
        (xy 16.297 1.767)
        (xy 16.304 1.79)
        (xy 16.309 1.813)
        (xy 16.315 1.835)
        (xy 16.318 1.859)
        (xy 16.318 1.882)
        (xy 16.319 1.905)
        (xy 16.318 1.928)
        (xy 16.318 1.952)
        (xy 16.315 1.976)
        (xy 16.309 1.998)
        (xy 16.304 2.02)
        (xy 16.297 2.044)
        (xy 16.289 2.065)
        (xy 16.281 2.086)
        (xy 16.271 2.108)
        (xy 16.26 2.127)
        (xy 16.248 2.147)
        (xy 16.234 2.167)
        (xy 16.22 2.186)
        (xy 16.205 2.203)
        (xy 16.19 2.221)
        (xy 16.172 2.237)
        (xy 16.155 2.251)
        (xy 16.137 2.266)
        (xy 16.117 2.278)
        (xy 16.097 2.29)
        (xy 16.077 2.302)
        (xy 16.056 2.312)
        (xy 16.033 2.32)
        (xy 16.013 2.328)
        (xy 15.989 2.335)
        (xy 15.967 2.34)
        (xy 15.944 2.346)
        (xy 15.922 2.348)
        (xy 15.897 2.35)
        (xy 15.874 2.351)
        (xy 15.851 2.35)
        (xy 15.826 2.348)
        (xy 15.803 2.346)
        (xy 15.781 2.34)
        (xy 15.759 2.335)
        (xy 15.736 2.328)
        (xy 15.714 2.322)
        (xy 15.692 2.312)
        (xy 15.672 2.302)
        (xy 15.651 2.291)
        (xy 15.631 2.278)
        (xy 15.612 2.266)
        (xy 15.593 2.251)
        (xy 15.576 2.237)
        (xy 15.56 2.221)
        (xy 15.544 2.203)
        (xy 15.528 2.186)
        (xy 15.515 2.167)
        (xy 15.502 2.149)
        (xy 15.489 2.129)
        (xy 15.477 2.109)
        (xy 15.467 2.088)
        (xy 15.458 2.065)
        (xy 15.451 2.044)
        (xy 15.444 2.021)
        (xy 15.439 2)
        (xy 15.435 1.976)
        (xy 15.432 1.954)
        (xy 15.43 1.93)
        (xy 15.429 1.907)
        (xy 15.874 1.907)
        (xy 15.874 1.903)
      )

      (stroke (width 0.001) (type solid)) (fill solid) (layer "B.Paste"))
    (fp_poly
      (pts
        (xy 15.874 3.173)
        (xy 15.429 3.173)
        (xy 15.43 3.151)
        (xy 15.432 3.127)
        (xy 15.435 3.105)
        (xy 15.439 3.081)
        (xy 15.444 3.06)
        (xy 15.451 3.037)
        (xy 15.458 3.016)
        (xy 15.467 2.993)
        (xy 15.477 2.972)
        (xy 15.489 2.952)
        (xy 15.502 2.932)
        (xy 15.515 2.913)
        (xy 15.528 2.895)
        (xy 15.544 2.877)
        (xy 15.56 2.86)
        (xy 15.576 2.844)
        (xy 15.593 2.83)
        (xy 15.612 2.815)
        (xy 15.631 2.802)
        (xy 15.651 2.79)
        (xy 15.672 2.778)
        (xy 15.692 2.768)
        (xy 15.714 2.759)
        (xy 15.736 2.752)
        (xy 15.759 2.746)
        (xy 15.781 2.741)
        (xy 15.803 2.735)
        (xy 15.826 2.733)
        (xy 15.851 2.731)
        (xy 15.874 2.73)
        (xy 15.897 2.731)
        (xy 15.922 2.733)
        (xy 15.944 2.735)
        (xy 15.967 2.741)
        (xy 15.989 2.746)
        (xy 16.013 2.752)
        (xy 16.033 2.76)
        (xy 16.056 2.768)
        (xy 16.077 2.779)
        (xy 16.097 2.79)
        (xy 16.117 2.802)
        (xy 16.137 2.815)
        (xy 16.155 2.83)
        (xy 16.172 2.844)
        (xy 16.19 2.86)
        (xy 16.205 2.877)
        (xy 16.22 2.895)
        (xy 16.234 2.913)
        (xy 16.248 2.933)
        (xy 16.26 2.952)
        (xy 16.271 2.973)
        (xy 16.281 2.995)
        (xy 16.289 3.016)
        (xy 16.297 3.037)
        (xy 16.304 3.06)
        (xy 16.309 3.082)
        (xy 16.315 3.105)
        (xy 16.318 3.129)
        (xy 16.318 3.153)
        (xy 16.319 3.175)
        (xy 16.318 3.198)
        (xy 16.318 3.222)
        (xy 16.315 3.246)
        (xy 16.309 3.268)
        (xy 16.304 3.29)
        (xy 16.297 3.314)
        (xy 16.289 3.335)
        (xy 16.281 3.356)
        (xy 16.271 3.377)
        (xy 16.26 3.397)
        (xy 16.248 3.417)
        (xy 16.234 3.437)
        (xy 16.22 3.455)
        (xy 16.205 3.473)
        (xy 16.19 3.491)
        (xy 16.172 3.506)
        (xy 16.155 3.521)
        (xy 16.137 3.536)
        (xy 16.117 3.548)
        (xy 16.097 3.56)
        (xy 16.077 3.572)
        (xy 16.056 3.582)
        (xy 16.033 3.59)
        (xy 16.013 3.598)
        (xy 15.989 3.605)
        (xy 15.967 3.61)
        (xy 15.944 3.616)
        (xy 15.922 3.618)
        (xy 15.897 3.62)
        (xy 15.874 3.621)
        (xy 15.851 3.62)
        (xy 15.826 3.618)
        (xy 15.803 3.616)
        (xy 15.781 3.61)
        (xy 15.759 3.605)
        (xy 15.736 3.598)
        (xy 15.714 3.592)
        (xy 15.692 3.582)
        (xy 15.672 3.572)
        (xy 15.651 3.561)
        (xy 15.631 3.548)
        (xy 15.612 3.536)
        (xy 15.593 3.521)
        (xy 15.576 3.506)
        (xy 15.56 3.491)
        (xy 15.544 3.473)
        (xy 15.528 3.456)
        (xy 15.515 3.437)
        (xy 15.502 3.419)
        (xy 15.489 3.399)
        (xy 15.477 3.379)
        (xy 15.467 3.358)
        (xy 15.458 3.335)
        (xy 15.451 3.314)
        (xy 15.444 3.291)
        (xy 15.439 3.27)
        (xy 15.435 3.246)
        (xy 15.432 3.223)
        (xy 15.43 3.199)
        (xy 15.429 3.178)
        (xy 15.874 3.178)
        (xy 15.874 3.173)
      )

      (stroke (width 0.001) (type solid)) (fill solid) (layer "B.Paste"))
    (fp_poly
      (pts
        (xy 15.874 4.443)
        (xy 15.429 4.443)
        (xy 15.43 4.422)
        (xy 15.432 4.398)
        (xy 15.435 4.374)
        (xy 15.439 4.351)
        (xy 15.444 4.329)
        (xy 15.451 4.308)
        (xy 15.458 4.286)
        (xy 15.467 4.263)
        (xy 15.477 4.242)
        (xy 15.489 4.223)
        (xy 15.502 4.202)
        (xy 15.515 4.183)
        (xy 15.528 4.164)
        (xy 15.544 4.148)
        (xy 15.56 4.13)
        (xy 15.576 4.114)
        (xy 15.593 4.1)
        (xy 15.612 4.085)
        (xy 15.631 4.072)
        (xy 15.651 4.06)
        (xy 15.672 4.048)
        (xy 15.692 4.039)
        (xy 15.714 4.029)
        (xy 15.736 4.023)
        (xy 15.759 4.015)
        (xy 15.781 4.01)
        (xy 15.803 4.005)
        (xy 15.826 4.002)
        (xy 15.851 4.002)
        (xy 15.874 4)
        (xy 15.897 4.002)
        (xy 15.922 4.002)
        (xy 15.944 4.005)
        (xy 15.967 4.01)
        (xy 15.989 4.015)
        (xy 16.013 4.023)
        (xy 16.033 4.031)
        (xy 16.056 4.039)
        (xy 16.077 4.05)
        (xy 16.097 4.06)
        (xy 16.117 4.072)
        (xy 16.137 4.085)
        (xy 16.155 4.1)
        (xy 16.172 4.114)
        (xy 16.19 4.13)
        (xy 16.205 4.148)
        (xy 16.22 4.165)
        (xy 16.234 4.183)
        (xy 16.248 4.204)
        (xy 16.26 4.223)
        (xy 16.271 4.244)
        (xy 16.281 4.265)
        (xy 16.289 4.286)
        (xy 16.297 4.308)
        (xy 16.304 4.33)
        (xy 16.309 4.353)
        (xy 16.315 4.375)
        (xy 16.318 4.398)
        (xy 16.318 4.422)
        (xy 16.319 4.446)
        (xy 16.318 4.468)
        (xy 16.318 4.492)
        (xy 16.315 4.515)
        (xy 16.309 4.539)
        (xy 16.304 4.56)
        (xy 16.297 4.584)
        (xy 16.289 4.604)
        (xy 16.281 4.627)
        (xy 16.271 4.648)
        (xy 16.26 4.669)
        (xy 16.248 4.688)
        (xy 16.234 4.707)
        (xy 16.22 4.725)
        (xy 16.205 4.744)
        (xy 16.19 4.76)
        (xy 16.172 4.776)
        (xy 16.155 4.792)
        (xy 16.137 4.805)
        (xy 16.117 4.818)
        (xy 16.097 4.83)
        (xy 16.077 4.842)
        (xy 16.056 4.853)
        (xy 16.033 4.861)
        (xy 16.013 4.869)
        (xy 15.989 4.875)
        (xy 15.967 4.88)
        (xy 15.944 4.885)
        (xy 15.922 4.888)
        (xy 15.897 4.89)
        (xy 15.874 4.89)
        (xy 15.851 4.89)
        (xy 15.826 4.888)
        (xy 15.803 4.885)
        (xy 15.781 4.88)
        (xy 15.759 4.875)
        (xy 15.736 4.869)
        (xy 15.714 4.861)
        (xy 15.692 4.853)
        (xy 15.672 4.842)
        (xy 15.651 4.832)
        (xy 15.631 4.818)
        (xy 15.612 4.805)
        (xy 15.593 4.792)
        (xy 15.576 4.776)
        (xy 15.56 4.76)
        (xy 15.544 4.744)
        (xy 15.528 4.726)
        (xy 15.515 4.707)
        (xy 15.502 4.688)
        (xy 15.489 4.669)
        (xy 15.477 4.648)
        (xy 15.467 4.627)
        (xy 15.458 4.606)
        (xy 15.451 4.584)
        (xy 15.444 4.561)
        (xy 15.439 4.539)
        (xy 15.435 4.516)
        (xy 15.432 4.494)
        (xy 15.43 4.47)
        (xy 15.429 4.447)
        (xy 15.874 4.447)
        (xy 15.874 4.443)
      )

      (stroke (width 0.001) (type solid)) (fill solid) (layer "B.Paste"))
    (fp_poly
      (pts
        (xy 15.874 5.713)
        (xy 15.429 5.713)
        (xy 15.43 5.691)
        (xy 15.432 5.667)
        (xy 15.435 5.645)
        (xy 15.439 5.622)
        (xy 15.444 5.6)
        (xy 15.451 5.577)
        (xy 15.458 5.555)
        (xy 15.467 5.534)
        (xy 15.477 5.512)
        (xy 15.489 5.492)
        (xy 15.502 5.473)
        (xy 15.515 5.454)
        (xy 15.528 5.435)
        (xy 15.544 5.417)
        (xy 15.56 5.401)
        (xy 15.576 5.385)
        (xy 15.593 5.369)
        (xy 15.612 5.356)
        (xy 15.631 5.342)
        (xy 15.651 5.329)
        (xy 15.672 5.318)
        (xy 15.692 5.308)
        (xy 15.714 5.3)
        (xy 15.736 5.292)
        (xy 15.759 5.286)
        (xy 15.781 5.281)
        (xy 15.803 5.276)
        (xy 15.826 5.273)
        (xy 15.851 5.271)
        (xy 15.874 5.27)
        (xy 15.897 5.271)
        (xy 15.922 5.273)
        (xy 15.944 5.276)
        (xy 15.967 5.281)
        (xy 15.989 5.286)
        (xy 16.013 5.292)
        (xy 16.033 5.3)
        (xy 16.056 5.308)
        (xy 16.077 5.319)
        (xy 16.097 5.33)
        (xy 16.117 5.342)
        (xy 16.137 5.356)
        (xy 16.155 5.369)
        (xy 16.172 5.385)
        (xy 16.19 5.401)
        (xy 16.205 5.417)
        (xy 16.22 5.435)
        (xy 16.234 5.454)
        (xy 16.248 5.473)
        (xy 16.26 5.492)
        (xy 16.271 5.513)
        (xy 16.281 5.534)
        (xy 16.289 5.556)
        (xy 16.297 5.577)
        (xy 16.304 5.6)
        (xy 16.309 5.622)
        (xy 16.315 5.645)
        (xy 16.318 5.669)
        (xy 16.318 5.693)
        (xy 16.319 5.715)
        (xy 16.318 5.739)
        (xy 16.318 5.762)
        (xy 16.315 5.786)
        (xy 16.309 5.808)
        (xy 16.304 5.83)
        (xy 16.297 5.853)
        (xy 16.289 5.874)
        (xy 16.281 5.896)
        (xy 16.271 5.917)
        (xy 16.26 5.938)
        (xy 16.248 5.957)
        (xy 16.234 5.978)
        (xy 16.22 5.995)
        (xy 16.205 6.013)
        (xy 16.19 6.031)
        (xy 16.172 6.047)
        (xy 16.155 6.061)
        (xy 16.137 6.076)
        (xy 16.117 6.088)
        (xy 16.097 6.1)
        (xy 16.077 6.111)
        (xy 16.056 6.122)
        (xy 16.033 6.13)
        (xy 16.013 6.138)
        (xy 15.989 6.145)
        (xy 15.967 6.151)
        (xy 15.944 6.156)
        (xy 15.922 6.159)
        (xy 15.897 6.159)
        (xy 15.874 6.161)
        (xy 15.851 6.159)
        (xy 15.826 6.159)
        (xy 15.803 6.156)
        (xy 15.781 6.151)
        (xy 15.759 6.145)
        (xy 15.736 6.138)
        (xy 15.714 6.132)
        (xy 15.692 6.122)
        (xy 15.672 6.112)
        (xy 15.651 6.101)
        (xy 15.631 6.088)
        (xy 15.612 6.076)
        (xy 15.593 6.061)
        (xy 15.576 6.047)
        (xy 15.56 6.031)
        (xy 15.544 6.013)
        (xy 15.528 5.997)
        (xy 15.515 5.978)
        (xy 15.502 5.959)
        (xy 15.489 5.938)
        (xy 15.477 5.919)
        (xy 15.467 5.898)
        (xy 15.458 5.875)
        (xy 15.451 5.853)
        (xy 15.444 5.832)
        (xy 15.439 5.81)
        (xy 15.435 5.786)
        (xy 15.432 5.763)
        (xy 15.43 5.739)
        (xy 15.429 5.718)
        (xy 15.874 5.718)
        (xy 15.874 5.713)
      )

      (stroke (width 0.001) (type solid)) (fill solid) (layer "B.Paste"))
    (fp_poly
      (pts
        (xy 17.144 -5.717)
        (xy 16.699 -5.717)
        (xy 16.701 -5.738)
        (xy 16.702 -5.762)
        (xy 16.704 -5.785)
        (xy 16.71 -5.809)
        (xy 16.714 -5.831)
        (xy 16.722 -5.852)
        (xy 16.728 -5.874)
        (xy 16.737 -5.897)
        (xy 16.748 -5.918)
        (xy 16.758 -5.937)
        (xy 16.771 -5.958)
        (xy 16.784 -5.977)
        (xy 16.798 -5.996)
        (xy 16.813 -6.012)
        (xy 16.829 -6.03)
        (xy 16.847 -6.046)
        (xy 16.864 -6.06)
        (xy 16.882 -6.075)
        (xy 16.902 -6.087)
        (xy 16.922 -6.1)
        (xy 16.941 -6.111)
        (xy 16.963 -6.121)
        (xy 16.984 -6.131)
        (xy 17.007 -6.137)
        (xy 17.028 -6.144)
        (xy 17.05 -6.15)
        (xy 17.074 -6.155)
        (xy 17.097 -6.158)
        (xy 17.12 -6.158)
        (xy 17.144 -6.16)
        (xy 17.167 -6.158)
        (xy 17.191 -6.158)
        (xy 17.214 -6.155)
        (xy 17.237 -6.15)
        (xy 17.26 -6.144)
        (xy 17.283 -6.137)
        (xy 17.303 -6.129)
        (xy 17.326 -6.121)
        (xy 17.347 -6.11)
        (xy 17.367 -6.099)
        (xy 17.387 -6.087)
        (xy 17.406 -6.075)
        (xy 17.425 -6.06)
        (xy 17.443 -6.046)
        (xy 17.46 -6.03)
        (xy 17.475 -6.012)
        (xy 17.49 -5.994)
        (xy 17.504 -5.977)
        (xy 17.518 -5.956)
        (xy 17.53 -5.937)
        (xy 17.541 -5.916)
        (xy 17.551 -5.895)
        (xy 17.559 -5.873)
        (xy 17.568 -5.852)
        (xy 17.574 -5.829)
        (xy 17.579 -5.807)
        (xy 17.585 -5.785)
        (xy 17.588 -5.761)
        (xy 17.588 -5.738)
        (xy 17.589 -5.714)
        (xy 17.588 -5.692)
        (xy 17.588 -5.668)
        (xy 17.585 -5.644)
        (xy 17.579 -5.621)
        (xy 17.574 -5.599)
        (xy 17.568 -5.576)
        (xy 17.559 -5.555)
        (xy 17.551 -5.533)
        (xy 17.541 -5.512)
        (xy 17.53 -5.491)
        (xy 17.518 -5.472)
        (xy 17.504 -5.453)
        (xy 17.49 -5.434)
        (xy 17.475 -5.416)
        (xy 17.46 -5.4)
        (xy 17.443 -5.384)
        (xy 17.425 -5.368)
        (xy 17.406 -5.355)
        (xy 17.387 -5.341)
        (xy 17.367 -5.329)
        (xy 17.347 -5.318)
        (xy 17.326 -5.307)
        (xy 17.303 -5.299)
        (xy 17.283 -5.291)
        (xy 17.26 -5.285)
        (xy 17.237 -5.28)
        (xy 17.214 -5.275)
        (xy 17.191 -5.272)
        (xy 17.167 -5.27)
        (xy 17.144 -5.269)
        (xy 17.12 -5.27)
        (xy 17.097 -5.272)
        (xy 17.074 -5.275)
        (xy 17.05 -5.28)
        (xy 17.028 -5.285)
        (xy 17.007 -5.291)
        (xy 16.984 -5.299)
        (xy 16.963 -5.307)
        (xy 16.941 -5.317)
        (xy 16.922 -5.328)
        (xy 16.902 -5.341)
        (xy 16.882 -5.355)
        (xy 16.864 -5.368)
        (xy 16.847 -5.384)
        (xy 16.829 -5.4)
        (xy 16.813 -5.416)
        (xy 16.798 -5.434)
        (xy 16.784 -5.453)
        (xy 16.771 -5.472)
        (xy 16.758 -5.491)
        (xy 16.748 -5.511)
        (xy 16.737 -5.533)
        (xy 16.728 -5.554)
        (xy 16.722 -5.576)
        (xy 16.714 -5.599)
        (xy 16.71 -5.621)
        (xy 16.704 -5.644)
        (xy 16.702 -5.666)
        (xy 16.701 -5.69)
        (xy 16.699 -5.712)
        (xy 17.144 -5.712)
        (xy 17.144 -5.717)
      )

      (stroke (width 0.001) (type solid)) (fill solid) (layer "B.Paste"))
    (fp_poly
      (pts
        (xy 17.144 -3.177)
        (xy 16.699 -3.177)
        (xy 16.701 -3.198)
        (xy 16.702 -3.222)
        (xy 16.704 -3.245)
        (xy 16.71 -3.269)
        (xy 16.714 -3.29)
        (xy 16.722 -3.313)
        (xy 16.728 -3.334)
        (xy 16.737 -3.357)
        (xy 16.748 -3.378)
        (xy 16.758 -3.398)
        (xy 16.771 -3.418)
        (xy 16.784 -3.436)
        (xy 16.798 -3.455)
        (xy 16.813 -3.472)
        (xy 16.829 -3.49)
        (xy 16.847 -3.505)
        (xy 16.864 -3.52)
        (xy 16.882 -3.535)
        (xy 16.902 -3.547)
        (xy 16.922 -3.56)
        (xy 16.941 -3.571)
        (xy 16.963 -3.581)
        (xy 16.984 -3.591)
        (xy 17.007 -3.597)
        (xy 17.028 -3.604)
        (xy 17.05 -3.609)
        (xy 17.074 -3.615)
        (xy 17.097 -3.617)
        (xy 17.12 -3.619)
        (xy 17.144 -3.62)
        (xy 17.167 -3.619)
        (xy 17.191 -3.617)
        (xy 17.214 -3.615)
        (xy 17.237 -3.609)
        (xy 17.26 -3.604)
        (xy 17.283 -3.597)
        (xy 17.303 -3.589)
        (xy 17.326 -3.581)
        (xy 17.347 -3.571)
        (xy 17.367 -3.559)
        (xy 17.387 -3.547)
        (xy 17.406 -3.535)
        (xy 17.425 -3.52)
        (xy 17.443 -3.505)
        (xy 17.46 -3.49)
        (xy 17.475 -3.472)
        (xy 17.49 -3.454)
        (xy 17.504 -3.436)
        (xy 17.518 -3.416)
        (xy 17.53 -3.396)
        (xy 17.541 -3.376)
        (xy 17.551 -3.355)
        (xy 17.559 -3.334)
        (xy 17.568 -3.313)
        (xy 17.574 -3.289)
        (xy 17.579 -3.267)
        (xy 17.585 -3.245)
        (xy 17.588 -3.221)
        (xy 17.588 -3.197)
        (xy 17.589 -3.174)
        (xy 17.588 -3.152)
        (xy 17.588 -3.128)
        (xy 17.585 -3.104)
        (xy 17.579 -3.081)
        (xy 17.574 -3.059)
        (xy 17.568 -3.036)
        (xy 17.559 -3.015)
        (xy 17.551 -2.994)
        (xy 17.541 -2.972)
        (xy 17.53 -2.951)
        (xy 17.518 -2.932)
        (xy 17.504 -2.912)
        (xy 17.49 -2.894)
        (xy 17.475 -2.876)
        (xy 17.46 -2.859)
        (xy 17.443 -2.843)
        (xy 17.425 -2.829)
        (xy 17.406 -2.814)
        (xy 17.387 -2.801)
        (xy 17.367 -2.789)
        (xy 17.347 -2.778)
        (xy 17.326 -2.767)
        (xy 17.303 -2.759)
        (xy 17.283 -2.751)
        (xy 17.26 -2.745)
        (xy 17.237 -2.74)
        (xy 17.214 -2.734)
        (xy 17.191 -2.732)
        (xy 17.167 -2.73)
        (xy 17.144 -2.729)
        (xy 17.12 -2.73)
        (xy 17.097 -2.732)
        (xy 17.074 -2.734)
        (xy 17.05 -2.74)
        (xy 17.028 -2.745)
        (xy 17.007 -2.751)
        (xy 16.984 -2.758)
        (xy 16.963 -2.767)
        (xy 16.941 -2.777)
        (xy 16.922 -2.789)
        (xy 16.902 -2.801)
        (xy 16.882 -2.814)
        (xy 16.864 -2.829)
        (xy 16.847 -2.843)
        (xy 16.829 -2.859)
        (xy 16.813 -2.876)
        (xy 16.798 -2.894)
        (xy 16.784 -2.912)
        (xy 16.771 -2.931)
        (xy 16.758 -2.951)
        (xy 16.748 -2.971)
        (xy 16.737 -2.992)
        (xy 16.728 -3.015)
        (xy 16.722 -3.036)
        (xy 16.714 -3.059)
        (xy 16.71 -3.08)
        (xy 16.704 -3.104)
        (xy 16.702 -3.126)
        (xy 16.701 -3.15)
        (xy 16.699 -3.172)
        (xy 17.144 -3.172)
        (xy 17.144 -3.177)
      )

      (stroke (width 0.001) (type solid)) (fill solid) (layer "B.Paste"))
    (fp_poly
      (pts
        (xy 17.144 1.903)
        (xy 16.699 1.903)
        (xy 16.701 1.881)
        (xy 16.702 1.857)
        (xy 16.704 1.835)
        (xy 16.71 1.811)
        (xy 16.714 1.789)
        (xy 16.722 1.767)
        (xy 16.728 1.746)
        (xy 16.737 1.724)
        (xy 16.748 1.702)
        (xy 16.758 1.682)
        (xy 16.771 1.662)
        (xy 16.784 1.643)
        (xy 16.798 1.625)
        (xy 16.813 1.607)
        (xy 16.829 1.591)
        (xy 16.847 1.575)
        (xy 16.864 1.559)
        (xy 16.882 1.545)
        (xy 16.902 1.532)
        (xy 16.922 1.519)
        (xy 16.941 1.508)
        (xy 16.963 1.498)
        (xy 16.984 1.49)
        (xy 17.007 1.482)
        (xy 17.028 1.476)
        (xy 17.05 1.47)
        (xy 17.074 1.466)
        (xy 17.097 1.462)
        (xy 17.12 1.462)
        (xy 17.144 1.46)
        (xy 17.167 1.462)
        (xy 17.191 1.462)
        (xy 17.214 1.466)
        (xy 17.237 1.47)
        (xy 17.26 1.476)
        (xy 17.283 1.482)
        (xy 17.303 1.49)
        (xy 17.326 1.498)
        (xy 17.347 1.509)
        (xy 17.367 1.52)
        (xy 17.387 1.532)
        (xy 17.406 1.545)
        (xy 17.425 1.559)
        (xy 17.443 1.575)
        (xy 17.46 1.591)
        (xy 17.475 1.607)
        (xy 17.49 1.625)
        (xy 17.504 1.643)
        (xy 17.518 1.663)
        (xy 17.53 1.684)
        (xy 17.541 1.704)
        (xy 17.551 1.724)
        (xy 17.559 1.746)
        (xy 17.568 1.767)
        (xy 17.574 1.79)
        (xy 17.579 1.813)
        (xy 17.585 1.835)
        (xy 17.588 1.859)
        (xy 17.588 1.882)
        (xy 17.589 1.905)
        (xy 17.588 1.928)
        (xy 17.588 1.952)
        (xy 17.585 1.976)
        (xy 17.579 1.998)
        (xy 17.574 2.02)
        (xy 17.568 2.044)
        (xy 17.559 2.065)
        (xy 17.551 2.086)
        (xy 17.541 2.108)
        (xy 17.53 2.127)
        (xy 17.518 2.147)
        (xy 17.504 2.167)
        (xy 17.49 2.186)
        (xy 17.475 2.203)
        (xy 17.46 2.221)
        (xy 17.443 2.237)
        (xy 17.425 2.251)
        (xy 17.406 2.266)
        (xy 17.387 2.278)
        (xy 17.367 2.29)
        (xy 17.347 2.302)
        (xy 17.326 2.312)
        (xy 17.303 2.32)
        (xy 17.283 2.328)
        (xy 17.26 2.335)
        (xy 17.237 2.34)
        (xy 17.214 2.346)
        (xy 17.191 2.348)
        (xy 17.167 2.35)
        (xy 17.144 2.351)
        (xy 17.12 2.35)
        (xy 17.097 2.348)
        (xy 17.074 2.346)
        (xy 17.05 2.34)
        (xy 17.028 2.335)
        (xy 17.007 2.328)
        (xy 16.984 2.322)
        (xy 16.963 2.312)
        (xy 16.941 2.302)
        (xy 16.922 2.291)
        (xy 16.902 2.278)
        (xy 16.882 2.266)
        (xy 16.864 2.251)
        (xy 16.847 2.237)
        (xy 16.829 2.221)
        (xy 16.813 2.203)
        (xy 16.798 2.186)
        (xy 16.784 2.167)
        (xy 16.771 2.149)
        (xy 16.758 2.129)
        (xy 16.748 2.109)
        (xy 16.737 2.088)
        (xy 16.728 2.065)
        (xy 16.722 2.044)
        (xy 16.714 2.021)
        (xy 16.71 2)
        (xy 16.704 1.976)
        (xy 16.702 1.954)
        (xy 16.701 1.93)
        (xy 16.699 1.907)
        (xy 17.144 1.907)
        (xy 17.144 1.903)
      )

      (stroke (width 0.001) (type solid)) (fill solid) (layer "B.Paste"))
    (fp_poly
      (pts
        (xy 17.144 3.173)
        (xy 16.699 3.173)
        (xy 16.701 3.151)
        (xy 16.702 3.127)
        (xy 16.704 3.105)
        (xy 16.71 3.081)
        (xy 16.714 3.06)
        (xy 16.722 3.037)
        (xy 16.728 3.016)
        (xy 16.737 2.993)
        (xy 16.748 2.972)
        (xy 16.758 2.952)
        (xy 16.771 2.932)
        (xy 16.784 2.913)
        (xy 16.798 2.895)
        (xy 16.813 2.877)
        (xy 16.829 2.86)
        (xy 16.847 2.844)
        (xy 16.864 2.83)
        (xy 16.882 2.815)
        (xy 16.902 2.802)
        (xy 16.922 2.79)
        (xy 16.941 2.778)
        (xy 16.963 2.768)
        (xy 16.984 2.759)
        (xy 17.007 2.752)
        (xy 17.028 2.746)
        (xy 17.05 2.741)
        (xy 17.074 2.735)
        (xy 17.097 2.733)
        (xy 17.12 2.731)
        (xy 17.144 2.73)
        (xy 17.167 2.731)
        (xy 17.191 2.733)
        (xy 17.214 2.735)
        (xy 17.237 2.741)
        (xy 17.26 2.746)
        (xy 17.283 2.752)
        (xy 17.303 2.76)
        (xy 17.326 2.768)
        (xy 17.347 2.779)
        (xy 17.367 2.79)
        (xy 17.387 2.802)
        (xy 17.406 2.815)
        (xy 17.425 2.83)
        (xy 17.443 2.844)
        (xy 17.46 2.86)
        (xy 17.475 2.877)
        (xy 17.49 2.895)
        (xy 17.504 2.913)
        (xy 17.518 2.933)
        (xy 17.53 2.952)
        (xy 17.541 2.973)
        (xy 17.551 2.995)
        (xy 17.559 3.016)
        (xy 17.568 3.037)
        (xy 17.574 3.06)
        (xy 17.579 3.082)
        (xy 17.585 3.105)
        (xy 17.588 3.129)
        (xy 17.588 3.153)
        (xy 17.589 3.175)
        (xy 17.588 3.198)
        (xy 17.588 3.222)
        (xy 17.585 3.246)
        (xy 17.579 3.268)
        (xy 17.574 3.29)
        (xy 17.568 3.314)
        (xy 17.559 3.335)
        (xy 17.551 3.356)
        (xy 17.541 3.377)
        (xy 17.53 3.397)
        (xy 17.518 3.417)
        (xy 17.504 3.437)
        (xy 17.49 3.455)
        (xy 17.475 3.473)
        (xy 17.46 3.491)
        (xy 17.443 3.506)
        (xy 17.425 3.521)
        (xy 17.406 3.536)
        (xy 17.387 3.548)
        (xy 17.367 3.56)
        (xy 17.347 3.572)
        (xy 17.326 3.582)
        (xy 17.303 3.59)
        (xy 17.283 3.598)
        (xy 17.26 3.605)
        (xy 17.237 3.61)
        (xy 17.214 3.616)
        (xy 17.191 3.618)
        (xy 17.167 3.62)
        (xy 17.144 3.621)
        (xy 17.12 3.62)
        (xy 17.097 3.618)
        (xy 17.074 3.616)
        (xy 17.05 3.61)
        (xy 17.028 3.605)
        (xy 17.007 3.598)
        (xy 16.984 3.592)
        (xy 16.963 3.582)
        (xy 16.941 3.572)
        (xy 16.922 3.561)
        (xy 16.902 3.548)
        (xy 16.882 3.536)
        (xy 16.864 3.521)
        (xy 16.847 3.506)
        (xy 16.829 3.491)
        (xy 16.813 3.473)
        (xy 16.798 3.456)
        (xy 16.784 3.437)
        (xy 16.771 3.419)
        (xy 16.758 3.399)
        (xy 16.748 3.379)
        (xy 16.737 3.358)
        (xy 16.728 3.335)
        (xy 16.722 3.314)
        (xy 16.714 3.291)
        (xy 16.71 3.27)
        (xy 16.704 3.246)
        (xy 16.702 3.223)
        (xy 16.701 3.199)
        (xy 16.699 3.178)
        (xy 17.144 3.178)
        (xy 17.144 3.173)
      )

      (stroke (width 0.001) (type solid)) (fill solid) (layer "B.Paste"))
    (fp_poly
      (pts
        (xy 17.144 4.443)
        (xy 16.699 4.443)
        (xy 16.701 4.422)
        (xy 16.702 4.398)
        (xy 16.704 4.374)
        (xy 16.71 4.351)
        (xy 16.714 4.329)
        (xy 16.722 4.308)
        (xy 16.728 4.286)
        (xy 16.737 4.263)
        (xy 16.748 4.242)
        (xy 16.758 4.223)
        (xy 16.771 4.202)
        (xy 16.784 4.183)
        (xy 16.798 4.164)
        (xy 16.813 4.148)
        (xy 16.829 4.13)
        (xy 16.847 4.114)
        (xy 16.864 4.1)
        (xy 16.882 4.085)
        (xy 16.902 4.072)
        (xy 16.922 4.06)
        (xy 16.941 4.048)
        (xy 16.963 4.039)
        (xy 16.984 4.029)
        (xy 17.007 4.023)
        (xy 17.028 4.015)
        (xy 17.05 4.01)
        (xy 17.074 4.005)
        (xy 17.097 4.002)
        (xy 17.12 4.002)
        (xy 17.144 4)
        (xy 17.167 4.002)
        (xy 17.191 4.002)
        (xy 17.214 4.005)
        (xy 17.237 4.01)
        (xy 17.26 4.015)
        (xy 17.283 4.023)
        (xy 17.303 4.031)
        (xy 17.326 4.039)
        (xy 17.347 4.05)
        (xy 17.367 4.06)
        (xy 17.387 4.072)
        (xy 17.406 4.085)
        (xy 17.425 4.1)
        (xy 17.443 4.114)
        (xy 17.46 4.13)
        (xy 17.475 4.148)
        (xy 17.49 4.165)
        (xy 17.504 4.183)
        (xy 17.518 4.204)
        (xy 17.53 4.223)
        (xy 17.541 4.244)
        (xy 17.551 4.265)
        (xy 17.559 4.286)
        (xy 17.568 4.308)
        (xy 17.574 4.33)
        (xy 17.579 4.353)
        (xy 17.585 4.375)
        (xy 17.588 4.398)
        (xy 17.588 4.422)
        (xy 17.589 4.446)
        (xy 17.588 4.468)
        (xy 17.588 4.492)
        (xy 17.585 4.515)
        (xy 17.579 4.539)
        (xy 17.574 4.56)
        (xy 17.568 4.584)
        (xy 17.559 4.604)
        (xy 17.551 4.627)
        (xy 17.541 4.648)
        (xy 17.53 4.669)
        (xy 17.518 4.688)
        (xy 17.504 4.707)
        (xy 17.49 4.725)
        (xy 17.475 4.744)
        (xy 17.46 4.76)
        (xy 17.443 4.776)
        (xy 17.425 4.792)
        (xy 17.406 4.805)
        (xy 17.387 4.818)
        (xy 17.367 4.83)
        (xy 17.347 4.842)
        (xy 17.326 4.853)
        (xy 17.303 4.861)
        (xy 17.283 4.869)
        (xy 17.26 4.875)
        (xy 17.237 4.88)
        (xy 17.214 4.885)
        (xy 17.191 4.888)
        (xy 17.167 4.89)
        (xy 17.144 4.89)
        (xy 17.12 4.89)
        (xy 17.097 4.888)
        (xy 17.074 4.885)
        (xy 17.05 4.88)
        (xy 17.028 4.875)
        (xy 17.007 4.869)
        (xy 16.984 4.861)
        (xy 16.963 4.853)
        (xy 16.941 4.842)
        (xy 16.922 4.832)
        (xy 16.902 4.818)
        (xy 16.882 4.805)
        (xy 16.864 4.792)
        (xy 16.847 4.776)
        (xy 16.829 4.76)
        (xy 16.813 4.744)
        (xy 16.798 4.726)
        (xy 16.784 4.707)
        (xy 16.771 4.688)
        (xy 16.758 4.669)
        (xy 16.748 4.648)
        (xy 16.737 4.627)
        (xy 16.728 4.606)
        (xy 16.722 4.584)
        (xy 16.714 4.561)
        (xy 16.71 4.539)
        (xy 16.704 4.516)
        (xy 16.702 4.494)
        (xy 16.701 4.47)
        (xy 16.699 4.447)
        (xy 17.144 4.447)
        (xy 17.144 4.443)
      )

      (stroke (width 0.001) (type solid)) (fill solid) (layer "B.Paste"))
    (fp_poly
      (pts
        (xy 17.144 5.713)
        (xy 16.699 5.713)
        (xy 16.701 5.691)
        (xy 16.702 5.667)
        (xy 16.704 5.645)
        (xy 16.71 5.622)
        (xy 16.714 5.6)
        (xy 16.722 5.577)
        (xy 16.728 5.555)
        (xy 16.737 5.534)
        (xy 16.748 5.512)
        (xy 16.758 5.492)
        (xy 16.771 5.473)
        (xy 16.784 5.454)
        (xy 16.798 5.435)
        (xy 16.813 5.417)
        (xy 16.829 5.401)
        (xy 16.847 5.385)
        (xy 16.864 5.369)
        (xy 16.882 5.356)
        (xy 16.902 5.342)
        (xy 16.922 5.329)
        (xy 16.941 5.318)
        (xy 16.963 5.308)
        (xy 16.984 5.3)
        (xy 17.007 5.292)
        (xy 17.028 5.286)
        (xy 17.05 5.281)
        (xy 17.074 5.276)
        (xy 17.097 5.273)
        (xy 17.12 5.271)
        (xy 17.144 5.27)
        (xy 17.167 5.271)
        (xy 17.191 5.273)
        (xy 17.214 5.276)
        (xy 17.237 5.281)
        (xy 17.26 5.286)
        (xy 17.283 5.292)
        (xy 17.303 5.3)
        (xy 17.326 5.308)
        (xy 17.347 5.319)
        (xy 17.367 5.33)
        (xy 17.387 5.342)
        (xy 17.406 5.356)
        (xy 17.425 5.369)
        (xy 17.443 5.385)
        (xy 17.46 5.401)
        (xy 17.475 5.417)
        (xy 17.49 5.435)
        (xy 17.504 5.454)
        (xy 17.518 5.473)
        (xy 17.53 5.492)
        (xy 17.541 5.513)
        (xy 17.551 5.534)
        (xy 17.559 5.556)
        (xy 17.568 5.577)
        (xy 17.574 5.6)
        (xy 17.579 5.622)
        (xy 17.585 5.645)
        (xy 17.588 5.669)
        (xy 17.588 5.693)
        (xy 17.589 5.715)
        (xy 17.588 5.739)
        (xy 17.588 5.762)
        (xy 17.585 5.786)
        (xy 17.579 5.808)
        (xy 17.574 5.83)
        (xy 17.568 5.853)
        (xy 17.559 5.874)
        (xy 17.551 5.896)
        (xy 17.541 5.917)
        (xy 17.53 5.938)
        (xy 17.518 5.957)
        (xy 17.504 5.978)
        (xy 17.49 5.995)
        (xy 17.475 6.013)
        (xy 17.46 6.031)
        (xy 17.443 6.047)
        (xy 17.425 6.061)
        (xy 17.406 6.076)
        (xy 17.387 6.088)
        (xy 17.367 6.1)
        (xy 17.347 6.111)
        (xy 17.326 6.122)
        (xy 17.303 6.13)
        (xy 17.283 6.138)
        (xy 17.26 6.145)
        (xy 17.237 6.151)
        (xy 17.214 6.156)
        (xy 17.191 6.159)
        (xy 17.167 6.159)
        (xy 17.144 6.161)
        (xy 17.12 6.159)
        (xy 17.097 6.159)
        (xy 17.074 6.156)
        (xy 17.05 6.151)
        (xy 17.028 6.145)
        (xy 17.007 6.138)
        (xy 16.984 6.132)
        (xy 16.963 6.122)
        (xy 16.941 6.112)
        (xy 16.922 6.101)
        (xy 16.902 6.088)
        (xy 16.882 6.076)
        (xy 16.864 6.061)
        (xy 16.847 6.047)
        (xy 16.829 6.031)
        (xy 16.813 6.013)
        (xy 16.798 5.997)
        (xy 16.784 5.978)
        (xy 16.771 5.959)
        (xy 16.758 5.938)
        (xy 16.748 5.919)
        (xy 16.737 5.898)
        (xy 16.728 5.875)
        (xy 16.722 5.853)
        (xy 16.714 5.832)
        (xy 16.71 5.81)
        (xy 16.704 5.786)
        (xy 16.702 5.763)
        (xy 16.701 5.739)
        (xy 16.699 5.718)
        (xy 17.144 5.718)
        (xy 17.144 5.713)
      )

      (stroke (width 0.001) (type solid)) (fill solid) (layer "B.Paste"))
    (fp_poly
      (pts
        (xy 18.414 -5.717)
        (xy 17.969 -5.717)
        (xy 17.97 -5.738)
        (xy 17.972 -5.762)
        (xy 17.975 -5.785)
        (xy 17.98 -5.809)
        (xy 17.984 -5.831)
        (xy 17.992 -5.852)
        (xy 17.998 -5.874)
        (xy 18.007 -5.897)
        (xy 18.018 -5.918)
        (xy 18.028 -5.937)
        (xy 18.042 -5.958)
        (xy 18.054 -5.977)
        (xy 18.068 -5.996)
        (xy 18.083 -6.012)
        (xy 18.1 -6.03)
        (xy 18.117 -6.046)
        (xy 18.133 -6.06)
        (xy 18.152 -6.075)
        (xy 18.172 -6.087)
        (xy 18.191 -6.1)
        (xy 18.211 -6.111)
        (xy 18.233 -6.121)
        (xy 18.254 -6.131)
        (xy 18.277 -6.137)
        (xy 18.298 -6.144)
        (xy 18.321 -6.15)
        (xy 18.344 -6.155)
        (xy 18.367 -6.158)
        (xy 18.39 -6.158)
        (xy 18.414 -6.16)
        (xy 18.437 -6.158)
        (xy 18.461 -6.158)
        (xy 18.484 -6.155)
        (xy 18.507 -6.15)
        (xy 18.53 -6.144)
        (xy 18.553 -6.137)
        (xy 18.574 -6.129)
        (xy 18.595 -6.121)
        (xy 18.617 -6.11)
        (xy 18.637 -6.099)
        (xy 18.656 -6.087)
        (xy 18.676 -6.075)
        (xy 18.694 -6.06)
        (xy 18.713 -6.046)
        (xy 18.73 -6.03)
        (xy 18.745 -6.012)
        (xy 18.76 -5.994)
        (xy 18.774 -5.977)
        (xy 18.787 -5.956)
        (xy 18.8 -5.937)
        (xy 18.81 -5.916)
        (xy 18.821 -5.895)
        (xy 18.829 -5.873)
        (xy 18.838 -5.852)
        (xy 18.844 -5.829)
        (xy 18.85 -5.807)
        (xy 18.855 -5.785)
        (xy 18.858 -5.761)
        (xy 18.859 -5.738)
        (xy 18.859 -5.714)
        (xy 18.859 -5.692)
        (xy 18.858 -5.668)
        (xy 18.855 -5.644)
        (xy 18.85 -5.621)
        (xy 18.844 -5.599)
        (xy 18.838 -5.576)
        (xy 18.829 -5.555)
        (xy 18.821 -5.533)
        (xy 18.81 -5.512)
        (xy 18.8 -5.491)
        (xy 18.787 -5.472)
        (xy 18.774 -5.453)
        (xy 18.76 -5.434)
        (xy 18.745 -5.416)
        (xy 18.73 -5.4)
        (xy 18.713 -5.384)
        (xy 18.694 -5.368)
        (xy 18.676 -5.355)
        (xy 18.656 -5.341)
        (xy 18.637 -5.329)
        (xy 18.617 -5.318)
        (xy 18.595 -5.307)
        (xy 18.574 -5.299)
        (xy 18.553 -5.291)
        (xy 18.53 -5.285)
        (xy 18.507 -5.28)
        (xy 18.484 -5.275)
        (xy 18.461 -5.272)
        (xy 18.437 -5.27)
        (xy 18.414 -5.269)
        (xy 18.39 -5.27)
        (xy 18.367 -5.272)
        (xy 18.344 -5.275)
        (xy 18.321 -5.28)
        (xy 18.298 -5.285)
        (xy 18.277 -5.291)
        (xy 18.254 -5.299)
        (xy 18.233 -5.307)
        (xy 18.211 -5.317)
        (xy 18.191 -5.328)
        (xy 18.172 -5.341)
        (xy 18.152 -5.355)
        (xy 18.133 -5.368)
        (xy 18.117 -5.384)
        (xy 18.1 -5.4)
        (xy 18.083 -5.416)
        (xy 18.068 -5.434)
        (xy 18.054 -5.453)
        (xy 18.042 -5.472)
        (xy 18.028 -5.491)
        (xy 18.018 -5.511)
        (xy 18.007 -5.533)
        (xy 17.998 -5.554)
        (xy 17.992 -5.576)
        (xy 17.984 -5.599)
        (xy 17.98 -5.621)
        (xy 17.975 -5.644)
        (xy 17.972 -5.666)
        (xy 17.97 -5.69)
        (xy 17.969 -5.712)
        (xy 18.414 -5.712)
        (xy 18.414 -5.717)
      )

      (stroke (width 0.001) (type solid)) (fill solid) (layer "B.Paste"))
    (fp_poly
      (pts
        (xy 18.414 -3.177)
        (xy 17.969 -3.177)
        (xy 17.97 -3.198)
        (xy 17.972 -3.222)
        (xy 17.975 -3.245)
        (xy 17.98 -3.269)
        (xy 17.984 -3.29)
        (xy 17.992 -3.313)
        (xy 17.998 -3.334)
        (xy 18.007 -3.357)
        (xy 18.018 -3.378)
        (xy 18.028 -3.398)
        (xy 18.042 -3.418)
        (xy 18.054 -3.436)
        (xy 18.068 -3.455)
        (xy 18.083 -3.472)
        (xy 18.1 -3.49)
        (xy 18.117 -3.505)
        (xy 18.133 -3.52)
        (xy 18.152 -3.535)
        (xy 18.172 -3.547)
        (xy 18.191 -3.56)
        (xy 18.211 -3.571)
        (xy 18.233 -3.581)
        (xy 18.254 -3.591)
        (xy 18.277 -3.597)
        (xy 18.298 -3.604)
        (xy 18.321 -3.609)
        (xy 18.344 -3.615)
        (xy 18.367 -3.617)
        (xy 18.39 -3.619)
        (xy 18.414 -3.62)
        (xy 18.437 -3.619)
        (xy 18.461 -3.617)
        (xy 18.484 -3.615)
        (xy 18.507 -3.609)
        (xy 18.53 -3.604)
        (xy 18.553 -3.597)
        (xy 18.574 -3.589)
        (xy 18.595 -3.581)
        (xy 18.617 -3.571)
        (xy 18.637 -3.559)
        (xy 18.656 -3.547)
        (xy 18.676 -3.535)
        (xy 18.694 -3.52)
        (xy 18.713 -3.505)
        (xy 18.73 -3.49)
        (xy 18.745 -3.472)
        (xy 18.76 -3.454)
        (xy 18.774 -3.436)
        (xy 18.787 -3.416)
        (xy 18.8 -3.396)
        (xy 18.81 -3.376)
        (xy 18.821 -3.355)
        (xy 18.829 -3.334)
        (xy 18.838 -3.313)
        (xy 18.844 -3.289)
        (xy 18.85 -3.267)
        (xy 18.855 -3.245)
        (xy 18.858 -3.221)
        (xy 18.859 -3.197)
        (xy 18.859 -3.174)
        (xy 18.859 -3.152)
        (xy 18.858 -3.128)
        (xy 18.855 -3.104)
        (xy 18.85 -3.081)
        (xy 18.844 -3.059)
        (xy 18.838 -3.036)
        (xy 18.829 -3.015)
        (xy 18.821 -2.994)
        (xy 18.81 -2.972)
        (xy 18.8 -2.951)
        (xy 18.787 -2.932)
        (xy 18.774 -2.912)
        (xy 18.76 -2.894)
        (xy 18.745 -2.876)
        (xy 18.73 -2.859)
        (xy 18.713 -2.843)
        (xy 18.694 -2.829)
        (xy 18.676 -2.814)
        (xy 18.656 -2.801)
        (xy 18.637 -2.789)
        (xy 18.617 -2.778)
        (xy 18.595 -2.767)
        (xy 18.574 -2.759)
        (xy 18.553 -2.751)
        (xy 18.53 -2.745)
        (xy 18.507 -2.74)
        (xy 18.484 -2.734)
        (xy 18.461 -2.732)
        (xy 18.437 -2.73)
        (xy 18.414 -2.729)
        (xy 18.39 -2.73)
        (xy 18.367 -2.732)
        (xy 18.344 -2.734)
        (xy 18.321 -2.74)
        (xy 18.298 -2.745)
        (xy 18.277 -2.751)
        (xy 18.254 -2.758)
        (xy 18.233 -2.767)
        (xy 18.211 -2.777)
        (xy 18.191 -2.789)
        (xy 18.172 -2.801)
        (xy 18.152 -2.814)
        (xy 18.133 -2.829)
        (xy 18.117 -2.843)
        (xy 18.1 -2.859)
        (xy 18.083 -2.876)
        (xy 18.068 -2.894)
        (xy 18.054 -2.912)
        (xy 18.042 -2.931)
        (xy 18.028 -2.951)
        (xy 18.018 -2.971)
        (xy 18.007 -2.992)
        (xy 17.998 -3.015)
        (xy 17.992 -3.036)
        (xy 17.984 -3.059)
        (xy 17.98 -3.08)
        (xy 17.975 -3.104)
        (xy 17.972 -3.126)
        (xy 17.97 -3.15)
        (xy 17.969 -3.172)
        (xy 18.414 -3.172)
        (xy 18.414 -3.177)
      )

      (stroke (width 0.001) (type solid)) (fill solid) (layer "B.Paste"))
    (fp_poly
      (pts
        (xy 18.414 1.903)
        (xy 17.969 1.903)
        (xy 17.97 1.881)
        (xy 17.972 1.857)
        (xy 17.975 1.835)
        (xy 17.98 1.811)
        (xy 17.984 1.789)
        (xy 17.992 1.767)
        (xy 17.998 1.746)
        (xy 18.007 1.724)
        (xy 18.018 1.702)
        (xy 18.028 1.682)
        (xy 18.042 1.662)
        (xy 18.054 1.643)
        (xy 18.068 1.625)
        (xy 18.083 1.607)
        (xy 18.1 1.591)
        (xy 18.117 1.575)
        (xy 18.133 1.559)
        (xy 18.152 1.545)
        (xy 18.172 1.532)
        (xy 18.191 1.519)
        (xy 18.211 1.508)
        (xy 18.233 1.498)
        (xy 18.254 1.49)
        (xy 18.277 1.482)
        (xy 18.298 1.476)
        (xy 18.321 1.47)
        (xy 18.344 1.466)
        (xy 18.367 1.462)
        (xy 18.39 1.462)
        (xy 18.414 1.46)
        (xy 18.437 1.462)
        (xy 18.461 1.462)
        (xy 18.484 1.466)
        (xy 18.507 1.47)
        (xy 18.53 1.476)
        (xy 18.553 1.482)
        (xy 18.574 1.49)
        (xy 18.595 1.498)
        (xy 18.617 1.509)
        (xy 18.637 1.52)
        (xy 18.656 1.532)
        (xy 18.676 1.545)
        (xy 18.694 1.559)
        (xy 18.713 1.575)
        (xy 18.73 1.591)
        (xy 18.745 1.607)
        (xy 18.76 1.625)
        (xy 18.774 1.643)
        (xy 18.787 1.663)
        (xy 18.8 1.684)
        (xy 18.81 1.704)
        (xy 18.821 1.724)
        (xy 18.829 1.746)
        (xy 18.838 1.767)
        (xy 18.844 1.79)
        (xy 18.85 1.813)
        (xy 18.855 1.835)
        (xy 18.858 1.859)
        (xy 18.859 1.882)
        (xy 18.859 1.905)
        (xy 18.859 1.928)
        (xy 18.858 1.952)
        (xy 18.855 1.976)
        (xy 18.85 1.998)
        (xy 18.844 2.02)
        (xy 18.838 2.044)
        (xy 18.829 2.065)
        (xy 18.821 2.086)
        (xy 18.81 2.108)
        (xy 18.8 2.127)
        (xy 18.787 2.147)
        (xy 18.774 2.167)
        (xy 18.76 2.186)
        (xy 18.745 2.203)
        (xy 18.73 2.221)
        (xy 18.713 2.237)
        (xy 18.694 2.251)
        (xy 18.676 2.266)
        (xy 18.656 2.278)
        (xy 18.637 2.29)
        (xy 18.617 2.302)
        (xy 18.595 2.312)
        (xy 18.574 2.32)
        (xy 18.553 2.328)
        (xy 18.53 2.335)
        (xy 18.507 2.34)
        (xy 18.484 2.346)
        (xy 18.461 2.348)
        (xy 18.437 2.35)
        (xy 18.414 2.351)
        (xy 18.39 2.35)
        (xy 18.367 2.348)
        (xy 18.344 2.346)
        (xy 18.321 2.34)
        (xy 18.298 2.335)
        (xy 18.277 2.328)
        (xy 18.254 2.322)
        (xy 18.233 2.312)
        (xy 18.211 2.302)
        (xy 18.191 2.291)
        (xy 18.172 2.278)
        (xy 18.152 2.266)
        (xy 18.133 2.251)
        (xy 18.117 2.237)
        (xy 18.1 2.221)
        (xy 18.083 2.203)
        (xy 18.068 2.186)
        (xy 18.054 2.167)
        (xy 18.042 2.149)
        (xy 18.028 2.129)
        (xy 18.018 2.109)
        (xy 18.007 2.088)
        (xy 17.998 2.065)
        (xy 17.992 2.044)
        (xy 17.984 2.021)
        (xy 17.98 2)
        (xy 17.975 1.976)
        (xy 17.972 1.954)
        (xy 17.97 1.93)
        (xy 17.969 1.907)
        (xy 18.414 1.907)
        (xy 18.414 1.903)
      )

      (stroke (width 0.001) (type solid)) (fill solid) (layer "B.Paste"))
    (fp_poly
      (pts
        (xy 18.414 3.173)
        (xy 17.969 3.173)
        (xy 17.97 3.151)
        (xy 17.972 3.127)
        (xy 17.975 3.105)
        (xy 17.98 3.081)
        (xy 17.984 3.06)
        (xy 17.992 3.037)
        (xy 17.998 3.016)
        (xy 18.007 2.993)
        (xy 18.018 2.972)
        (xy 18.028 2.952)
        (xy 18.042 2.932)
        (xy 18.054 2.913)
        (xy 18.068 2.895)
        (xy 18.083 2.877)
        (xy 18.1 2.86)
        (xy 18.117 2.844)
        (xy 18.133 2.83)
        (xy 18.152 2.815)
        (xy 18.172 2.802)
        (xy 18.191 2.79)
        (xy 18.211 2.778)
        (xy 18.233 2.768)
        (xy 18.254 2.759)
        (xy 18.277 2.752)
        (xy 18.298 2.746)
        (xy 18.321 2.741)
        (xy 18.344 2.735)
        (xy 18.367 2.733)
        (xy 18.39 2.731)
        (xy 18.414 2.73)
        (xy 18.437 2.731)
        (xy 18.461 2.733)
        (xy 18.484 2.735)
        (xy 18.507 2.741)
        (xy 18.53 2.746)
        (xy 18.553 2.752)
        (xy 18.574 2.76)
        (xy 18.595 2.768)
        (xy 18.617 2.779)
        (xy 18.637 2.79)
        (xy 18.656 2.802)
        (xy 18.676 2.815)
        (xy 18.694 2.83)
        (xy 18.713 2.844)
        (xy 18.73 2.86)
        (xy 18.745 2.877)
        (xy 18.76 2.895)
        (xy 18.774 2.913)
        (xy 18.787 2.933)
        (xy 18.8 2.952)
        (xy 18.81 2.973)
        (xy 18.821 2.995)
        (xy 18.829 3.016)
        (xy 18.838 3.037)
        (xy 18.844 3.06)
        (xy 18.85 3.082)
        (xy 18.855 3.105)
        (xy 18.858 3.129)
        (xy 18.859 3.153)
        (xy 18.859 3.175)
        (xy 18.859 3.198)
        (xy 18.858 3.222)
        (xy 18.855 3.246)
        (xy 18.85 3.268)
        (xy 18.844 3.29)
        (xy 18.838 3.314)
        (xy 18.829 3.335)
        (xy 18.821 3.356)
        (xy 18.81 3.377)
        (xy 18.8 3.397)
        (xy 18.787 3.417)
        (xy 18.774 3.437)
        (xy 18.76 3.455)
        (xy 18.745 3.473)
        (xy 18.73 3.491)
        (xy 18.713 3.506)
        (xy 18.694 3.521)
        (xy 18.676 3.536)
        (xy 18.656 3.548)
        (xy 18.637 3.56)
        (xy 18.617 3.572)
        (xy 18.595 3.582)
        (xy 18.574 3.59)
        (xy 18.553 3.598)
        (xy 18.53 3.605)
        (xy 18.507 3.61)
        (xy 18.484 3.616)
        (xy 18.461 3.618)
        (xy 18.437 3.62)
        (xy 18.414 3.621)
        (xy 18.39 3.62)
        (xy 18.367 3.618)
        (xy 18.344 3.616)
        (xy 18.321 3.61)
        (xy 18.298 3.605)
        (xy 18.277 3.598)
        (xy 18.254 3.592)
        (xy 18.233 3.582)
        (xy 18.211 3.572)
        (xy 18.191 3.561)
        (xy 18.172 3.548)
        (xy 18.152 3.536)
        (xy 18.133 3.521)
        (xy 18.117 3.506)
        (xy 18.1 3.491)
        (xy 18.083 3.473)
        (xy 18.068 3.456)
        (xy 18.054 3.437)
        (xy 18.042 3.419)
        (xy 18.028 3.399)
        (xy 18.018 3.379)
        (xy 18.007 3.358)
        (xy 17.998 3.335)
        (xy 17.992 3.314)
        (xy 17.984 3.291)
        (xy 17.98 3.27)
        (xy 17.975 3.246)
        (xy 17.972 3.223)
        (xy 17.97 3.199)
        (xy 17.969 3.178)
        (xy 18.414 3.178)
        (xy 18.414 3.173)
      )

      (stroke (width 0.001) (type solid)) (fill solid) (layer "B.Paste"))
    (fp_poly
      (pts
        (xy 18.414 4.443)
        (xy 17.969 4.443)
        (xy 17.97 4.422)
        (xy 17.972 4.398)
        (xy 17.975 4.374)
        (xy 17.98 4.351)
        (xy 17.984 4.329)
        (xy 17.992 4.308)
        (xy 17.998 4.286)
        (xy 18.007 4.263)
        (xy 18.018 4.242)
        (xy 18.028 4.223)
        (xy 18.042 4.202)
        (xy 18.054 4.183)
        (xy 18.068 4.164)
        (xy 18.083 4.148)
        (xy 18.1 4.13)
        (xy 18.117 4.114)
        (xy 18.133 4.1)
        (xy 18.152 4.085)
        (xy 18.172 4.072)
        (xy 18.191 4.06)
        (xy 18.211 4.048)
        (xy 18.233 4.039)
        (xy 18.254 4.029)
        (xy 18.277 4.023)
        (xy 18.298 4.015)
        (xy 18.321 4.01)
        (xy 18.344 4.005)
        (xy 18.367 4.002)
        (xy 18.39 4.002)
        (xy 18.414 4)
        (xy 18.437 4.002)
        (xy 18.461 4.002)
        (xy 18.484 4.005)
        (xy 18.507 4.01)
        (xy 18.53 4.015)
        (xy 18.553 4.023)
        (xy 18.574 4.031)
        (xy 18.595 4.039)
        (xy 18.617 4.05)
        (xy 18.637 4.06)
        (xy 18.656 4.072)
        (xy 18.676 4.085)
        (xy 18.694 4.1)
        (xy 18.713 4.114)
        (xy 18.73 4.13)
        (xy 18.745 4.148)
        (xy 18.76 4.165)
        (xy 18.774 4.183)
        (xy 18.787 4.204)
        (xy 18.8 4.223)
        (xy 18.81 4.244)
        (xy 18.821 4.265)
        (xy 18.829 4.286)
        (xy 18.838 4.308)
        (xy 18.844 4.33)
        (xy 18.85 4.353)
        (xy 18.855 4.375)
        (xy 18.858 4.398)
        (xy 18.859 4.422)
        (xy 18.859 4.446)
        (xy 18.859 4.468)
        (xy 18.858 4.492)
        (xy 18.855 4.515)
        (xy 18.85 4.539)
        (xy 18.844 4.56)
        (xy 18.838 4.584)
        (xy 18.829 4.604)
        (xy 18.821 4.627)
        (xy 18.81 4.648)
        (xy 18.8 4.669)
        (xy 18.787 4.688)
        (xy 18.774 4.707)
        (xy 18.76 4.725)
        (xy 18.745 4.744)
        (xy 18.73 4.76)
        (xy 18.713 4.776)
        (xy 18.694 4.792)
        (xy 18.676 4.805)
        (xy 18.656 4.818)
        (xy 18.637 4.83)
        (xy 18.617 4.842)
        (xy 18.595 4.853)
        (xy 18.574 4.861)
        (xy 18.553 4.869)
        (xy 18.53 4.875)
        (xy 18.507 4.88)
        (xy 18.484 4.885)
        (xy 18.461 4.888)
        (xy 18.437 4.89)
        (xy 18.414 4.89)
        (xy 18.39 4.89)
        (xy 18.367 4.888)
        (xy 18.344 4.885)
        (xy 18.321 4.88)
        (xy 18.298 4.875)
        (xy 18.277 4.869)
        (xy 18.254 4.861)
        (xy 18.233 4.853)
        (xy 18.211 4.842)
        (xy 18.191 4.832)
        (xy 18.172 4.818)
        (xy 18.152 4.805)
        (xy 18.133 4.792)
        (xy 18.117 4.776)
        (xy 18.1 4.76)
        (xy 18.083 4.744)
        (xy 18.068 4.726)
        (xy 18.054 4.707)
        (xy 18.042 4.688)
        (xy 18.028 4.669)
        (xy 18.018 4.648)
        (xy 18.007 4.627)
        (xy 17.998 4.606)
        (xy 17.992 4.584)
        (xy 17.984 4.561)
        (xy 17.98 4.539)
        (xy 17.975 4.516)
        (xy 17.972 4.494)
        (xy 17.97 4.47)
        (xy 17.969 4.447)
        (xy 18.414 4.447)
        (xy 18.414 4.443)
      )

      (stroke (width 0.001) (type solid)) (fill solid) (layer "B.Paste"))
    (fp_poly
      (pts
        (xy 18.414 5.713)
        (xy 17.969 5.713)
        (xy 17.97 5.691)
        (xy 17.972 5.667)
        (xy 17.975 5.645)
        (xy 17.98 5.622)
        (xy 17.984 5.6)
        (xy 17.992 5.577)
        (xy 17.998 5.555)
        (xy 18.007 5.534)
        (xy 18.018 5.512)
        (xy 18.028 5.492)
        (xy 18.042 5.473)
        (xy 18.054 5.454)
        (xy 18.068 5.435)
        (xy 18.083 5.417)
        (xy 18.1 5.401)
        (xy 18.117 5.385)
        (xy 18.133 5.369)
        (xy 18.152 5.356)
        (xy 18.172 5.342)
        (xy 18.191 5.329)
        (xy 18.211 5.318)
        (xy 18.233 5.308)
        (xy 18.254 5.3)
        (xy 18.277 5.292)
        (xy 18.298 5.286)
        (xy 18.321 5.281)
        (xy 18.344 5.276)
        (xy 18.367 5.273)
        (xy 18.39 5.271)
        (xy 18.414 5.27)
        (xy 18.437 5.271)
        (xy 18.461 5.273)
        (xy 18.484 5.276)
        (xy 18.507 5.281)
        (xy 18.53 5.286)
        (xy 18.553 5.292)
        (xy 18.574 5.3)
        (xy 18.595 5.308)
        (xy 18.617 5.319)
        (xy 18.637 5.33)
        (xy 18.656 5.342)
        (xy 18.676 5.356)
        (xy 18.694 5.369)
        (xy 18.713 5.385)
        (xy 18.73 5.401)
        (xy 18.745 5.417)
        (xy 18.76 5.435)
        (xy 18.774 5.454)
        (xy 18.787 5.473)
        (xy 18.8 5.492)
        (xy 18.81 5.513)
        (xy 18.821 5.534)
        (xy 18.829 5.556)
        (xy 18.838 5.577)
        (xy 18.844 5.6)
        (xy 18.85 5.622)
        (xy 18.855 5.645)
        (xy 18.858 5.669)
        (xy 18.859 5.693)
        (xy 18.859 5.715)
        (xy 18.859 5.739)
        (xy 18.858 5.762)
        (xy 18.855 5.786)
        (xy 18.85 5.808)
        (xy 18.844 5.83)
        (xy 18.838 5.853)
        (xy 18.829 5.874)
        (xy 18.821 5.896)
        (xy 18.81 5.917)
        (xy 18.8 5.938)
        (xy 18.787 5.957)
        (xy 18.774 5.978)
        (xy 18.76 5.995)
        (xy 18.745 6.013)
        (xy 18.73 6.031)
        (xy 18.713 6.047)
        (xy 18.694 6.061)
        (xy 18.676 6.076)
        (xy 18.656 6.088)
        (xy 18.637 6.1)
        (xy 18.617 6.111)
        (xy 18.595 6.122)
        (xy 18.574 6.13)
        (xy 18.553 6.138)
        (xy 18.53 6.145)
        (xy 18.507 6.151)
        (xy 18.484 6.156)
        (xy 18.461 6.159)
        (xy 18.437 6.159)
        (xy 18.414 6.161)
        (xy 18.39 6.159)
        (xy 18.367 6.159)
        (xy 18.344 6.156)
        (xy 18.321 6.151)
        (xy 18.298 6.145)
        (xy 18.277 6.138)
        (xy 18.254 6.132)
        (xy 18.233 6.122)
        (xy 18.211 6.112)
        (xy 18.191 6.101)
        (xy 18.172 6.088)
        (xy 18.152 6.076)
        (xy 18.133 6.061)
        (xy 18.117 6.047)
        (xy 18.1 6.031)
        (xy 18.083 6.013)
        (xy 18.068 5.997)
        (xy 18.054 5.978)
        (xy 18.042 5.959)
        (xy 18.028 5.938)
        (xy 18.018 5.919)
        (xy 18.007 5.898)
        (xy 17.998 5.875)
        (xy 17.992 5.853)
        (xy 17.984 5.832)
        (xy 17.98 5.81)
        (xy 17.975 5.786)
        (xy 17.972 5.763)
        (xy 17.97 5.739)
        (xy 17.969 5.718)
        (xy 18.414 5.718)
        (xy 18.414 5.713)
      )

      (stroke (width 0.001) (type solid)) (fill solid) (layer "B.Paste"))
    (fp_poly
      (pts
        (xy 19.684 -5.717)
        (xy 19.239 -5.717)
        (xy 19.24 -5.738)
        (xy 19.242 -5.762)
        (xy 19.245 -5.785)
        (xy 19.249 -5.809)
        (xy 19.254 -5.831)
        (xy 19.262 -5.852)
        (xy 19.268 -5.874)
        (xy 19.277 -5.897)
        (xy 19.287 -5.918)
        (xy 19.298 -5.937)
        (xy 19.312 -5.958)
        (xy 19.324 -5.977)
        (xy 19.338 -5.996)
        (xy 19.353 -6.012)
        (xy 19.37 -6.03)
        (xy 19.387 -6.046)
        (xy 19.403 -6.06)
        (xy 19.422 -6.075)
        (xy 19.441 -6.087)
        (xy 19.461 -6.1)
        (xy 19.481 -6.111)
        (xy 19.502 -6.121)
        (xy 19.524 -6.131)
        (xy 19.547 -6.137)
        (xy 19.568 -6.144)
        (xy 19.591 -6.15)
        (xy 19.614 -6.155)
        (xy 19.637 -6.158)
        (xy 19.661 -6.158)
        (xy 19.684 -6.16)
        (xy 19.707 -6.158)
        (xy 19.731 -6.158)
        (xy 19.754 -6.155)
        (xy 19.777 -6.15)
        (xy 19.8 -6.144)
        (xy 19.822 -6.137)
        (xy 19.844 -6.129)
        (xy 19.865 -6.121)
        (xy 19.887 -6.11)
        (xy 19.906 -6.099)
        (xy 19.926 -6.087)
        (xy 19.946 -6.075)
        (xy 19.964 -6.06)
        (xy 19.983 -6.046)
        (xy 19.999 -6.03)
        (xy 20.015 -6.012)
        (xy 20.03 -5.994)
        (xy 20.045 -5.977)
        (xy 20.057 -5.956)
        (xy 20.069 -5.937)
        (xy 20.08 -5.916)
        (xy 20.091 -5.895)
        (xy 20.1 -5.873)
        (xy 20.108 -5.852)
        (xy 20.114 -5.829)
        (xy 20.12 -5.807)
        (xy 20.124 -5.785)
        (xy 20.127 -5.761)
        (xy 20.129 -5.738)
        (xy 20.129 -5.714)
        (xy 20.129 -5.692)
        (xy 20.127 -5.668)
        (xy 20.124 -5.644)
        (xy 20.12 -5.621)
        (xy 20.114 -5.599)
        (xy 20.108 -5.576)
        (xy 20.1 -5.555)
        (xy 20.091 -5.533)
        (xy 20.08 -5.512)
        (xy 20.069 -5.491)
        (xy 20.057 -5.472)
        (xy 20.045 -5.453)
        (xy 20.03 -5.434)
        (xy 20.015 -5.416)
        (xy 19.999 -5.4)
        (xy 19.983 -5.384)
        (xy 19.964 -5.368)
        (xy 19.946 -5.355)
        (xy 19.926 -5.341)
        (xy 19.906 -5.329)
        (xy 19.887 -5.318)
        (xy 19.865 -5.307)
        (xy 19.844 -5.299)
        (xy 19.822 -5.291)
        (xy 19.8 -5.285)
        (xy 19.777 -5.28)
        (xy 19.754 -5.275)
        (xy 19.731 -5.272)
        (xy 19.707 -5.27)
        (xy 19.684 -5.269)
        (xy 19.661 -5.27)
        (xy 19.637 -5.272)
        (xy 19.614 -5.275)
        (xy 19.591 -5.28)
        (xy 19.568 -5.285)
        (xy 19.547 -5.291)
        (xy 19.524 -5.299)
        (xy 19.502 -5.307)
        (xy 19.481 -5.317)
        (xy 19.461 -5.328)
        (xy 19.441 -5.341)
        (xy 19.422 -5.355)
        (xy 19.403 -5.368)
        (xy 19.387 -5.384)
        (xy 19.37 -5.4)
        (xy 19.353 -5.416)
        (xy 19.338 -5.434)
        (xy 19.324 -5.453)
        (xy 19.312 -5.472)
        (xy 19.298 -5.491)
        (xy 19.287 -5.511)
        (xy 19.277 -5.533)
        (xy 19.268 -5.554)
        (xy 19.262 -5.576)
        (xy 19.254 -5.599)
        (xy 19.249 -5.621)
        (xy 19.245 -5.644)
        (xy 19.242 -5.666)
        (xy 19.24 -5.69)
        (xy 19.239 -5.712)
        (xy 19.684 -5.712)
        (xy 19.684 -5.717)
      )

      (stroke (width 0.001) (type solid)) (fill solid) (layer "B.Paste"))
    (fp_poly
      (pts
        (xy 19.684 -3.177)
        (xy 19.239 -3.177)
        (xy 19.24 -3.198)
        (xy 19.242 -3.222)
        (xy 19.245 -3.245)
        (xy 19.249 -3.269)
        (xy 19.254 -3.29)
        (xy 19.262 -3.313)
        (xy 19.268 -3.334)
        (xy 19.277 -3.357)
        (xy 19.287 -3.378)
        (xy 19.298 -3.398)
        (xy 19.312 -3.418)
        (xy 19.324 -3.436)
        (xy 19.338 -3.455)
        (xy 19.353 -3.472)
        (xy 19.37 -3.49)
        (xy 19.387 -3.505)
        (xy 19.403 -3.52)
        (xy 19.422 -3.535)
        (xy 19.441 -3.547)
        (xy 19.461 -3.56)
        (xy 19.481 -3.571)
        (xy 19.502 -3.581)
        (xy 19.524 -3.591)
        (xy 19.547 -3.597)
        (xy 19.568 -3.604)
        (xy 19.591 -3.609)
        (xy 19.614 -3.615)
        (xy 19.637 -3.617)
        (xy 19.661 -3.619)
        (xy 19.684 -3.62)
        (xy 19.707 -3.619)
        (xy 19.731 -3.617)
        (xy 19.754 -3.615)
        (xy 19.777 -3.609)
        (xy 19.8 -3.604)
        (xy 19.822 -3.597)
        (xy 19.844 -3.589)
        (xy 19.865 -3.581)
        (xy 19.887 -3.571)
        (xy 19.906 -3.559)
        (xy 19.926 -3.547)
        (xy 19.946 -3.535)
        (xy 19.964 -3.52)
        (xy 19.983 -3.505)
        (xy 19.999 -3.49)
        (xy 20.015 -3.472)
        (xy 20.03 -3.454)
        (xy 20.045 -3.436)
        (xy 20.057 -3.416)
        (xy 20.069 -3.396)
        (xy 20.08 -3.376)
        (xy 20.091 -3.355)
        (xy 20.1 -3.334)
        (xy 20.108 -3.313)
        (xy 20.114 -3.289)
        (xy 20.12 -3.267)
        (xy 20.124 -3.245)
        (xy 20.127 -3.221)
        (xy 20.129 -3.197)
        (xy 20.129 -3.174)
        (xy 20.129 -3.152)
        (xy 20.127 -3.128)
        (xy 20.124 -3.104)
        (xy 20.12 -3.081)
        (xy 20.114 -3.059)
        (xy 20.108 -3.036)
        (xy 20.1 -3.015)
        (xy 20.091 -2.994)
        (xy 20.08 -2.972)
        (xy 20.069 -2.951)
        (xy 20.057 -2.932)
        (xy 20.045 -2.912)
        (xy 20.03 -2.894)
        (xy 20.015 -2.876)
        (xy 19.999 -2.859)
        (xy 19.983 -2.843)
        (xy 19.964 -2.829)
        (xy 19.946 -2.814)
        (xy 19.926 -2.801)
        (xy 19.906 -2.789)
        (xy 19.887 -2.778)
        (xy 19.865 -2.767)
        (xy 19.844 -2.759)
        (xy 19.822 -2.751)
        (xy 19.8 -2.745)
        (xy 19.777 -2.74)
        (xy 19.754 -2.734)
        (xy 19.731 -2.732)
        (xy 19.707 -2.73)
        (xy 19.684 -2.729)
        (xy 19.661 -2.73)
        (xy 19.637 -2.732)
        (xy 19.614 -2.734)
        (xy 19.591 -2.74)
        (xy 19.568 -2.745)
        (xy 19.547 -2.751)
        (xy 19.524 -2.758)
        (xy 19.502 -2.767)
        (xy 19.481 -2.777)
        (xy 19.461 -2.789)
        (xy 19.441 -2.801)
        (xy 19.422 -2.814)
        (xy 19.403 -2.829)
        (xy 19.387 -2.843)
        (xy 19.37 -2.859)
        (xy 19.353 -2.876)
        (xy 19.338 -2.894)
        (xy 19.324 -2.912)
        (xy 19.312 -2.931)
        (xy 19.298 -2.951)
        (xy 19.287 -2.971)
        (xy 19.277 -2.992)
        (xy 19.268 -3.015)
        (xy 19.262 -3.036)
        (xy 19.254 -3.059)
        (xy 19.249 -3.08)
        (xy 19.245 -3.104)
        (xy 19.242 -3.126)
        (xy 19.24 -3.15)
        (xy 19.239 -3.172)
        (xy 19.684 -3.172)
        (xy 19.684 -3.177)
      )

      (stroke (width 0.001) (type solid)) (fill solid) (layer "B.Paste"))
    (fp_poly
      (pts
        (xy 19.684 1.903)
        (xy 19.239 1.903)
        (xy 19.24 1.881)
        (xy 19.242 1.857)
        (xy 19.245 1.835)
        (xy 19.249 1.811)
        (xy 19.254 1.789)
        (xy 19.262 1.767)
        (xy 19.268 1.746)
        (xy 19.277 1.724)
        (xy 19.287 1.702)
        (xy 19.298 1.682)
        (xy 19.312 1.662)
        (xy 19.324 1.643)
        (xy 19.338 1.625)
        (xy 19.353 1.607)
        (xy 19.37 1.591)
        (xy 19.387 1.575)
        (xy 19.403 1.559)
        (xy 19.422 1.545)
        (xy 19.441 1.532)
        (xy 19.461 1.519)
        (xy 19.481 1.508)
        (xy 19.502 1.498)
        (xy 19.524 1.49)
        (xy 19.547 1.482)
        (xy 19.568 1.476)
        (xy 19.591 1.47)
        (xy 19.614 1.466)
        (xy 19.637 1.462)
        (xy 19.661 1.462)
        (xy 19.684 1.46)
        (xy 19.707 1.462)
        (xy 19.731 1.462)
        (xy 19.754 1.466)
        (xy 19.777 1.47)
        (xy 19.8 1.476)
        (xy 19.822 1.482)
        (xy 19.844 1.49)
        (xy 19.865 1.498)
        (xy 19.887 1.509)
        (xy 19.906 1.52)
        (xy 19.926 1.532)
        (xy 19.946 1.545)
        (xy 19.964 1.559)
        (xy 19.983 1.575)
        (xy 19.999 1.591)
        (xy 20.015 1.607)
        (xy 20.03 1.625)
        (xy 20.045 1.643)
        (xy 20.057 1.663)
        (xy 20.069 1.684)
        (xy 20.08 1.704)
        (xy 20.091 1.724)
        (xy 20.1 1.746)
        (xy 20.108 1.767)
        (xy 20.114 1.79)
        (xy 20.12 1.813)
        (xy 20.124 1.835)
        (xy 20.127 1.859)
        (xy 20.129 1.882)
        (xy 20.129 1.905)
        (xy 20.129 1.928)
        (xy 20.127 1.952)
        (xy 20.124 1.976)
        (xy 20.12 1.998)
        (xy 20.114 2.02)
        (xy 20.108 2.044)
        (xy 20.1 2.065)
        (xy 20.091 2.086)
        (xy 20.08 2.108)
        (xy 20.069 2.127)
        (xy 20.057 2.147)
        (xy 20.045 2.167)
        (xy 20.03 2.186)
        (xy 20.015 2.203)
        (xy 19.999 2.221)
        (xy 19.983 2.237)
        (xy 19.964 2.251)
        (xy 19.946 2.266)
        (xy 19.926 2.278)
        (xy 19.906 2.29)
        (xy 19.887 2.302)
        (xy 19.865 2.312)
        (xy 19.844 2.32)
        (xy 19.822 2.328)
        (xy 19.8 2.335)
        (xy 19.777 2.34)
        (xy 19.754 2.346)
        (xy 19.731 2.348)
        (xy 19.707 2.35)
        (xy 19.684 2.351)
        (xy 19.661 2.35)
        (xy 19.637 2.348)
        (xy 19.614 2.346)
        (xy 19.591 2.34)
        (xy 19.568 2.335)
        (xy 19.547 2.328)
        (xy 19.524 2.322)
        (xy 19.502 2.312)
        (xy 19.481 2.302)
        (xy 19.461 2.291)
        (xy 19.441 2.278)
        (xy 19.422 2.266)
        (xy 19.403 2.251)
        (xy 19.387 2.237)
        (xy 19.37 2.221)
        (xy 19.353 2.203)
        (xy 19.338 2.186)
        (xy 19.324 2.167)
        (xy 19.312 2.149)
        (xy 19.298 2.129)
        (xy 19.287 2.109)
        (xy 19.277 2.088)
        (xy 19.268 2.065)
        (xy 19.262 2.044)
        (xy 19.254 2.021)
        (xy 19.249 2)
        (xy 19.245 1.976)
        (xy 19.242 1.954)
        (xy 19.24 1.93)
        (xy 19.239 1.907)
        (xy 19.684 1.907)
        (xy 19.684 1.903)
      )

      (stroke (width 0.001) (type solid)) (fill solid) (layer "B.Paste"))
    (fp_poly
      (pts
        (xy 19.684 3.173)
        (xy 19.239 3.173)
        (xy 19.24 3.151)
        (xy 19.242 3.127)
        (xy 19.245 3.105)
        (xy 19.249 3.081)
        (xy 19.254 3.06)
        (xy 19.262 3.037)
        (xy 19.268 3.016)
        (xy 19.277 2.993)
        (xy 19.287 2.972)
        (xy 19.298 2.952)
        (xy 19.312 2.932)
        (xy 19.324 2.913)
        (xy 19.338 2.895)
        (xy 19.353 2.877)
        (xy 19.37 2.86)
        (xy 19.387 2.844)
        (xy 19.403 2.83)
        (xy 19.422 2.815)
        (xy 19.441 2.802)
        (xy 19.461 2.79)
        (xy 19.481 2.778)
        (xy 19.502 2.768)
        (xy 19.524 2.759)
        (xy 19.547 2.752)
        (xy 19.568 2.746)
        (xy 19.591 2.741)
        (xy 19.614 2.735)
        (xy 19.637 2.733)
        (xy 19.661 2.731)
        (xy 19.684 2.73)
        (xy 19.707 2.731)
        (xy 19.731 2.733)
        (xy 19.754 2.735)
        (xy 19.777 2.741)
        (xy 19.8 2.746)
        (xy 19.822 2.752)
        (xy 19.844 2.76)
        (xy 19.865 2.768)
        (xy 19.887 2.779)
        (xy 19.906 2.79)
        (xy 19.926 2.802)
        (xy 19.946 2.815)
        (xy 19.964 2.83)
        (xy 19.983 2.844)
        (xy 19.999 2.86)
        (xy 20.015 2.877)
        (xy 20.03 2.895)
        (xy 20.045 2.913)
        (xy 20.057 2.933)
        (xy 20.069 2.952)
        (xy 20.08 2.973)
        (xy 20.091 2.995)
        (xy 20.1 3.016)
        (xy 20.108 3.037)
        (xy 20.114 3.06)
        (xy 20.12 3.082)
        (xy 20.124 3.105)
        (xy 20.127 3.129)
        (xy 20.129 3.153)
        (xy 20.129 3.175)
        (xy 20.129 3.198)
        (xy 20.127 3.222)
        (xy 20.124 3.246)
        (xy 20.12 3.268)
        (xy 20.114 3.29)
        (xy 20.108 3.314)
        (xy 20.1 3.335)
        (xy 20.091 3.356)
        (xy 20.08 3.377)
        (xy 20.069 3.397)
        (xy 20.057 3.417)
        (xy 20.045 3.437)
        (xy 20.03 3.455)
        (xy 20.015 3.473)
        (xy 19.999 3.491)
        (xy 19.983 3.506)
        (xy 19.964 3.521)
        (xy 19.946 3.536)
        (xy 19.926 3.548)
        (xy 19.906 3.56)
        (xy 19.887 3.572)
        (xy 19.865 3.582)
        (xy 19.844 3.59)
        (xy 19.822 3.598)
        (xy 19.8 3.605)
        (xy 19.777 3.61)
        (xy 19.754 3.616)
        (xy 19.731 3.618)
        (xy 19.707 3.62)
        (xy 19.684 3.621)
        (xy 19.661 3.62)
        (xy 19.637 3.618)
        (xy 19.614 3.616)
        (xy 19.591 3.61)
        (xy 19.568 3.605)
        (xy 19.547 3.598)
        (xy 19.524 3.592)
        (xy 19.502 3.582)
        (xy 19.481 3.572)
        (xy 19.461 3.561)
        (xy 19.441 3.548)
        (xy 19.422 3.536)
        (xy 19.403 3.521)
        (xy 19.387 3.506)
        (xy 19.37 3.491)
        (xy 19.353 3.473)
        (xy 19.338 3.456)
        (xy 19.324 3.437)
        (xy 19.312 3.419)
        (xy 19.298 3.399)
        (xy 19.287 3.379)
        (xy 19.277 3.358)
        (xy 19.268 3.335)
        (xy 19.262 3.314)
        (xy 19.254 3.291)
        (xy 19.249 3.27)
        (xy 19.245 3.246)
        (xy 19.242 3.223)
        (xy 19.24 3.199)
        (xy 19.239 3.178)
        (xy 19.684 3.178)
        (xy 19.684 3.173)
      )

      (stroke (width 0.001) (type solid)) (fill solid) (layer "B.Paste"))
    (fp_poly
      (pts
        (xy 19.684 4.443)
        (xy 19.239 4.443)
        (xy 19.24 4.422)
        (xy 19.242 4.398)
        (xy 19.245 4.374)
        (xy 19.249 4.351)
        (xy 19.254 4.329)
        (xy 19.262 4.308)
        (xy 19.268 4.286)
        (xy 19.277 4.263)
        (xy 19.287 4.242)
        (xy 19.298 4.223)
        (xy 19.312 4.202)
        (xy 19.324 4.183)
        (xy 19.338 4.164)
        (xy 19.353 4.148)
        (xy 19.37 4.13)
        (xy 19.387 4.114)
        (xy 19.403 4.1)
        (xy 19.422 4.085)
        (xy 19.441 4.072)
        (xy 19.461 4.06)
        (xy 19.481 4.048)
        (xy 19.502 4.039)
        (xy 19.524 4.029)
        (xy 19.547 4.023)
        (xy 19.568 4.015)
        (xy 19.591 4.01)
        (xy 19.614 4.005)
        (xy 19.637 4.002)
        (xy 19.661 4.002)
        (xy 19.684 4)
        (xy 19.707 4.002)
        (xy 19.731 4.002)
        (xy 19.754 4.005)
        (xy 19.777 4.01)
        (xy 19.8 4.015)
        (xy 19.822 4.023)
        (xy 19.844 4.031)
        (xy 19.865 4.039)
        (xy 19.887 4.05)
        (xy 19.906 4.06)
        (xy 19.926 4.072)
        (xy 19.946 4.085)
        (xy 19.964 4.1)
        (xy 19.983 4.114)
        (xy 19.999 4.13)
        (xy 20.015 4.148)
        (xy 20.03 4.165)
        (xy 20.045 4.183)
        (xy 20.057 4.204)
        (xy 20.069 4.223)
        (xy 20.08 4.244)
        (xy 20.091 4.265)
        (xy 20.1 4.286)
        (xy 20.108 4.308)
        (xy 20.114 4.33)
        (xy 20.12 4.353)
        (xy 20.124 4.375)
        (xy 20.127 4.398)
        (xy 20.129 4.422)
        (xy 20.129 4.446)
        (xy 20.129 4.468)
        (xy 20.127 4.492)
        (xy 20.124 4.515)
        (xy 20.12 4.539)
        (xy 20.114 4.56)
        (xy 20.108 4.584)
        (xy 20.1 4.604)
        (xy 20.091 4.627)
        (xy 20.08 4.648)
        (xy 20.069 4.669)
        (xy 20.057 4.688)
        (xy 20.045 4.707)
        (xy 20.03 4.725)
        (xy 20.015 4.744)
        (xy 19.999 4.76)
        (xy 19.983 4.776)
        (xy 19.964 4.792)
        (xy 19.946 4.805)
        (xy 19.926 4.818)
        (xy 19.906 4.83)
        (xy 19.887 4.842)
        (xy 19.865 4.853)
        (xy 19.844 4.861)
        (xy 19.822 4.869)
        (xy 19.8 4.875)
        (xy 19.777 4.88)
        (xy 19.754 4.885)
        (xy 19.731 4.888)
        (xy 19.707 4.89)
        (xy 19.684 4.89)
        (xy 19.661 4.89)
        (xy 19.637 4.888)
        (xy 19.614 4.885)
        (xy 19.591 4.88)
        (xy 19.568 4.875)
        (xy 19.547 4.869)
        (xy 19.524 4.861)
        (xy 19.502 4.853)
        (xy 19.481 4.842)
        (xy 19.461 4.832)
        (xy 19.441 4.818)
        (xy 19.422 4.805)
        (xy 19.403 4.792)
        (xy 19.387 4.776)
        (xy 19.37 4.76)
        (xy 19.353 4.744)
        (xy 19.338 4.726)
        (xy 19.324 4.707)
        (xy 19.312 4.688)
        (xy 19.298 4.669)
        (xy 19.287 4.648)
        (xy 19.277 4.627)
        (xy 19.268 4.606)
        (xy 19.262 4.584)
        (xy 19.254 4.561)
        (xy 19.249 4.539)
        (xy 19.245 4.516)
        (xy 19.242 4.494)
        (xy 19.24 4.47)
        (xy 19.239 4.447)
        (xy 19.684 4.447)
        (xy 19.684 4.443)
      )

      (stroke (width 0.001) (type solid)) (fill solid) (layer "B.Paste"))
    (fp_poly
      (pts
        (xy 19.684 5.713)
        (xy 19.239 5.713)
        (xy 19.24 5.691)
        (xy 19.242 5.667)
        (xy 19.245 5.645)
        (xy 19.249 5.622)
        (xy 19.254 5.6)
        (xy 19.262 5.577)
        (xy 19.268 5.555)
        (xy 19.277 5.534)
        (xy 19.287 5.512)
        (xy 19.298 5.492)
        (xy 19.312 5.473)
        (xy 19.324 5.454)
        (xy 19.338 5.435)
        (xy 19.353 5.417)
        (xy 19.37 5.401)
        (xy 19.387 5.385)
        (xy 19.403 5.369)
        (xy 19.422 5.356)
        (xy 19.441 5.342)
        (xy 19.461 5.329)
        (xy 19.481 5.318)
        (xy 19.502 5.308)
        (xy 19.524 5.3)
        (xy 19.547 5.292)
        (xy 19.568 5.286)
        (xy 19.591 5.281)
        (xy 19.614 5.276)
        (xy 19.637 5.273)
        (xy 19.661 5.271)
        (xy 19.684 5.27)
        (xy 19.707 5.271)
        (xy 19.731 5.273)
        (xy 19.754 5.276)
        (xy 19.777 5.281)
        (xy 19.8 5.286)
        (xy 19.822 5.292)
        (xy 19.844 5.3)
        (xy 19.865 5.308)
        (xy 19.887 5.319)
        (xy 19.906 5.33)
        (xy 19.926 5.342)
        (xy 19.946 5.356)
        (xy 19.964 5.369)
        (xy 19.983 5.385)
        (xy 19.999 5.401)
        (xy 20.015 5.417)
        (xy 20.03 5.435)
        (xy 20.045 5.454)
        (xy 20.057 5.473)
        (xy 20.069 5.492)
        (xy 20.08 5.513)
        (xy 20.091 5.534)
        (xy 20.1 5.556)
        (xy 20.108 5.577)
        (xy 20.114 5.6)
        (xy 20.12 5.622)
        (xy 20.124 5.645)
        (xy 20.127 5.669)
        (xy 20.129 5.693)
        (xy 20.129 5.715)
        (xy 20.129 5.739)
        (xy 20.127 5.762)
        (xy 20.124 5.786)
        (xy 20.12 5.808)
        (xy 20.114 5.83)
        (xy 20.108 5.853)
        (xy 20.1 5.874)
        (xy 20.091 5.896)
        (xy 20.08 5.917)
        (xy 20.069 5.938)
        (xy 20.057 5.957)
        (xy 20.045 5.978)
        (xy 20.03 5.995)
        (xy 20.015 6.013)
        (xy 19.999 6.031)
        (xy 19.983 6.047)
        (xy 19.964 6.061)
        (xy 19.946 6.076)
        (xy 19.926 6.088)
        (xy 19.906 6.1)
        (xy 19.887 6.111)
        (xy 19.865 6.122)
        (xy 19.844 6.13)
        (xy 19.822 6.138)
        (xy 19.8 6.145)
        (xy 19.777 6.151)
        (xy 19.754 6.156)
        (xy 19.731 6.159)
        (xy 19.707 6.159)
        (xy 19.684 6.161)
        (xy 19.661 6.159)
        (xy 19.637 6.159)
        (xy 19.614 6.156)
        (xy 19.591 6.151)
        (xy 19.568 6.145)
        (xy 19.547 6.138)
        (xy 19.524 6.132)
        (xy 19.502 6.122)
        (xy 19.481 6.112)
        (xy 19.461 6.101)
        (xy 19.441 6.088)
        (xy 19.422 6.076)
        (xy 19.403 6.061)
        (xy 19.387 6.047)
        (xy 19.37 6.031)
        (xy 19.353 6.013)
        (xy 19.338 5.997)
        (xy 19.324 5.978)
        (xy 19.312 5.959)
        (xy 19.298 5.938)
        (xy 19.287 5.919)
        (xy 19.277 5.898)
        (xy 19.268 5.875)
        (xy 19.262 5.853)
        (xy 19.254 5.832)
        (xy 19.249 5.81)
        (xy 19.245 5.786)
        (xy 19.242 5.763)
        (xy 19.24 5.739)
        (xy 19.239 5.718)
        (xy 19.684 5.718)
        (xy 19.684 5.713)
      )

      (stroke (width 0.001) (type solid)) (fill solid) (layer "B.Paste"))
    (fp_poly
      (pts
        (xy 20.954 -5.717)
        (xy 20.51 -5.717)
        (xy 20.51 -5.738)
        (xy 20.512 -5.762)
        (xy 20.515 -5.785)
        (xy 20.519 -5.809)
        (xy 20.524 -5.831)
        (xy 20.531 -5.852)
        (xy 20.539 -5.874)
        (xy 20.547 -5.897)
        (xy 20.557 -5.918)
        (xy 20.568 -5.937)
        (xy 20.582 -5.958)
        (xy 20.594 -5.977)
        (xy 20.609 -5.996)
        (xy 20.623 -6.012)
        (xy 20.64 -6.03)
        (xy 20.656 -6.046)
        (xy 20.673 -6.06)
        (xy 20.693 -6.075)
        (xy 20.711 -6.087)
        (xy 20.731 -6.1)
        (xy 20.751 -6.111)
        (xy 20.772 -6.121)
        (xy 20.795 -6.131)
        (xy 20.816 -6.137)
        (xy 20.838 -6.144)
        (xy 20.861 -6.15)
        (xy 20.883 -6.155)
        (xy 20.906 -6.158)
        (xy 20.931 -6.158)
        (xy 20.954 -6.16)
        (xy 20.978 -6.158)
        (xy 21.001 -6.158)
        (xy 21.024 -6.155)
        (xy 21.047 -6.15)
        (xy 21.069 -6.144)
        (xy 21.092 -6.137)
        (xy 21.114 -6.129)
        (xy 21.135 -6.121)
        (xy 21.156 -6.11)
        (xy 21.176 -6.099)
        (xy 21.196 -6.087)
        (xy 21.216 -6.075)
        (xy 21.234 -6.06)
        (xy 21.252 -6.046)
        (xy 21.269 -6.03)
        (xy 21.286 -6.012)
        (xy 21.3 -5.994)
        (xy 21.315 -5.977)
        (xy 21.327 -5.956)
        (xy 21.339 -5.937)
        (xy 21.35 -5.916)
        (xy 21.361 -5.895)
        (xy 21.37 -5.873)
        (xy 21.377 -5.852)
        (xy 21.385 -5.829)
        (xy 21.39 -5.807)
        (xy 21.394 -5.785)
        (xy 21.397 -5.761)
        (xy 21.399 -5.738)
        (xy 21.399 -5.714)
        (xy 21.399 -5.692)
        (xy 21.397 -5.668)
        (xy 21.394 -5.644)
        (xy 21.39 -5.621)
        (xy 21.385 -5.599)
        (xy 21.377 -5.576)
        (xy 21.37 -5.555)
        (xy 21.361 -5.533)
        (xy 21.35 -5.512)
        (xy 21.339 -5.491)
        (xy 21.327 -5.472)
        (xy 21.315 -5.453)
        (xy 21.3 -5.434)
        (xy 21.286 -5.416)
        (xy 21.269 -5.4)
        (xy 21.252 -5.384)
        (xy 21.234 -5.368)
        (xy 21.216 -5.355)
        (xy 21.196 -5.341)
        (xy 21.176 -5.329)
        (xy 21.156 -5.318)
        (xy 21.135 -5.307)
        (xy 21.114 -5.299)
        (xy 21.092 -5.291)
        (xy 21.069 -5.285)
        (xy 21.047 -5.28)
        (xy 21.024 -5.275)
        (xy 21.001 -5.272)
        (xy 20.978 -5.27)
        (xy 20.954 -5.269)
        (xy 20.931 -5.27)
        (xy 20.906 -5.272)
        (xy 20.883 -5.275)
        (xy 20.861 -5.28)
        (xy 20.838 -5.285)
        (xy 20.816 -5.291)
        (xy 20.795 -5.299)
        (xy 20.772 -5.307)
        (xy 20.751 -5.317)
        (xy 20.731 -5.328)
        (xy 20.711 -5.341)
        (xy 20.693 -5.355)
        (xy 20.673 -5.368)
        (xy 20.656 -5.384)
        (xy 20.64 -5.4)
        (xy 20.623 -5.416)
        (xy 20.609 -5.434)
        (xy 20.594 -5.453)
        (xy 20.582 -5.472)
        (xy 20.568 -5.491)
        (xy 20.557 -5.511)
        (xy 20.547 -5.533)
        (xy 20.539 -5.554)
        (xy 20.531 -5.576)
        (xy 20.524 -5.599)
        (xy 20.519 -5.621)
        (xy 20.515 -5.644)
        (xy 20.512 -5.666)
        (xy 20.51 -5.69)
        (xy 20.51 -5.712)
        (xy 20.954 -5.712)
        (xy 20.954 -5.717)
      )

      (stroke (width 0.001) (type solid)) (fill solid) (layer "B.Paste"))
    (fp_poly
      (pts
        (xy 20.954 -3.177)
        (xy 20.51 -3.177)
        (xy 20.51 -3.198)
        (xy 20.512 -3.222)
        (xy 20.515 -3.245)
        (xy 20.519 -3.269)
        (xy 20.524 -3.29)
        (xy 20.531 -3.313)
        (xy 20.539 -3.334)
        (xy 20.547 -3.357)
        (xy 20.557 -3.378)
        (xy 20.568 -3.398)
        (xy 20.582 -3.418)
        (xy 20.594 -3.436)
        (xy 20.609 -3.455)
        (xy 20.623 -3.472)
        (xy 20.64 -3.49)
        (xy 20.656 -3.505)
        (xy 20.673 -3.52)
        (xy 20.693 -3.535)
        (xy 20.711 -3.547)
        (xy 20.731 -3.56)
        (xy 20.751 -3.571)
        (xy 20.772 -3.581)
        (xy 20.795 -3.591)
        (xy 20.816 -3.597)
        (xy 20.838 -3.604)
        (xy 20.861 -3.609)
        (xy 20.883 -3.615)
        (xy 20.906 -3.617)
        (xy 20.931 -3.619)
        (xy 20.954 -3.62)
        (xy 20.978 -3.619)
        (xy 21.001 -3.617)
        (xy 21.024 -3.615)
        (xy 21.047 -3.609)
        (xy 21.069 -3.604)
        (xy 21.092 -3.597)
        (xy 21.114 -3.589)
        (xy 21.135 -3.581)
        (xy 21.156 -3.571)
        (xy 21.176 -3.559)
        (xy 21.196 -3.547)
        (xy 21.216 -3.535)
        (xy 21.234 -3.52)
        (xy 21.252 -3.505)
        (xy 21.269 -3.49)
        (xy 21.286 -3.472)
        (xy 21.3 -3.454)
        (xy 21.315 -3.436)
        (xy 21.327 -3.416)
        (xy 21.339 -3.396)
        (xy 21.35 -3.376)
        (xy 21.361 -3.355)
        (xy 21.37 -3.334)
        (xy 21.377 -3.313)
        (xy 21.385 -3.289)
        (xy 21.39 -3.267)
        (xy 21.394 -3.245)
        (xy 21.397 -3.221)
        (xy 21.399 -3.197)
        (xy 21.399 -3.174)
        (xy 21.399 -3.152)
        (xy 21.397 -3.128)
        (xy 21.394 -3.104)
        (xy 21.39 -3.081)
        (xy 21.385 -3.059)
        (xy 21.377 -3.036)
        (xy 21.37 -3.015)
        (xy 21.361 -2.994)
        (xy 21.35 -2.972)
        (xy 21.339 -2.951)
        (xy 21.327 -2.932)
        (xy 21.315 -2.912)
        (xy 21.3 -2.894)
        (xy 21.286 -2.876)
        (xy 21.269 -2.859)
        (xy 21.252 -2.843)
        (xy 21.234 -2.829)
        (xy 21.216 -2.814)
        (xy 21.196 -2.801)
        (xy 21.176 -2.789)
        (xy 21.156 -2.778)
        (xy 21.135 -2.767)
        (xy 21.114 -2.759)
        (xy 21.092 -2.751)
        (xy 21.069 -2.745)
        (xy 21.047 -2.74)
        (xy 21.024 -2.734)
        (xy 21.001 -2.732)
        (xy 20.978 -2.73)
        (xy 20.954 -2.729)
        (xy 20.931 -2.73)
        (xy 20.906 -2.732)
        (xy 20.883 -2.734)
        (xy 20.861 -2.74)
        (xy 20.838 -2.745)
        (xy 20.816 -2.751)
        (xy 20.795 -2.758)
        (xy 20.772 -2.767)
        (xy 20.751 -2.777)
        (xy 20.731 -2.789)
        (xy 20.711 -2.801)
        (xy 20.693 -2.814)
        (xy 20.673 -2.829)
        (xy 20.656 -2.843)
        (xy 20.64 -2.859)
        (xy 20.623 -2.876)
        (xy 20.609 -2.894)
        (xy 20.594 -2.912)
        (xy 20.582 -2.931)
        (xy 20.568 -2.951)
        (xy 20.557 -2.971)
        (xy 20.547 -2.992)
        (xy 20.539 -3.015)
        (xy 20.531 -3.036)
        (xy 20.524 -3.059)
        (xy 20.519 -3.08)
        (xy 20.515 -3.104)
        (xy 20.512 -3.126)
        (xy 20.51 -3.15)
        (xy 20.51 -3.172)
        (xy 20.954 -3.172)
        (xy 20.954 -3.177)
      )

      (stroke (width 0.001) (type solid)) (fill solid) (layer "B.Paste"))
    (fp_poly
      (pts
        (xy 20.954 1.903)
        (xy 20.51 1.903)
        (xy 20.51 1.881)
        (xy 20.512 1.857)
        (xy 20.515 1.835)
        (xy 20.519 1.811)
        (xy 20.524 1.789)
        (xy 20.531 1.767)
        (xy 20.539 1.746)
        (xy 20.547 1.724)
        (xy 20.557 1.702)
        (xy 20.568 1.682)
        (xy 20.582 1.662)
        (xy 20.594 1.643)
        (xy 20.609 1.625)
        (xy 20.623 1.607)
        (xy 20.64 1.591)
        (xy 20.656 1.575)
        (xy 20.673 1.559)
        (xy 20.693 1.545)
        (xy 20.711 1.532)
        (xy 20.731 1.519)
        (xy 20.751 1.508)
        (xy 20.772 1.498)
        (xy 20.795 1.49)
        (xy 20.816 1.482)
        (xy 20.838 1.476)
        (xy 20.861 1.47)
        (xy 20.883 1.466)
        (xy 20.906 1.462)
        (xy 20.931 1.462)
        (xy 20.954 1.46)
        (xy 20.978 1.462)
        (xy 21.001 1.462)
        (xy 21.024 1.466)
        (xy 21.047 1.47)
        (xy 21.069 1.476)
        (xy 21.092 1.482)
        (xy 21.114 1.49)
        (xy 21.135 1.498)
        (xy 21.156 1.509)
        (xy 21.176 1.52)
        (xy 21.196 1.532)
        (xy 21.216 1.545)
        (xy 21.234 1.559)
        (xy 21.252 1.575)
        (xy 21.269 1.591)
        (xy 21.286 1.607)
        (xy 21.3 1.625)
        (xy 21.315 1.643)
        (xy 21.327 1.663)
        (xy 21.339 1.684)
        (xy 21.35 1.704)
        (xy 21.361 1.724)
        (xy 21.37 1.746)
        (xy 21.377 1.767)
        (xy 21.385 1.79)
        (xy 21.39 1.813)
        (xy 21.394 1.835)
        (xy 21.397 1.859)
        (xy 21.399 1.882)
        (xy 21.399 1.905)
        (xy 21.399 1.928)
        (xy 21.397 1.952)
        (xy 21.394 1.976)
        (xy 21.39 1.998)
        (xy 21.385 2.02)
        (xy 21.377 2.044)
        (xy 21.37 2.065)
        (xy 21.361 2.086)
        (xy 21.35 2.108)
        (xy 21.339 2.127)
        (xy 21.327 2.147)
        (xy 21.315 2.167)
        (xy 21.3 2.186)
        (xy 21.286 2.203)
        (xy 21.269 2.221)
        (xy 21.252 2.237)
        (xy 21.234 2.251)
        (xy 21.216 2.266)
        (xy 21.196 2.278)
        (xy 21.176 2.29)
        (xy 21.156 2.302)
        (xy 21.135 2.312)
        (xy 21.114 2.32)
        (xy 21.092 2.328)
        (xy 21.069 2.335)
        (xy 21.047 2.34)
        (xy 21.024 2.346)
        (xy 21.001 2.348)
        (xy 20.978 2.35)
        (xy 20.954 2.351)
        (xy 20.931 2.35)
        (xy 20.906 2.348)
        (xy 20.883 2.346)
        (xy 20.861 2.34)
        (xy 20.838 2.335)
        (xy 20.816 2.328)
        (xy 20.795 2.322)
        (xy 20.772 2.312)
        (xy 20.751 2.302)
        (xy 20.731 2.291)
        (xy 20.711 2.278)
        (xy 20.693 2.266)
        (xy 20.673 2.251)
        (xy 20.656 2.237)
        (xy 20.64 2.221)
        (xy 20.623 2.203)
        (xy 20.609 2.186)
        (xy 20.594 2.167)
        (xy 20.582 2.149)
        (xy 20.568 2.129)
        (xy 20.557 2.109)
        (xy 20.547 2.088)
        (xy 20.539 2.065)
        (xy 20.531 2.044)
        (xy 20.524 2.021)
        (xy 20.519 2)
        (xy 20.515 1.976)
        (xy 20.512 1.954)
        (xy 20.51 1.93)
        (xy 20.51 1.907)
        (xy 20.954 1.907)
        (xy 20.954 1.903)
      )

      (stroke (width 0.001) (type solid)) (fill solid) (layer "B.Paste"))
    (fp_poly
      (pts
        (xy 20.954 3.173)
        (xy 20.51 3.173)
        (xy 20.51 3.151)
        (xy 20.512 3.127)
        (xy 20.515 3.105)
        (xy 20.519 3.081)
        (xy 20.524 3.06)
        (xy 20.531 3.037)
        (xy 20.539 3.016)
        (xy 20.547 2.993)
        (xy 20.557 2.972)
        (xy 20.568 2.952)
        (xy 20.582 2.932)
        (xy 20.594 2.913)
        (xy 20.609 2.895)
        (xy 20.623 2.877)
        (xy 20.64 2.86)
        (xy 20.656 2.844)
        (xy 20.673 2.83)
        (xy 20.693 2.815)
        (xy 20.711 2.802)
        (xy 20.731 2.79)
        (xy 20.751 2.778)
        (xy 20.772 2.768)
        (xy 20.795 2.759)
        (xy 20.816 2.752)
        (xy 20.838 2.746)
        (xy 20.861 2.741)
        (xy 20.883 2.735)
        (xy 20.906 2.733)
        (xy 20.931 2.731)
        (xy 20.954 2.73)
        (xy 20.978 2.731)
        (xy 21.001 2.733)
        (xy 21.024 2.735)
        (xy 21.047 2.741)
        (xy 21.069 2.746)
        (xy 21.092 2.752)
        (xy 21.114 2.76)
        (xy 21.135 2.768)
        (xy 21.156 2.779)
        (xy 21.176 2.79)
        (xy 21.196 2.802)
        (xy 21.216 2.815)
        (xy 21.234 2.83)
        (xy 21.252 2.844)
        (xy 21.269 2.86)
        (xy 21.286 2.877)
        (xy 21.3 2.895)
        (xy 21.315 2.913)
        (xy 21.327 2.933)
        (xy 21.339 2.952)
        (xy 21.35 2.973)
        (xy 21.361 2.995)
        (xy 21.37 3.016)
        (xy 21.377 3.037)
        (xy 21.385 3.06)
        (xy 21.39 3.082)
        (xy 21.394 3.105)
        (xy 21.397 3.129)
        (xy 21.399 3.153)
        (xy 21.399 3.175)
        (xy 21.399 3.198)
        (xy 21.397 3.222)
        (xy 21.394 3.246)
        (xy 21.39 3.268)
        (xy 21.385 3.29)
        (xy 21.377 3.314)
        (xy 21.37 3.335)
        (xy 21.361 3.356)
        (xy 21.35 3.377)
        (xy 21.339 3.397)
        (xy 21.327 3.417)
        (xy 21.315 3.437)
        (xy 21.3 3.455)
        (xy 21.286 3.473)
        (xy 21.269 3.491)
        (xy 21.252 3.506)
        (xy 21.234 3.521)
        (xy 21.216 3.536)
        (xy 21.196 3.548)
        (xy 21.176 3.56)
        (xy 21.156 3.572)
        (xy 21.135 3.582)
        (xy 21.114 3.59)
        (xy 21.092 3.598)
        (xy 21.069 3.605)
        (xy 21.047 3.61)
        (xy 21.024 3.616)
        (xy 21.001 3.618)
        (xy 20.978 3.62)
        (xy 20.954 3.621)
        (xy 20.931 3.62)
        (xy 20.906 3.618)
        (xy 20.883 3.616)
        (xy 20.861 3.61)
        (xy 20.838 3.605)
        (xy 20.816 3.598)
        (xy 20.795 3.592)
        (xy 20.772 3.582)
        (xy 20.751 3.572)
        (xy 20.731 3.561)
        (xy 20.711 3.548)
        (xy 20.693 3.536)
        (xy 20.673 3.521)
        (xy 20.656 3.506)
        (xy 20.64 3.491)
        (xy 20.623 3.473)
        (xy 20.609 3.456)
        (xy 20.594 3.437)
        (xy 20.582 3.419)
        (xy 20.568 3.399)
        (xy 20.557 3.379)
        (xy 20.547 3.358)
        (xy 20.539 3.335)
        (xy 20.531 3.314)
        (xy 20.524 3.291)
        (xy 20.519 3.27)
        (xy 20.515 3.246)
        (xy 20.512 3.223)
        (xy 20.51 3.199)
        (xy 20.51 3.178)
        (xy 20.954 3.178)
        (xy 20.954 3.173)
      )

      (stroke (width 0.001) (type solid)) (fill solid) (layer "B.Paste"))
    (fp_poly
      (pts
        (xy 20.954 4.443)
        (xy 20.51 4.443)
        (xy 20.51 4.422)
        (xy 20.512 4.398)
        (xy 20.515 4.374)
        (xy 20.519 4.351)
        (xy 20.524 4.329)
        (xy 20.531 4.308)
        (xy 20.539 4.286)
        (xy 20.547 4.263)
        (xy 20.557 4.242)
        (xy 20.568 4.223)
        (xy 20.582 4.202)
        (xy 20.594 4.183)
        (xy 20.609 4.164)
        (xy 20.623 4.148)
        (xy 20.64 4.13)
        (xy 20.656 4.114)
        (xy 20.673 4.1)
        (xy 20.693 4.085)
        (xy 20.711 4.072)
        (xy 20.731 4.06)
        (xy 20.751 4.048)
        (xy 20.772 4.039)
        (xy 20.795 4.029)
        (xy 20.816 4.023)
        (xy 20.838 4.015)
        (xy 20.861 4.01)
        (xy 20.883 4.005)
        (xy 20.906 4.002)
        (xy 20.931 4.002)
        (xy 20.954 4)
        (xy 20.978 4.002)
        (xy 21.001 4.002)
        (xy 21.024 4.005)
        (xy 21.047 4.01)
        (xy 21.069 4.015)
        (xy 21.092 4.023)
        (xy 21.114 4.031)
        (xy 21.135 4.039)
        (xy 21.156 4.05)
        (xy 21.176 4.06)
        (xy 21.196 4.072)
        (xy 21.216 4.085)
        (xy 21.234 4.1)
        (xy 21.252 4.114)
        (xy 21.269 4.13)
        (xy 21.286 4.148)
        (xy 21.3 4.165)
        (xy 21.315 4.183)
        (xy 21.327 4.204)
        (xy 21.339 4.223)
        (xy 21.35 4.244)
        (xy 21.361 4.265)
        (xy 21.37 4.286)
        (xy 21.377 4.308)
        (xy 21.385 4.33)
        (xy 21.39 4.353)
        (xy 21.394 4.375)
        (xy 21.397 4.398)
        (xy 21.399 4.422)
        (xy 21.399 4.446)
        (xy 21.399 4.468)
        (xy 21.397 4.492)
        (xy 21.394 4.515)
        (xy 21.39 4.539)
        (xy 21.385 4.56)
        (xy 21.377 4.584)
        (xy 21.37 4.604)
        (xy 21.361 4.627)
        (xy 21.35 4.648)
        (xy 21.339 4.669)
        (xy 21.327 4.688)
        (xy 21.315 4.707)
        (xy 21.3 4.725)
        (xy 21.286 4.744)
        (xy 21.269 4.76)
        (xy 21.252 4.776)
        (xy 21.234 4.792)
        (xy 21.216 4.805)
        (xy 21.196 4.818)
        (xy 21.176 4.83)
        (xy 21.156 4.842)
        (xy 21.135 4.853)
        (xy 21.114 4.861)
        (xy 21.092 4.869)
        (xy 21.069 4.875)
        (xy 21.047 4.88)
        (xy 21.024 4.885)
        (xy 21.001 4.888)
        (xy 20.978 4.89)
        (xy 20.954 4.89)
        (xy 20.931 4.89)
        (xy 20.906 4.888)
        (xy 20.883 4.885)
        (xy 20.861 4.88)
        (xy 20.838 4.875)
        (xy 20.816 4.869)
        (xy 20.795 4.861)
        (xy 20.772 4.853)
        (xy 20.751 4.842)
        (xy 20.731 4.832)
        (xy 20.711 4.818)
        (xy 20.693 4.805)
        (xy 20.673 4.792)
        (xy 20.656 4.776)
        (xy 20.64 4.76)
        (xy 20.623 4.744)
        (xy 20.609 4.726)
        (xy 20.594 4.707)
        (xy 20.582 4.688)
        (xy 20.568 4.669)
        (xy 20.557 4.648)
        (xy 20.547 4.627)
        (xy 20.539 4.606)
        (xy 20.531 4.584)
        (xy 20.524 4.561)
        (xy 20.519 4.539)
        (xy 20.515 4.516)
        (xy 20.512 4.494)
        (xy 20.51 4.47)
        (xy 20.51 4.447)
        (xy 20.954 4.447)
        (xy 20.954 4.443)
      )

      (stroke (width 0.001) (type solid)) (fill solid) (layer "B.Paste"))
    (fp_poly
      (pts
        (xy 20.954 5.713)
        (xy 20.51 5.713)
        (xy 20.51 5.691)
        (xy 20.512 5.667)
        (xy 20.515 5.645)
        (xy 20.519 5.622)
        (xy 20.524 5.6)
        (xy 20.531 5.577)
        (xy 20.539 5.555)
        (xy 20.547 5.534)
        (xy 20.557 5.512)
        (xy 20.568 5.492)
        (xy 20.582 5.473)
        (xy 20.594 5.454)
        (xy 20.609 5.435)
        (xy 20.623 5.417)
        (xy 20.64 5.401)
        (xy 20.656 5.385)
        (xy 20.673 5.369)
        (xy 20.693 5.356)
        (xy 20.711 5.342)
        (xy 20.731 5.329)
        (xy 20.751 5.318)
        (xy 20.772 5.308)
        (xy 20.795 5.3)
        (xy 20.816 5.292)
        (xy 20.838 5.286)
        (xy 20.861 5.281)
        (xy 20.883 5.276)
        (xy 20.906 5.273)
        (xy 20.931 5.271)
        (xy 20.954 5.27)
        (xy 20.978 5.271)
        (xy 21.001 5.273)
        (xy 21.024 5.276)
        (xy 21.047 5.281)
        (xy 21.069 5.286)
        (xy 21.092 5.292)
        (xy 21.114 5.3)
        (xy 21.135 5.308)
        (xy 21.156 5.319)
        (xy 21.176 5.33)
        (xy 21.196 5.342)
        (xy 21.216 5.356)
        (xy 21.234 5.369)
        (xy 21.252 5.385)
        (xy 21.269 5.401)
        (xy 21.286 5.417)
        (xy 21.3 5.435)
        (xy 21.315 5.454)
        (xy 21.327 5.473)
        (xy 21.339 5.492)
        (xy 21.35 5.513)
        (xy 21.361 5.534)
        (xy 21.37 5.556)
        (xy 21.377 5.577)
        (xy 21.385 5.6)
        (xy 21.39 5.622)
        (xy 21.394 5.645)
        (xy 21.397 5.669)
        (xy 21.399 5.693)
        (xy 21.399 5.715)
        (xy 21.399 5.739)
        (xy 21.397 5.762)
        (xy 21.394 5.786)
        (xy 21.39 5.808)
        (xy 21.385 5.83)
        (xy 21.377 5.853)
        (xy 21.37 5.874)
        (xy 21.361 5.896)
        (xy 21.35 5.917)
        (xy 21.339 5.938)
        (xy 21.327 5.957)
        (xy 21.315 5.978)
        (xy 21.3 5.995)
        (xy 21.286 6.013)
        (xy 21.269 6.031)
        (xy 21.252 6.047)
        (xy 21.234 6.061)
        (xy 21.216 6.076)
        (xy 21.196 6.088)
        (xy 21.176 6.1)
        (xy 21.156 6.111)
        (xy 21.135 6.122)
        (xy 21.114 6.13)
        (xy 21.092 6.138)
        (xy 21.069 6.145)
        (xy 21.047 6.151)
        (xy 21.024 6.156)
        (xy 21.001 6.159)
        (xy 20.978 6.159)
        (xy 20.954 6.161)
        (xy 20.931 6.159)
        (xy 20.906 6.159)
        (xy 20.883 6.156)
        (xy 20.861 6.151)
        (xy 20.838 6.145)
        (xy 20.816 6.138)
        (xy 20.795 6.132)
        (xy 20.772 6.122)
        (xy 20.751 6.112)
        (xy 20.731 6.101)
        (xy 20.711 6.088)
        (xy 20.693 6.076)
        (xy 20.673 6.061)
        (xy 20.656 6.047)
        (xy 20.64 6.031)
        (xy 20.623 6.013)
        (xy 20.609 5.997)
        (xy 20.594 5.978)
        (xy 20.582 5.959)
        (xy 20.568 5.938)
        (xy 20.557 5.919)
        (xy 20.547 5.898)
        (xy 20.539 5.875)
        (xy 20.531 5.853)
        (xy 20.524 5.832)
        (xy 20.519 5.81)
        (xy 20.515 5.786)
        (xy 20.512 5.763)
        (xy 20.51 5.739)
        (xy 20.51 5.718)
        (xy 20.954 5.718)
        (xy 20.954 5.713)
      )

      (stroke (width 0.001) (type solid)) (fill solid) (layer "B.Paste"))
    (fp_poly
      (pts
        (xy 22.225 -5.717)
        (xy 21.78 -5.717)
        (xy 21.78 -5.738)
        (xy 21.781 -5.762)
        (xy 21.784 -5.785)
        (xy 21.789 -5.809)
        (xy 21.795 -5.831)
        (xy 21.801 -5.852)
        (xy 21.809 -5.874)
        (xy 21.818 -5.897)
        (xy 21.827 -5.918)
        (xy 21.838 -5.937)
        (xy 21.851 -5.958)
        (xy 21.864 -5.977)
        (xy 21.879 -5.996)
        (xy 21.893 -6.012)
        (xy 21.909 -6.03)
        (xy 21.926 -6.046)
        (xy 21.943 -6.06)
        (xy 21.963 -6.075)
        (xy 21.981 -6.087)
        (xy 22.001 -6.1)
        (xy 22.021 -6.111)
        (xy 22.042 -6.121)
        (xy 22.065 -6.131)
        (xy 22.086 -6.137)
        (xy 22.109 -6.144)
        (xy 22.13 -6.15)
        (xy 22.153 -6.155)
        (xy 22.176 -6.158)
        (xy 22.201 -6.158)
        (xy 22.225 -6.16)
        (xy 22.248 -6.158)
        (xy 22.271 -6.158)
        (xy 22.295 -6.155)
        (xy 22.318 -6.15)
        (xy 22.339 -6.144)
        (xy 22.362 -6.137)
        (xy 22.383 -6.129)
        (xy 22.405 -6.121)
        (xy 22.426 -6.11)
        (xy 22.447 -6.099)
        (xy 22.466 -6.087)
        (xy 22.486 -6.075)
        (xy 22.504 -6.06)
        (xy 22.522 -6.046)
        (xy 22.539 -6.03)
        (xy 22.556 -6.012)
        (xy 22.571 -5.994)
        (xy 22.585 -5.977)
        (xy 22.597 -5.956)
        (xy 22.609 -5.937)
        (xy 22.62 -5.916)
        (xy 22.632 -5.895)
        (xy 22.64 -5.873)
        (xy 22.647 -5.852)
        (xy 22.655 -5.829)
        (xy 22.659 -5.807)
        (xy 22.664 -5.785)
        (xy 22.667 -5.761)
        (xy 22.669 -5.738)
        (xy 22.67 -5.714)
        (xy 22.669 -5.692)
        (xy 22.667 -5.668)
        (xy 22.664 -5.644)
        (xy 22.659 -5.621)
        (xy 22.655 -5.599)
        (xy 22.647 -5.576)
        (xy 22.64 -5.555)
        (xy 22.632 -5.533)
        (xy 22.62 -5.512)
        (xy 22.609 -5.491)
        (xy 22.597 -5.472)
        (xy 22.585 -5.453)
        (xy 22.571 -5.434)
        (xy 22.556 -5.416)
        (xy 22.539 -5.4)
        (xy 22.522 -5.384)
        (xy 22.504 -5.368)
        (xy 22.486 -5.355)
        (xy 22.466 -5.341)
        (xy 22.447 -5.329)
        (xy 22.426 -5.318)
        (xy 22.405 -5.307)
        (xy 22.383 -5.299)
        (xy 22.362 -5.291)
        (xy 22.339 -5.285)
        (xy 22.318 -5.28)
        (xy 22.295 -5.275)
        (xy 22.271 -5.272)
        (xy 22.248 -5.27)
        (xy 22.225 -5.269)
        (xy 22.201 -5.27)
        (xy 22.176 -5.272)
        (xy 22.153 -5.275)
        (xy 22.13 -5.28)
        (xy 22.109 -5.285)
        (xy 22.086 -5.291)
        (xy 22.065 -5.299)
        (xy 22.042 -5.307)
        (xy 22.021 -5.317)
        (xy 22.001 -5.328)
        (xy 21.981 -5.341)
        (xy 21.963 -5.355)
        (xy 21.943 -5.368)
        (xy 21.926 -5.384)
        (xy 21.909 -5.4)
        (xy 21.893 -5.416)
        (xy 21.879 -5.434)
        (xy 21.864 -5.453)
        (xy 21.851 -5.472)
        (xy 21.838 -5.491)
        (xy 21.827 -5.511)
        (xy 21.818 -5.533)
        (xy 21.809 -5.554)
        (xy 21.801 -5.576)
        (xy 21.795 -5.599)
        (xy 21.789 -5.621)
        (xy 21.784 -5.644)
        (xy 21.781 -5.666)
        (xy 21.78 -5.69)
        (xy 21.78 -5.712)
        (xy 22.225 -5.712)
        (xy 22.225 -5.717)
      )

      (stroke (width 0.001) (type solid)) (fill solid) (layer "B.Paste"))
    (fp_poly
      (pts
        (xy 22.225 -3.177)
        (xy 21.78 -3.177)
        (xy 21.78 -3.198)
        (xy 21.781 -3.222)
        (xy 21.784 -3.245)
        (xy 21.789 -3.269)
        (xy 21.795 -3.29)
        (xy 21.801 -3.313)
        (xy 21.809 -3.334)
        (xy 21.818 -3.357)
        (xy 21.827 -3.378)
        (xy 21.838 -3.398)
        (xy 21.851 -3.418)
        (xy 21.864 -3.436)
        (xy 21.879 -3.455)
        (xy 21.893 -3.472)
        (xy 21.909 -3.49)
        (xy 21.926 -3.505)
        (xy 21.943 -3.52)
        (xy 21.963 -3.535)
        (xy 21.981 -3.547)
        (xy 22.001 -3.56)
        (xy 22.021 -3.571)
        (xy 22.042 -3.581)
        (xy 22.065 -3.591)
        (xy 22.086 -3.597)
        (xy 22.109 -3.604)
        (xy 22.13 -3.609)
        (xy 22.153 -3.615)
        (xy 22.176 -3.617)
        (xy 22.201 -3.619)
        (xy 22.225 -3.62)
        (xy 22.248 -3.619)
        (xy 22.271 -3.617)
        (xy 22.295 -3.615)
        (xy 22.318 -3.609)
        (xy 22.339 -3.604)
        (xy 22.362 -3.597)
        (xy 22.383 -3.589)
        (xy 22.405 -3.581)
        (xy 22.426 -3.571)
        (xy 22.447 -3.559)
        (xy 22.466 -3.547)
        (xy 22.486 -3.535)
        (xy 22.504 -3.52)
        (xy 22.522 -3.505)
        (xy 22.539 -3.49)
        (xy 22.556 -3.472)
        (xy 22.571 -3.454)
        (xy 22.585 -3.436)
        (xy 22.597 -3.416)
        (xy 22.609 -3.396)
        (xy 22.62 -3.376)
        (xy 22.632 -3.355)
        (xy 22.64 -3.334)
        (xy 22.647 -3.313)
        (xy 22.655 -3.289)
        (xy 22.659 -3.267)
        (xy 22.664 -3.245)
        (xy 22.667 -3.221)
        (xy 22.669 -3.197)
        (xy 22.67 -3.174)
        (xy 22.669 -3.152)
        (xy 22.667 -3.128)
        (xy 22.664 -3.104)
        (xy 22.659 -3.081)
        (xy 22.655 -3.059)
        (xy 22.647 -3.036)
        (xy 22.64 -3.015)
        (xy 22.632 -2.994)
        (xy 22.62 -2.972)
        (xy 22.609 -2.951)
        (xy 22.597 -2.932)
        (xy 22.585 -2.912)
        (xy 22.571 -2.894)
        (xy 22.556 -2.876)
        (xy 22.539 -2.859)
        (xy 22.522 -2.843)
        (xy 22.504 -2.829)
        (xy 22.486 -2.814)
        (xy 22.466 -2.801)
        (xy 22.447 -2.789)
        (xy 22.426 -2.778)
        (xy 22.405 -2.767)
        (xy 22.383 -2.759)
        (xy 22.362 -2.751)
        (xy 22.339 -2.745)
        (xy 22.318 -2.74)
        (xy 22.295 -2.734)
        (xy 22.271 -2.732)
        (xy 22.248 -2.73)
        (xy 22.225 -2.729)
        (xy 22.201 -2.73)
        (xy 22.176 -2.732)
        (xy 22.153 -2.734)
        (xy 22.13 -2.74)
        (xy 22.109 -2.745)
        (xy 22.086 -2.751)
        (xy 22.065 -2.758)
        (xy 22.042 -2.767)
        (xy 22.021 -2.777)
        (xy 22.001 -2.789)
        (xy 21.981 -2.801)
        (xy 21.963 -2.814)
        (xy 21.943 -2.829)
        (xy 21.926 -2.843)
        (xy 21.909 -2.859)
        (xy 21.893 -2.876)
        (xy 21.879 -2.894)
        (xy 21.864 -2.912)
        (xy 21.851 -2.931)
        (xy 21.838 -2.951)
        (xy 21.827 -2.971)
        (xy 21.818 -2.992)
        (xy 21.809 -3.015)
        (xy 21.801 -3.036)
        (xy 21.795 -3.059)
        (xy 21.789 -3.08)
        (xy 21.784 -3.104)
        (xy 21.781 -3.126)
        (xy 21.78 -3.15)
        (xy 21.78 -3.172)
        (xy 22.225 -3.172)
        (xy 22.225 -3.177)
      )

      (stroke (width 0.001) (type solid)) (fill solid) (layer "B.Paste"))
    (fp_poly
      (pts
        (xy 22.225 1.903)
        (xy 21.78 1.903)
        (xy 21.78 1.881)
        (xy 21.781 1.857)
        (xy 21.784 1.835)
        (xy 21.789 1.811)
        (xy 21.795 1.789)
        (xy 21.801 1.767)
        (xy 21.809 1.746)
        (xy 21.818 1.724)
        (xy 21.827 1.702)
        (xy 21.838 1.682)
        (xy 21.851 1.662)
        (xy 21.864 1.643)
        (xy 21.879 1.625)
        (xy 21.893 1.607)
        (xy 21.909 1.591)
        (xy 21.926 1.575)
        (xy 21.943 1.559)
        (xy 21.963 1.545)
        (xy 21.981 1.532)
        (xy 22.001 1.519)
        (xy 22.021 1.508)
        (xy 22.042 1.498)
        (xy 22.065 1.49)
        (xy 22.086 1.482)
        (xy 22.109 1.476)
        (xy 22.13 1.47)
        (xy 22.153 1.466)
        (xy 22.176 1.462)
        (xy 22.201 1.462)
        (xy 22.225 1.46)
        (xy 22.248 1.462)
        (xy 22.271 1.462)
        (xy 22.295 1.466)
        (xy 22.318 1.47)
        (xy 22.339 1.476)
        (xy 22.362 1.482)
        (xy 22.383 1.49)
        (xy 22.405 1.498)
        (xy 22.426 1.509)
        (xy 22.447 1.52)
        (xy 22.466 1.532)
        (xy 22.486 1.545)
        (xy 22.504 1.559)
        (xy 22.522 1.575)
        (xy 22.539 1.591)
        (xy 22.556 1.607)
        (xy 22.571 1.625)
        (xy 22.585 1.643)
        (xy 22.597 1.663)
        (xy 22.609 1.684)
        (xy 22.62 1.704)
        (xy 22.632 1.724)
        (xy 22.64 1.746)
        (xy 22.647 1.767)
        (xy 22.655 1.79)
        (xy 22.659 1.813)
        (xy 22.664 1.835)
        (xy 22.667 1.859)
        (xy 22.669 1.882)
        (xy 22.67 1.905)
        (xy 22.669 1.928)
        (xy 22.667 1.952)
        (xy 22.664 1.976)
        (xy 22.659 1.998)
        (xy 22.655 2.02)
        (xy 22.647 2.044)
        (xy 22.64 2.065)
        (xy 22.632 2.086)
        (xy 22.62 2.108)
        (xy 22.609 2.127)
        (xy 22.597 2.147)
        (xy 22.585 2.167)
        (xy 22.571 2.186)
        (xy 22.556 2.203)
        (xy 22.539 2.221)
        (xy 22.522 2.237)
        (xy 22.504 2.251)
        (xy 22.486 2.266)
        (xy 22.466 2.278)
        (xy 22.447 2.29)
        (xy 22.426 2.302)
        (xy 22.405 2.312)
        (xy 22.383 2.32)
        (xy 22.362 2.328)
        (xy 22.339 2.335)
        (xy 22.318 2.34)
        (xy 22.295 2.346)
        (xy 22.271 2.348)
        (xy 22.248 2.35)
        (xy 22.225 2.351)
        (xy 22.201 2.35)
        (xy 22.176 2.348)
        (xy 22.153 2.346)
        (xy 22.13 2.34)
        (xy 22.109 2.335)
        (xy 22.086 2.328)
        (xy 22.065 2.322)
        (xy 22.042 2.312)
        (xy 22.021 2.302)
        (xy 22.001 2.291)
        (xy 21.981 2.278)
        (xy 21.963 2.266)
        (xy 21.943 2.251)
        (xy 21.926 2.237)
        (xy 21.909 2.221)
        (xy 21.893 2.203)
        (xy 21.879 2.186)
        (xy 21.864 2.167)
        (xy 21.851 2.149)
        (xy 21.838 2.129)
        (xy 21.827 2.109)
        (xy 21.818 2.088)
        (xy 21.809 2.065)
        (xy 21.801 2.044)
        (xy 21.795 2.021)
        (xy 21.789 2)
        (xy 21.784 1.976)
        (xy 21.781 1.954)
        (xy 21.78 1.93)
        (xy 21.78 1.907)
        (xy 22.225 1.907)
        (xy 22.225 1.903)
      )

      (stroke (width 0.001) (type solid)) (fill solid) (layer "B.Paste"))
    (fp_poly
      (pts
        (xy 22.225 3.173)
        (xy 21.78 3.173)
        (xy 21.78 3.151)
        (xy 21.781 3.127)
        (xy 21.784 3.105)
        (xy 21.789 3.081)
        (xy 21.795 3.06)
        (xy 21.801 3.037)
        (xy 21.809 3.016)
        (xy 21.818 2.993)
        (xy 21.827 2.972)
        (xy 21.838 2.952)
        (xy 21.851 2.932)
        (xy 21.864 2.913)
        (xy 21.879 2.895)
        (xy 21.893 2.877)
        (xy 21.909 2.86)
        (xy 21.926 2.844)
        (xy 21.943 2.83)
        (xy 21.963 2.815)
        (xy 21.981 2.802)
        (xy 22.001 2.79)
        (xy 22.021 2.778)
        (xy 22.042 2.768)
        (xy 22.065 2.759)
        (xy 22.086 2.752)
        (xy 22.109 2.746)
        (xy 22.13 2.741)
        (xy 22.153 2.735)
        (xy 22.176 2.733)
        (xy 22.201 2.731)
        (xy 22.225 2.73)
        (xy 22.248 2.731)
        (xy 22.271 2.733)
        (xy 22.295 2.735)
        (xy 22.318 2.741)
        (xy 22.339 2.746)
        (xy 22.362 2.752)
        (xy 22.383 2.76)
        (xy 22.405 2.768)
        (xy 22.426 2.779)
        (xy 22.447 2.79)
        (xy 22.466 2.802)
        (xy 22.486 2.815)
        (xy 22.504 2.83)
        (xy 22.522 2.844)
        (xy 22.539 2.86)
        (xy 22.556 2.877)
        (xy 22.571 2.895)
        (xy 22.585 2.913)
        (xy 22.597 2.933)
        (xy 22.609 2.952)
        (xy 22.62 2.973)
        (xy 22.632 2.995)
        (xy 22.64 3.016)
        (xy 22.647 3.037)
        (xy 22.655 3.06)
        (xy 22.659 3.082)
        (xy 22.664 3.105)
        (xy 22.667 3.129)
        (xy 22.669 3.153)
        (xy 22.67 3.175)
        (xy 22.669 3.198)
        (xy 22.667 3.222)
        (xy 22.664 3.246)
        (xy 22.659 3.268)
        (xy 22.655 3.29)
        (xy 22.647 3.314)
        (xy 22.64 3.335)
        (xy 22.632 3.356)
        (xy 22.62 3.377)
        (xy 22.609 3.397)
        (xy 22.597 3.417)
        (xy 22.585 3.437)
        (xy 22.571 3.455)
        (xy 22.556 3.473)
        (xy 22.539 3.491)
        (xy 22.522 3.506)
        (xy 22.504 3.521)
        (xy 22.486 3.536)
        (xy 22.466 3.548)
        (xy 22.447 3.56)
        (xy 22.426 3.572)
        (xy 22.405 3.582)
        (xy 22.383 3.59)
        (xy 22.362 3.598)
        (xy 22.339 3.605)
        (xy 22.318 3.61)
        (xy 22.295 3.616)
        (xy 22.271 3.618)
        (xy 22.248 3.62)
        (xy 22.225 3.621)
        (xy 22.201 3.62)
        (xy 22.176 3.618)
        (xy 22.153 3.616)
        (xy 22.13 3.61)
        (xy 22.109 3.605)
        (xy 22.086 3.598)
        (xy 22.065 3.592)
        (xy 22.042 3.582)
        (xy 22.021 3.572)
        (xy 22.001 3.561)
        (xy 21.981 3.548)
        (xy 21.963 3.536)
        (xy 21.943 3.521)
        (xy 21.926 3.506)
        (xy 21.909 3.491)
        (xy 21.893 3.473)
        (xy 21.879 3.456)
        (xy 21.864 3.437)
        (xy 21.851 3.419)
        (xy 21.838 3.399)
        (xy 21.827 3.379)
        (xy 21.818 3.358)
        (xy 21.809 3.335)
        (xy 21.801 3.314)
        (xy 21.795 3.291)
        (xy 21.789 3.27)
        (xy 21.784 3.246)
        (xy 21.781 3.223)
        (xy 21.78 3.199)
        (xy 21.78 3.178)
        (xy 22.225 3.178)
        (xy 22.225 3.173)
      )

      (stroke (width 0.001) (type solid)) (fill solid) (layer "B.Paste"))
    (fp_poly
      (pts
        (xy 22.225 4.443)
        (xy 21.78 4.443)
        (xy 21.78 4.422)
        (xy 21.781 4.398)
        (xy 21.784 4.374)
        (xy 21.789 4.351)
        (xy 21.795 4.329)
        (xy 21.801 4.308)
        (xy 21.809 4.286)
        (xy 21.818 4.263)
        (xy 21.827 4.242)
        (xy 21.838 4.223)
        (xy 21.851 4.202)
        (xy 21.864 4.183)
        (xy 21.879 4.164)
        (xy 21.893 4.148)
        (xy 21.909 4.13)
        (xy 21.926 4.114)
        (xy 21.943 4.1)
        (xy 21.963 4.085)
        (xy 21.981 4.072)
        (xy 22.001 4.06)
        (xy 22.021 4.048)
        (xy 22.042 4.039)
        (xy 22.065 4.029)
        (xy 22.086 4.023)
        (xy 22.109 4.015)
        (xy 22.13 4.01)
        (xy 22.153 4.005)
        (xy 22.176 4.002)
        (xy 22.201 4.002)
        (xy 22.225 4)
        (xy 22.248 4.002)
        (xy 22.271 4.002)
        (xy 22.295 4.005)
        (xy 22.318 4.01)
        (xy 22.339 4.015)
        (xy 22.362 4.023)
        (xy 22.383 4.031)
        (xy 22.405 4.039)
        (xy 22.426 4.05)
        (xy 22.447 4.06)
        (xy 22.466 4.072)
        (xy 22.486 4.085)
        (xy 22.504 4.1)
        (xy 22.522 4.114)
        (xy 22.539 4.13)
        (xy 22.556 4.148)
        (xy 22.571 4.165)
        (xy 22.585 4.183)
        (xy 22.597 4.204)
        (xy 22.609 4.223)
        (xy 22.62 4.244)
        (xy 22.632 4.265)
        (xy 22.64 4.286)
        (xy 22.647 4.308)
        (xy 22.655 4.33)
        (xy 22.659 4.353)
        (xy 22.664 4.375)
        (xy 22.667 4.398)
        (xy 22.669 4.422)
        (xy 22.67 4.446)
        (xy 22.669 4.468)
        (xy 22.667 4.492)
        (xy 22.664 4.515)
        (xy 22.659 4.539)
        (xy 22.655 4.56)
        (xy 22.647 4.584)
        (xy 22.64 4.604)
        (xy 22.632 4.627)
        (xy 22.62 4.648)
        (xy 22.609 4.669)
        (xy 22.597 4.688)
        (xy 22.585 4.707)
        (xy 22.571 4.725)
        (xy 22.556 4.744)
        (xy 22.539 4.76)
        (xy 22.522 4.776)
        (xy 22.504 4.792)
        (xy 22.486 4.805)
        (xy 22.466 4.818)
        (xy 22.447 4.83)
        (xy 22.426 4.842)
        (xy 22.405 4.853)
        (xy 22.383 4.861)
        (xy 22.362 4.869)
        (xy 22.339 4.875)
        (xy 22.318 4.88)
        (xy 22.295 4.885)
        (xy 22.271 4.888)
        (xy 22.248 4.89)
        (xy 22.225 4.89)
        (xy 22.201 4.89)
        (xy 22.176 4.888)
        (xy 22.153 4.885)
        (xy 22.13 4.88)
        (xy 22.109 4.875)
        (xy 22.086 4.869)
        (xy 22.065 4.861)
        (xy 22.042 4.853)
        (xy 22.021 4.842)
        (xy 22.001 4.832)
        (xy 21.981 4.818)
        (xy 21.963 4.805)
        (xy 21.943 4.792)
        (xy 21.926 4.776)
        (xy 21.909 4.76)
        (xy 21.893 4.744)
        (xy 21.879 4.726)
        (xy 21.864 4.707)
        (xy 21.851 4.688)
        (xy 21.838 4.669)
        (xy 21.827 4.648)
        (xy 21.818 4.627)
        (xy 21.809 4.606)
        (xy 21.801 4.584)
        (xy 21.795 4.561)
        (xy 21.789 4.539)
        (xy 21.784 4.516)
        (xy 21.781 4.494)
        (xy 21.78 4.47)
        (xy 21.78 4.447)
        (xy 22.225 4.447)
        (xy 22.225 4.443)
      )

      (stroke (width 0.001) (type solid)) (fill solid) (layer "B.Paste"))
    (fp_poly
      (pts
        (xy 22.225 5.713)
        (xy 21.78 5.713)
        (xy 21.78 5.691)
        (xy 21.781 5.667)
        (xy 21.784 5.645)
        (xy 21.789 5.622)
        (xy 21.795 5.6)
        (xy 21.801 5.577)
        (xy 21.809 5.555)
        (xy 21.818 5.534)
        (xy 21.827 5.512)
        (xy 21.838 5.492)
        (xy 21.851 5.473)
        (xy 21.864 5.454)
        (xy 21.879 5.435)
        (xy 21.893 5.417)
        (xy 21.909 5.401)
        (xy 21.926 5.385)
        (xy 21.943 5.369)
        (xy 21.963 5.356)
        (xy 21.981 5.342)
        (xy 22.001 5.329)
        (xy 22.021 5.318)
        (xy 22.042 5.308)
        (xy 22.065 5.3)
        (xy 22.086 5.292)
        (xy 22.109 5.286)
        (xy 22.13 5.281)
        (xy 22.153 5.276)
        (xy 22.176 5.273)
        (xy 22.201 5.271)
        (xy 22.225 5.27)
        (xy 22.248 5.271)
        (xy 22.271 5.273)
        (xy 22.295 5.276)
        (xy 22.318 5.281)
        (xy 22.339 5.286)
        (xy 22.362 5.292)
        (xy 22.383 5.3)
        (xy 22.405 5.308)
        (xy 22.426 5.319)
        (xy 22.447 5.33)
        (xy 22.466 5.342)
        (xy 22.486 5.356)
        (xy 22.504 5.369)
        (xy 22.522 5.385)
        (xy 22.539 5.401)
        (xy 22.556 5.417)
        (xy 22.571 5.435)
        (xy 22.585 5.454)
        (xy 22.597 5.473)
        (xy 22.609 5.492)
        (xy 22.62 5.513)
        (xy 22.632 5.534)
        (xy 22.64 5.556)
        (xy 22.647 5.577)
        (xy 22.655 5.6)
        (xy 22.659 5.622)
        (xy 22.664 5.645)
        (xy 22.667 5.669)
        (xy 22.669 5.693)
        (xy 22.67 5.715)
        (xy 22.669 5.739)
        (xy 22.667 5.762)
        (xy 22.664 5.786)
        (xy 22.659 5.808)
        (xy 22.655 5.83)
        (xy 22.647 5.853)
        (xy 22.64 5.874)
        (xy 22.632 5.896)
        (xy 22.62 5.917)
        (xy 22.609 5.938)
        (xy 22.597 5.957)
        (xy 22.585 5.978)
        (xy 22.571 5.995)
        (xy 22.556 6.013)
        (xy 22.539 6.031)
        (xy 22.522 6.047)
        (xy 22.504 6.061)
        (xy 22.486 6.076)
        (xy 22.466 6.088)
        (xy 22.447 6.1)
        (xy 22.426 6.111)
        (xy 22.405 6.122)
        (xy 22.383 6.13)
        (xy 22.362 6.138)
        (xy 22.339 6.145)
        (xy 22.318 6.151)
        (xy 22.295 6.156)
        (xy 22.271 6.159)
        (xy 22.248 6.159)
        (xy 22.225 6.161)
        (xy 22.201 6.159)
        (xy 22.176 6.159)
        (xy 22.153 6.156)
        (xy 22.13 6.151)
        (xy 22.109 6.145)
        (xy 22.086 6.138)
        (xy 22.065 6.132)
        (xy 22.042 6.122)
        (xy 22.021 6.112)
        (xy 22.001 6.101)
        (xy 21.981 6.088)
        (xy 21.963 6.076)
        (xy 21.943 6.061)
        (xy 21.926 6.047)
        (xy 21.909 6.031)
        (xy 21.893 6.013)
        (xy 21.879 5.997)
        (xy 21.864 5.978)
        (xy 21.851 5.959)
        (xy 21.838 5.938)
        (xy 21.827 5.919)
        (xy 21.818 5.898)
        (xy 21.809 5.875)
        (xy 21.801 5.853)
        (xy 21.795 5.832)
        (xy 21.789 5.81)
        (xy 21.784 5.786)
        (xy 21.781 5.763)
        (xy 21.78 5.739)
        (xy 21.78 5.718)
        (xy 22.225 5.718)
        (xy 22.225 5.713)
      )

      (stroke (width 0.001) (type solid)) (fill solid) (layer "B.Paste"))
    (fp_poly
      (pts
        (xy 23.495 -5.717)
        (xy 23.05 -5.717)
        (xy 23.05 -5.738)
        (xy 23.051 -5.762)
        (xy 23.054 -5.785)
        (xy 23.059 -5.809)
        (xy 23.065 -5.831)
        (xy 23.071 -5.852)
        (xy 23.079 -5.874)
        (xy 23.088 -5.897)
        (xy 23.097 -5.918)
        (xy 23.109 -5.937)
        (xy 23.121 -5.958)
        (xy 23.135 -5.977)
        (xy 23.149 -5.996)
        (xy 23.164 -6.012)
        (xy 23.179 -6.03)
        (xy 23.196 -6.046)
        (xy 23.213 -6.06)
        (xy 23.233 -6.075)
        (xy 23.251 -6.087)
        (xy 23.271 -6.1)
        (xy 23.292 -6.111)
        (xy 23.312 -6.121)
        (xy 23.335 -6.131)
        (xy 23.356 -6.137)
        (xy 23.379 -6.144)
        (xy 23.4 -6.15)
        (xy 23.423 -6.155)
        (xy 23.446 -6.158)
        (xy 23.47 -6.158)
        (xy 23.495 -6.16)
        (xy 23.518 -6.158)
        (xy 23.542 -6.158)
        (xy 23.565 -6.155)
        (xy 23.588 -6.15)
        (xy 23.609 -6.144)
        (xy 23.632 -6.137)
        (xy 23.653 -6.129)
        (xy 23.675 -6.121)
        (xy 23.696 -6.11)
        (xy 23.717 -6.099)
        (xy 23.736 -6.087)
        (xy 23.757 -6.075)
        (xy 23.774 -6.06)
        (xy 23.792 -6.046)
        (xy 23.809 -6.03)
        (xy 23.826 -6.012)
        (xy 23.841 -5.994)
        (xy 23.854 -5.977)
        (xy 23.867 -5.956)
        (xy 23.879 -5.937)
        (xy 23.89 -5.916)
        (xy 23.902 -5.895)
        (xy 23.909 -5.873)
        (xy 23.917 -5.852)
        (xy 23.925 -5.829)
        (xy 23.929 -5.807)
        (xy 23.934 -5.785)
        (xy 23.937 -5.761)
        (xy 23.938 -5.738)
        (xy 23.94 -5.714)
        (xy 23.938 -5.692)
        (xy 23.937 -5.668)
        (xy 23.934 -5.644)
        (xy 23.929 -5.621)
        (xy 23.925 -5.599)
        (xy 23.917 -5.576)
        (xy 23.909 -5.555)
        (xy 23.902 -5.533)
        (xy 23.89 -5.512)
        (xy 23.879 -5.491)
        (xy 23.867 -5.472)
        (xy 23.854 -5.453)
        (xy 23.841 -5.434)
        (xy 23.826 -5.416)
        (xy 23.809 -5.4)
        (xy 23.792 -5.384)
        (xy 23.774 -5.368)
        (xy 23.757 -5.355)
        (xy 23.736 -5.341)
        (xy 23.717 -5.329)
        (xy 23.696 -5.318)
        (xy 23.675 -5.307)
        (xy 23.653 -5.299)
        (xy 23.632 -5.291)
        (xy 23.609 -5.285)
        (xy 23.588 -5.28)
        (xy 23.565 -5.275)
        (xy 23.542 -5.272)
        (xy 23.518 -5.27)
        (xy 23.495 -5.269)
        (xy 23.47 -5.27)
        (xy 23.446 -5.272)
        (xy 23.423 -5.275)
        (xy 23.4 -5.28)
        (xy 23.379 -5.285)
        (xy 23.356 -5.291)
        (xy 23.335 -5.299)
        (xy 23.312 -5.307)
        (xy 23.292 -5.317)
        (xy 23.271 -5.328)
        (xy 23.251 -5.341)
        (xy 23.233 -5.355)
        (xy 23.213 -5.368)
        (xy 23.196 -5.384)
        (xy 23.179 -5.4)
        (xy 23.164 -5.416)
        (xy 23.149 -5.434)
        (xy 23.135 -5.453)
        (xy 23.121 -5.472)
        (xy 23.109 -5.491)
        (xy 23.097 -5.511)
        (xy 23.088 -5.533)
        (xy 23.079 -5.554)
        (xy 23.071 -5.576)
        (xy 23.065 -5.599)
        (xy 23.059 -5.621)
        (xy 23.054 -5.644)
        (xy 23.051 -5.666)
        (xy 23.05 -5.69)
        (xy 23.05 -5.712)
        (xy 23.495 -5.712)
        (xy 23.495 -5.717)
      )

      (stroke (width 0.001) (type solid)) (fill solid) (layer "B.Paste"))
    (fp_poly
      (pts
        (xy 23.495 -3.177)
        (xy 23.05 -3.177)
        (xy 23.05 -3.198)
        (xy 23.051 -3.222)
        (xy 23.054 -3.245)
        (xy 23.059 -3.269)
        (xy 23.065 -3.29)
        (xy 23.071 -3.313)
        (xy 23.079 -3.334)
        (xy 23.088 -3.357)
        (xy 23.097 -3.378)
        (xy 23.109 -3.398)
        (xy 23.121 -3.418)
        (xy 23.135 -3.436)
        (xy 23.149 -3.455)
        (xy 23.164 -3.472)
        (xy 23.179 -3.49)
        (xy 23.196 -3.505)
        (xy 23.213 -3.52)
        (xy 23.233 -3.535)
        (xy 23.251 -3.547)
        (xy 23.271 -3.56)
        (xy 23.292 -3.571)
        (xy 23.312 -3.581)
        (xy 23.335 -3.591)
        (xy 23.356 -3.597)
        (xy 23.379 -3.604)
        (xy 23.4 -3.609)
        (xy 23.423 -3.615)
        (xy 23.446 -3.617)
        (xy 23.47 -3.619)
        (xy 23.495 -3.62)
        (xy 23.518 -3.619)
        (xy 23.542 -3.617)
        (xy 23.565 -3.615)
        (xy 23.588 -3.609)
        (xy 23.609 -3.604)
        (xy 23.632 -3.597)
        (xy 23.653 -3.589)
        (xy 23.675 -3.581)
        (xy 23.696 -3.571)
        (xy 23.717 -3.559)
        (xy 23.736 -3.547)
        (xy 23.757 -3.535)
        (xy 23.774 -3.52)
        (xy 23.792 -3.505)
        (xy 23.809 -3.49)
        (xy 23.826 -3.472)
        (xy 23.841 -3.454)
        (xy 23.854 -3.436)
        (xy 23.867 -3.416)
        (xy 23.879 -3.396)
        (xy 23.89 -3.376)
        (xy 23.902 -3.355)
        (xy 23.909 -3.334)
        (xy 23.917 -3.313)
        (xy 23.925 -3.289)
        (xy 23.929 -3.267)
        (xy 23.934 -3.245)
        (xy 23.937 -3.221)
        (xy 23.938 -3.197)
        (xy 23.94 -3.174)
        (xy 23.938 -3.152)
        (xy 23.937 -3.128)
        (xy 23.934 -3.104)
        (xy 23.929 -3.081)
        (xy 23.925 -3.059)
        (xy 23.917 -3.036)
        (xy 23.909 -3.015)
        (xy 23.902 -2.994)
        (xy 23.89 -2.972)
        (xy 23.879 -2.951)
        (xy 23.867 -2.932)
        (xy 23.854 -2.912)
        (xy 23.841 -2.894)
        (xy 23.826 -2.876)
        (xy 23.809 -2.859)
        (xy 23.792 -2.843)
        (xy 23.774 -2.829)
        (xy 23.757 -2.814)
        (xy 23.736 -2.801)
        (xy 23.717 -2.789)
        (xy 23.696 -2.778)
        (xy 23.675 -2.767)
        (xy 23.653 -2.759)
        (xy 23.632 -2.751)
        (xy 23.609 -2.745)
        (xy 23.588 -2.74)
        (xy 23.565 -2.734)
        (xy 23.542 -2.732)
        (xy 23.518 -2.73)
        (xy 23.495 -2.729)
        (xy 23.47 -2.73)
        (xy 23.446 -2.732)
        (xy 23.423 -2.734)
        (xy 23.4 -2.74)
        (xy 23.379 -2.745)
        (xy 23.356 -2.751)
        (xy 23.335 -2.758)
        (xy 23.312 -2.767)
        (xy 23.292 -2.777)
        (xy 23.271 -2.789)
        (xy 23.251 -2.801)
        (xy 23.233 -2.814)
        (xy 23.213 -2.829)
        (xy 23.196 -2.843)
        (xy 23.179 -2.859)
        (xy 23.164 -2.876)
        (xy 23.149 -2.894)
        (xy 23.135 -2.912)
        (xy 23.121 -2.931)
        (xy 23.109 -2.951)
        (xy 23.097 -2.971)
        (xy 23.088 -2.992)
        (xy 23.079 -3.015)
        (xy 23.071 -3.036)
        (xy 23.065 -3.059)
        (xy 23.059 -3.08)
        (xy 23.054 -3.104)
        (xy 23.051 -3.126)
        (xy 23.05 -3.15)
        (xy 23.05 -3.172)
        (xy 23.495 -3.172)
        (xy 23.495 -3.177)
      )

      (stroke (width 0.001) (type solid)) (fill solid) (layer "B.Paste"))
    (fp_poly
      (pts
        (xy 23.495 1.903)
        (xy 23.05 1.903)
        (xy 23.05 1.881)
        (xy 23.051 1.857)
        (xy 23.054 1.835)
        (xy 23.059 1.811)
        (xy 23.065 1.789)
        (xy 23.071 1.767)
        (xy 23.079 1.746)
        (xy 23.088 1.724)
        (xy 23.097 1.702)
        (xy 23.109 1.682)
        (xy 23.121 1.662)
        (xy 23.135 1.643)
        (xy 23.149 1.625)
        (xy 23.164 1.607)
        (xy 23.179 1.591)
        (xy 23.196 1.575)
        (xy 23.213 1.559)
        (xy 23.233 1.545)
        (xy 23.251 1.532)
        (xy 23.271 1.519)
        (xy 23.292 1.508)
        (xy 23.312 1.498)
        (xy 23.335 1.49)
        (xy 23.356 1.482)
        (xy 23.379 1.476)
        (xy 23.4 1.47)
        (xy 23.423 1.466)
        (xy 23.446 1.462)
        (xy 23.47 1.462)
        (xy 23.495 1.46)
        (xy 23.518 1.462)
        (xy 23.542 1.462)
        (xy 23.565 1.466)
        (xy 23.588 1.47)
        (xy 23.609 1.476)
        (xy 23.632 1.482)
        (xy 23.653 1.49)
        (xy 23.675 1.498)
        (xy 23.696 1.509)
        (xy 23.717 1.52)
        (xy 23.736 1.532)
        (xy 23.757 1.545)
        (xy 23.774 1.559)
        (xy 23.792 1.575)
        (xy 23.809 1.591)
        (xy 23.826 1.607)
        (xy 23.841 1.625)
        (xy 23.854 1.643)
        (xy 23.867 1.663)
        (xy 23.879 1.684)
        (xy 23.89 1.704)
        (xy 23.902 1.724)
        (xy 23.909 1.746)
        (xy 23.917 1.767)
        (xy 23.925 1.79)
        (xy 23.929 1.813)
        (xy 23.934 1.835)
        (xy 23.937 1.859)
        (xy 23.938 1.882)
        (xy 23.94 1.905)
        (xy 23.938 1.928)
        (xy 23.937 1.952)
        (xy 23.934 1.976)
        (xy 23.929 1.998)
        (xy 23.925 2.02)
        (xy 23.917 2.044)
        (xy 23.909 2.065)
        (xy 23.902 2.086)
        (xy 23.89 2.108)
        (xy 23.879 2.127)
        (xy 23.867 2.147)
        (xy 23.854 2.167)
        (xy 23.841 2.186)
        (xy 23.826 2.203)
        (xy 23.809 2.221)
        (xy 23.792 2.237)
        (xy 23.774 2.251)
        (xy 23.757 2.266)
        (xy 23.736 2.278)
        (xy 23.717 2.29)
        (xy 23.696 2.302)
        (xy 23.675 2.312)
        (xy 23.653 2.32)
        (xy 23.632 2.328)
        (xy 23.609 2.335)
        (xy 23.588 2.34)
        (xy 23.565 2.346)
        (xy 23.542 2.348)
        (xy 23.518 2.35)
        (xy 23.495 2.351)
        (xy 23.47 2.35)
        (xy 23.446 2.348)
        (xy 23.423 2.346)
        (xy 23.4 2.34)
        (xy 23.379 2.335)
        (xy 23.356 2.328)
        (xy 23.335 2.322)
        (xy 23.312 2.312)
        (xy 23.292 2.302)
        (xy 23.271 2.291)
        (xy 23.251 2.278)
        (xy 23.233 2.266)
        (xy 23.213 2.251)
        (xy 23.196 2.237)
        (xy 23.179 2.221)
        (xy 23.164 2.203)
        (xy 23.149 2.186)
        (xy 23.135 2.167)
        (xy 23.121 2.149)
        (xy 23.109 2.129)
        (xy 23.097 2.109)
        (xy 23.088 2.088)
        (xy 23.079 2.065)
        (xy 23.071 2.044)
        (xy 23.065 2.021)
        (xy 23.059 2)
        (xy 23.054 1.976)
        (xy 23.051 1.954)
        (xy 23.05 1.93)
        (xy 23.05 1.907)
        (xy 23.495 1.907)
        (xy 23.495 1.903)
      )

      (stroke (width 0.001) (type solid)) (fill solid) (layer "B.Paste"))
    (fp_poly
      (pts
        (xy 23.495 3.173)
        (xy 23.05 3.173)
        (xy 23.05 3.151)
        (xy 23.051 3.127)
        (xy 23.054 3.105)
        (xy 23.059 3.081)
        (xy 23.065 3.06)
        (xy 23.071 3.037)
        (xy 23.079 3.016)
        (xy 23.088 2.993)
        (xy 23.097 2.972)
        (xy 23.109 2.952)
        (xy 23.121 2.932)
        (xy 23.135 2.913)
        (xy 23.149 2.895)
        (xy 23.164 2.877)
        (xy 23.179 2.86)
        (xy 23.196 2.844)
        (xy 23.213 2.83)
        (xy 23.233 2.815)
        (xy 23.251 2.802)
        (xy 23.271 2.79)
        (xy 23.292 2.778)
        (xy 23.312 2.768)
        (xy 23.335 2.759)
        (xy 23.356 2.752)
        (xy 23.379 2.746)
        (xy 23.4 2.741)
        (xy 23.423 2.735)
        (xy 23.446 2.733)
        (xy 23.47 2.731)
        (xy 23.495 2.73)
        (xy 23.518 2.731)
        (xy 23.542 2.733)
        (xy 23.565 2.735)
        (xy 23.588 2.741)
        (xy 23.609 2.746)
        (xy 23.632 2.752)
        (xy 23.653 2.76)
        (xy 23.675 2.768)
        (xy 23.696 2.779)
        (xy 23.717 2.79)
        (xy 23.736 2.802)
        (xy 23.757 2.815)
        (xy 23.774 2.83)
        (xy 23.792 2.844)
        (xy 23.809 2.86)
        (xy 23.826 2.877)
        (xy 23.841 2.895)
        (xy 23.854 2.913)
        (xy 23.867 2.933)
        (xy 23.879 2.952)
        (xy 23.89 2.973)
        (xy 23.902 2.995)
        (xy 23.909 3.016)
        (xy 23.917 3.037)
        (xy 23.925 3.06)
        (xy 23.929 3.082)
        (xy 23.934 3.105)
        (xy 23.937 3.129)
        (xy 23.938 3.153)
        (xy 23.94 3.175)
        (xy 23.938 3.198)
        (xy 23.937 3.222)
        (xy 23.934 3.246)
        (xy 23.929 3.268)
        (xy 23.925 3.29)
        (xy 23.917 3.314)
        (xy 23.909 3.335)
        (xy 23.902 3.356)
        (xy 23.89 3.377)
        (xy 23.879 3.397)
        (xy 23.867 3.417)
        (xy 23.854 3.437)
        (xy 23.841 3.455)
        (xy 23.826 3.473)
        (xy 23.809 3.491)
        (xy 23.792 3.506)
        (xy 23.774 3.521)
        (xy 23.757 3.536)
        (xy 23.736 3.548)
        (xy 23.717 3.56)
        (xy 23.696 3.572)
        (xy 23.675 3.582)
        (xy 23.653 3.59)
        (xy 23.632 3.598)
        (xy 23.609 3.605)
        (xy 23.588 3.61)
        (xy 23.565 3.616)
        (xy 23.542 3.618)
        (xy 23.518 3.62)
        (xy 23.495 3.621)
        (xy 23.47 3.62)
        (xy 23.446 3.618)
        (xy 23.423 3.616)
        (xy 23.4 3.61)
        (xy 23.379 3.605)
        (xy 23.356 3.598)
        (xy 23.335 3.592)
        (xy 23.312 3.582)
        (xy 23.292 3.572)
        (xy 23.271 3.561)
        (xy 23.251 3.548)
        (xy 23.233 3.536)
        (xy 23.213 3.521)
        (xy 23.196 3.506)
        (xy 23.179 3.491)
        (xy 23.164 3.473)
        (xy 23.149 3.456)
        (xy 23.135 3.437)
        (xy 23.121 3.419)
        (xy 23.109 3.399)
        (xy 23.097 3.379)
        (xy 23.088 3.358)
        (xy 23.079 3.335)
        (xy 23.071 3.314)
        (xy 23.065 3.291)
        (xy 23.059 3.27)
        (xy 23.054 3.246)
        (xy 23.051 3.223)
        (xy 23.05 3.199)
        (xy 23.05 3.178)
        (xy 23.495 3.178)
        (xy 23.495 3.173)
      )

      (stroke (width 0.001) (type solid)) (fill solid) (layer "B.Paste"))
    (fp_poly
      (pts
        (xy 23.495 4.443)
        (xy 23.05 4.443)
        (xy 23.05 4.422)
        (xy 23.051 4.398)
        (xy 23.054 4.374)
        (xy 23.059 4.351)
        (xy 23.065 4.329)
        (xy 23.071 4.308)
        (xy 23.079 4.286)
        (xy 23.088 4.263)
        (xy 23.097 4.242)
        (xy 23.109 4.223)
        (xy 23.121 4.202)
        (xy 23.135 4.183)
        (xy 23.149 4.164)
        (xy 23.164 4.148)
        (xy 23.179 4.13)
        (xy 23.196 4.114)
        (xy 23.213 4.1)
        (xy 23.233 4.085)
        (xy 23.251 4.072)
        (xy 23.271 4.06)
        (xy 23.292 4.048)
        (xy 23.312 4.039)
        (xy 23.335 4.029)
        (xy 23.356 4.023)
        (xy 23.379 4.015)
        (xy 23.4 4.01)
        (xy 23.423 4.005)
        (xy 23.446 4.002)
        (xy 23.47 4.002)
        (xy 23.495 4)
        (xy 23.518 4.002)
        (xy 23.542 4.002)
        (xy 23.565 4.005)
        (xy 23.588 4.01)
        (xy 23.609 4.015)
        (xy 23.632 4.023)
        (xy 23.653 4.031)
        (xy 23.675 4.039)
        (xy 23.696 4.05)
        (xy 23.717 4.06)
        (xy 23.736 4.072)
        (xy 23.757 4.085)
        (xy 23.774 4.1)
        (xy 23.792 4.114)
        (xy 23.809 4.13)
        (xy 23.826 4.148)
        (xy 23.841 4.165)
        (xy 23.854 4.183)
        (xy 23.867 4.204)
        (xy 23.879 4.223)
        (xy 23.89 4.244)
        (xy 23.902 4.265)
        (xy 23.909 4.286)
        (xy 23.917 4.308)
        (xy 23.925 4.33)
        (xy 23.929 4.353)
        (xy 23.934 4.375)
        (xy 23.937 4.398)
        (xy 23.938 4.422)
        (xy 23.94 4.446)
        (xy 23.938 4.468)
        (xy 23.937 4.492)
        (xy 23.934 4.515)
        (xy 23.929 4.539)
        (xy 23.925 4.56)
        (xy 23.917 4.584)
        (xy 23.909 4.604)
        (xy 23.902 4.627)
        (xy 23.89 4.648)
        (xy 23.879 4.669)
        (xy 23.867 4.688)
        (xy 23.854 4.707)
        (xy 23.841 4.725)
        (xy 23.826 4.744)
        (xy 23.809 4.76)
        (xy 23.792 4.776)
        (xy 23.774 4.792)
        (xy 23.757 4.805)
        (xy 23.736 4.818)
        (xy 23.717 4.83)
        (xy 23.696 4.842)
        (xy 23.675 4.853)
        (xy 23.653 4.861)
        (xy 23.632 4.869)
        (xy 23.609 4.875)
        (xy 23.588 4.88)
        (xy 23.565 4.885)
        (xy 23.542 4.888)
        (xy 23.518 4.89)
        (xy 23.495 4.89)
        (xy 23.47 4.89)
        (xy 23.446 4.888)
        (xy 23.423 4.885)
        (xy 23.4 4.88)
        (xy 23.379 4.875)
        (xy 23.356 4.869)
        (xy 23.335 4.861)
        (xy 23.312 4.853)
        (xy 23.292 4.842)
        (xy 23.271 4.832)
        (xy 23.251 4.818)
        (xy 23.233 4.805)
        (xy 23.213 4.792)
        (xy 23.196 4.776)
        (xy 23.179 4.76)
        (xy 23.164 4.744)
        (xy 23.149 4.726)
        (xy 23.135 4.707)
        (xy 23.121 4.688)
        (xy 23.109 4.669)
        (xy 23.097 4.648)
        (xy 23.088 4.627)
        (xy 23.079 4.606)
        (xy 23.071 4.584)
        (xy 23.065 4.561)
        (xy 23.059 4.539)
        (xy 23.054 4.516)
        (xy 23.051 4.494)
        (xy 23.05 4.47)
        (xy 23.05 4.447)
        (xy 23.495 4.447)
        (xy 23.495 4.443)
      )

      (stroke (width 0.001) (type solid)) (fill solid) (layer "B.Paste"))
    (fp_poly
      (pts
        (xy 23.495 5.713)
        (xy 23.05 5.713)
        (xy 23.05 5.691)
        (xy 23.051 5.667)
        (xy 23.054 5.645)
        (xy 23.059 5.622)
        (xy 23.065 5.6)
        (xy 23.071 5.577)
        (xy 23.079 5.555)
        (xy 23.088 5.534)
        (xy 23.097 5.512)
        (xy 23.109 5.492)
        (xy 23.121 5.473)
        (xy 23.135 5.454)
        (xy 23.149 5.435)
        (xy 23.164 5.417)
        (xy 23.179 5.401)
        (xy 23.196 5.385)
        (xy 23.213 5.369)
        (xy 23.233 5.356)
        (xy 23.251 5.342)
        (xy 23.271 5.329)
        (xy 23.292 5.318)
        (xy 23.312 5.308)
        (xy 23.335 5.3)
        (xy 23.356 5.292)
        (xy 23.379 5.286)
        (xy 23.4 5.281)
        (xy 23.423 5.276)
        (xy 23.446 5.273)
        (xy 23.47 5.271)
        (xy 23.495 5.27)
        (xy 23.518 5.271)
        (xy 23.542 5.273)
        (xy 23.565 5.276)
        (xy 23.588 5.281)
        (xy 23.609 5.286)
        (xy 23.632 5.292)
        (xy 23.653 5.3)
        (xy 23.675 5.308)
        (xy 23.696 5.319)
        (xy 23.717 5.33)
        (xy 23.736 5.342)
        (xy 23.757 5.356)
        (xy 23.774 5.369)
        (xy 23.792 5.385)
        (xy 23.809 5.401)
        (xy 23.826 5.417)
        (xy 23.841 5.435)
        (xy 23.854 5.454)
        (xy 23.867 5.473)
        (xy 23.879 5.492)
        (xy 23.89 5.513)
        (xy 23.902 5.534)
        (xy 23.909 5.556)
        (xy 23.917 5.577)
        (xy 23.925 5.6)
        (xy 23.929 5.622)
        (xy 23.934 5.645)
        (xy 23.937 5.669)
        (xy 23.938 5.693)
        (xy 23.94 5.715)
        (xy 23.938 5.739)
        (xy 23.937 5.762)
        (xy 23.934 5.786)
        (xy 23.929 5.808)
        (xy 23.925 5.83)
        (xy 23.917 5.853)
        (xy 23.909 5.874)
        (xy 23.902 5.896)
        (xy 23.89 5.917)
        (xy 23.879 5.938)
        (xy 23.867 5.957)
        (xy 23.854 5.978)
        (xy 23.841 5.995)
        (xy 23.826 6.013)
        (xy 23.809 6.031)
        (xy 23.792 6.047)
        (xy 23.774 6.061)
        (xy 23.757 6.076)
        (xy 23.736 6.088)
        (xy 23.717 6.1)
        (xy 23.696 6.111)
        (xy 23.675 6.122)
        (xy 23.653 6.13)
        (xy 23.632 6.138)
        (xy 23.609 6.145)
        (xy 23.588 6.151)
        (xy 23.565 6.156)
        (xy 23.542 6.159)
        (xy 23.518 6.159)
        (xy 23.495 6.161)
        (xy 23.47 6.159)
        (xy 23.446 6.159)
        (xy 23.423 6.156)
        (xy 23.4 6.151)
        (xy 23.379 6.145)
        (xy 23.356 6.138)
        (xy 23.335 6.132)
        (xy 23.312 6.122)
        (xy 23.292 6.112)
        (xy 23.271 6.101)
        (xy 23.251 6.088)
        (xy 23.233 6.076)
        (xy 23.213 6.061)
        (xy 23.196 6.047)
        (xy 23.179 6.031)
        (xy 23.164 6.013)
        (xy 23.149 5.997)
        (xy 23.135 5.978)
        (xy 23.121 5.959)
        (xy 23.109 5.938)
        (xy 23.097 5.919)
        (xy 23.088 5.898)
        (xy 23.079 5.875)
        (xy 23.071 5.853)
        (xy 23.065 5.832)
        (xy 23.059 5.81)
        (xy 23.054 5.786)
        (xy 23.051 5.763)
        (xy 23.05 5.739)
        (xy 23.05 5.718)
        (xy 23.495 5.718)
        (xy 23.495 5.713)
      )

      (stroke (width 0.001) (type solid)) (fill solid) (layer "B.Paste"))
    (fp_poly
      (pts
        (xy 24.765 -5.717)
        (xy 24.319 -5.717)
        (xy 24.321 -5.738)
        (xy 24.321 -5.762)
        (xy 24.324 -5.785)
        (xy 24.329 -5.809)
        (xy 24.335 -5.831)
        (xy 24.341 -5.852)
        (xy 24.348 -5.874)
        (xy 24.358 -5.897)
        (xy 24.367 -5.918)
        (xy 24.379 -5.937)
        (xy 24.391 -5.958)
        (xy 24.405 -5.977)
        (xy 24.418 -5.996)
        (xy 24.434 -6.012)
        (xy 24.449 -6.03)
        (xy 24.466 -6.046)
        (xy 24.484 -6.06)
        (xy 24.502 -6.075)
        (xy 24.521 -6.087)
        (xy 24.542 -6.1)
        (xy 24.562 -6.111)
        (xy 24.582 -6.121)
        (xy 24.604 -6.131)
        (xy 24.626 -6.137)
        (xy 24.649 -6.144)
        (xy 24.67 -6.15)
        (xy 24.693 -6.155)
        (xy 24.716 -6.158)
        (xy 24.74 -6.158)
        (xy 24.765 -6.16)
        (xy 24.787 -6.158)
        (xy 24.812 -6.158)
        (xy 24.835 -6.155)
        (xy 24.858 -6.15)
        (xy 24.879 -6.144)
        (xy 24.902 -6.137)
        (xy 24.923 -6.129)
        (xy 24.946 -6.121)
        (xy 24.966 -6.11)
        (xy 24.987 -6.099)
        (xy 25.007 -6.087)
        (xy 25.027 -6.075)
        (xy 25.045 -6.06)
        (xy 25.062 -6.046)
        (xy 25.079 -6.03)
        (xy 25.095 -6.012)
        (xy 25.111 -5.994)
        (xy 25.124 -5.977)
        (xy 25.138 -5.956)
        (xy 25.149 -5.937)
        (xy 25.161 -5.916)
        (xy 25.172 -5.895)
        (xy 25.179 -5.873)
        (xy 25.187 -5.852)
        (xy 25.194 -5.829)
        (xy 25.199 -5.807)
        (xy 25.204 -5.785)
        (xy 25.207 -5.761)
        (xy 25.208 -5.738)
        (xy 25.21 -5.714)
        (xy 25.208 -5.692)
        (xy 25.207 -5.668)
        (xy 25.204 -5.644)
        (xy 25.199 -5.621)
        (xy 25.194 -5.599)
        (xy 25.187 -5.576)
        (xy 25.179 -5.555)
        (xy 25.172 -5.533)
        (xy 25.161 -5.512)
        (xy 25.149 -5.491)
        (xy 25.138 -5.472)
        (xy 25.124 -5.453)
        (xy 25.111 -5.434)
        (xy 25.095 -5.416)
        (xy 25.079 -5.4)
        (xy 25.062 -5.384)
        (xy 25.045 -5.368)
        (xy 25.027 -5.355)
        (xy 25.007 -5.341)
        (xy 24.987 -5.329)
        (xy 24.966 -5.318)
        (xy 24.946 -5.307)
        (xy 24.923 -5.299)
        (xy 24.902 -5.291)
        (xy 24.879 -5.285)
        (xy 24.858 -5.28)
        (xy 24.835 -5.275)
        (xy 24.812 -5.272)
        (xy 24.787 -5.27)
        (xy 24.765 -5.269)
        (xy 24.74 -5.27)
        (xy 24.716 -5.272)
        (xy 24.693 -5.275)
        (xy 24.67 -5.28)
        (xy 24.649 -5.285)
        (xy 24.626 -5.291)
        (xy 24.604 -5.299)
        (xy 24.582 -5.307)
        (xy 24.562 -5.317)
        (xy 24.542 -5.328)
        (xy 24.521 -5.341)
        (xy 24.502 -5.355)
        (xy 24.484 -5.368)
        (xy 24.466 -5.384)
        (xy 24.449 -5.4)
        (xy 24.434 -5.416)
        (xy 24.418 -5.434)
        (xy 24.405 -5.453)
        (xy 24.391 -5.472)
        (xy 24.379 -5.491)
        (xy 24.367 -5.511)
        (xy 24.358 -5.533)
        (xy 24.348 -5.554)
        (xy 24.341 -5.576)
        (xy 24.335 -5.599)
        (xy 24.329 -5.621)
        (xy 24.324 -5.644)
        (xy 24.321 -5.666)
        (xy 24.321 -5.69)
        (xy 24.319 -5.712)
        (xy 24.765 -5.712)
        (xy 24.765 -5.717)
      )

      (stroke (width 0.001) (type solid)) (fill solid) (layer "B.Paste"))
    (fp_poly
      (pts
        (xy 24.765 -3.177)
        (xy 24.319 -3.177)
        (xy 24.321 -3.198)
        (xy 24.321 -3.222)
        (xy 24.324 -3.245)
        (xy 24.329 -3.269)
        (xy 24.335 -3.29)
        (xy 24.341 -3.313)
        (xy 24.348 -3.334)
        (xy 24.358 -3.357)
        (xy 24.367 -3.378)
        (xy 24.379 -3.398)
        (xy 24.391 -3.418)
        (xy 24.405 -3.436)
        (xy 24.418 -3.455)
        (xy 24.434 -3.472)
        (xy 24.449 -3.49)
        (xy 24.466 -3.505)
        (xy 24.484 -3.52)
        (xy 24.502 -3.535)
        (xy 24.521 -3.547)
        (xy 24.542 -3.56)
        (xy 24.562 -3.571)
        (xy 24.582 -3.581)
        (xy 24.604 -3.591)
        (xy 24.626 -3.597)
        (xy 24.649 -3.604)
        (xy 24.67 -3.609)
        (xy 24.693 -3.615)
        (xy 24.716 -3.617)
        (xy 24.74 -3.619)
        (xy 24.765 -3.62)
        (xy 24.787 -3.619)
        (xy 24.812 -3.617)
        (xy 24.835 -3.615)
        (xy 24.858 -3.609)
        (xy 24.879 -3.604)
        (xy 24.902 -3.597)
        (xy 24.923 -3.589)
        (xy 24.946 -3.581)
        (xy 24.966 -3.571)
        (xy 24.987 -3.559)
        (xy 25.007 -3.547)
        (xy 25.027 -3.535)
        (xy 25.045 -3.52)
        (xy 25.062 -3.505)
        (xy 25.079 -3.49)
        (xy 25.095 -3.472)
        (xy 25.111 -3.454)
        (xy 25.124 -3.436)
        (xy 25.138 -3.416)
        (xy 25.149 -3.396)
        (xy 25.161 -3.376)
        (xy 25.172 -3.355)
        (xy 25.179 -3.334)
        (xy 25.187 -3.313)
        (xy 25.194 -3.289)
        (xy 25.199 -3.267)
        (xy 25.204 -3.245)
        (xy 25.207 -3.221)
        (xy 25.208 -3.197)
        (xy 25.21 -3.174)
        (xy 25.208 -3.152)
        (xy 25.207 -3.128)
        (xy 25.204 -3.104)
        (xy 25.199 -3.081)
        (xy 25.194 -3.059)
        (xy 25.187 -3.036)
        (xy 25.179 -3.015)
        (xy 25.172 -2.994)
        (xy 25.161 -2.972)
        (xy 25.149 -2.951)
        (xy 25.138 -2.932)
        (xy 25.124 -2.912)
        (xy 25.111 -2.894)
        (xy 25.095 -2.876)
        (xy 25.079 -2.859)
        (xy 25.062 -2.843)
        (xy 25.045 -2.829)
        (xy 25.027 -2.814)
        (xy 25.007 -2.801)
        (xy 24.987 -2.789)
        (xy 24.966 -2.778)
        (xy 24.946 -2.767)
        (xy 24.923 -2.759)
        (xy 24.902 -2.751)
        (xy 24.879 -2.745)
        (xy 24.858 -2.74)
        (xy 24.835 -2.734)
        (xy 24.812 -2.732)
        (xy 24.787 -2.73)
        (xy 24.765 -2.729)
        (xy 24.74 -2.73)
        (xy 24.716 -2.732)
        (xy 24.693 -2.734)
        (xy 24.67 -2.74)
        (xy 24.649 -2.745)
        (xy 24.626 -2.751)
        (xy 24.604 -2.758)
        (xy 24.582 -2.767)
        (xy 24.562 -2.777)
        (xy 24.542 -2.789)
        (xy 24.521 -2.801)
        (xy 24.502 -2.814)
        (xy 24.484 -2.829)
        (xy 24.466 -2.843)
        (xy 24.449 -2.859)
        (xy 24.434 -2.876)
        (xy 24.418 -2.894)
        (xy 24.405 -2.912)
        (xy 24.391 -2.931)
        (xy 24.379 -2.951)
        (xy 24.367 -2.971)
        (xy 24.358 -2.992)
        (xy 24.348 -3.015)
        (xy 24.341 -3.036)
        (xy 24.335 -3.059)
        (xy 24.329 -3.08)
        (xy 24.324 -3.104)
        (xy 24.321 -3.126)
        (xy 24.321 -3.15)
        (xy 24.319 -3.172)
        (xy 24.765 -3.172)
        (xy 24.765 -3.177)
      )

      (stroke (width 0.001) (type solid)) (fill solid) (layer "B.Paste"))
    (fp_poly
      (pts
        (xy 24.765 1.903)
        (xy 24.319 1.903)
        (xy 24.321 1.881)
        (xy 24.321 1.857)
        (xy 24.324 1.835)
        (xy 24.329 1.811)
        (xy 24.335 1.789)
        (xy 24.341 1.767)
        (xy 24.348 1.746)
        (xy 24.358 1.724)
        (xy 24.367 1.702)
        (xy 24.379 1.682)
        (xy 24.391 1.662)
        (xy 24.405 1.643)
        (xy 24.418 1.625)
        (xy 24.434 1.607)
        (xy 24.449 1.591)
        (xy 24.466 1.575)
        (xy 24.484 1.559)
        (xy 24.502 1.545)
        (xy 24.521 1.532)
        (xy 24.542 1.519)
        (xy 24.562 1.508)
        (xy 24.582 1.498)
        (xy 24.604 1.49)
        (xy 24.626 1.482)
        (xy 24.649 1.476)
        (xy 24.67 1.47)
        (xy 24.693 1.466)
        (xy 24.716 1.462)
        (xy 24.74 1.462)
        (xy 24.765 1.46)
        (xy 24.787 1.462)
        (xy 24.812 1.462)
        (xy 24.835 1.466)
        (xy 24.858 1.47)
        (xy 24.879 1.476)
        (xy 24.902 1.482)
        (xy 24.923 1.49)
        (xy 24.946 1.498)
        (xy 24.966 1.509)
        (xy 24.987 1.52)
        (xy 25.007 1.532)
        (xy 25.027 1.545)
        (xy 25.045 1.559)
        (xy 25.062 1.575)
        (xy 25.079 1.591)
        (xy 25.095 1.607)
        (xy 25.111 1.625)
        (xy 25.124 1.643)
        (xy 25.138 1.663)
        (xy 25.149 1.684)
        (xy 25.161 1.704)
        (xy 25.172 1.724)
        (xy 25.179 1.746)
        (xy 25.187 1.767)
        (xy 25.194 1.79)
        (xy 25.199 1.813)
        (xy 25.204 1.835)
        (xy 25.207 1.859)
        (xy 25.208 1.882)
        (xy 25.21 1.905)
        (xy 25.208 1.928)
        (xy 25.207 1.952)
        (xy 25.204 1.976)
        (xy 25.199 1.998)
        (xy 25.194 2.02)
        (xy 25.187 2.044)
        (xy 25.179 2.065)
        (xy 25.172 2.086)
        (xy 25.161 2.108)
        (xy 25.149 2.127)
        (xy 25.138 2.147)
        (xy 25.124 2.167)
        (xy 25.111 2.186)
        (xy 25.095 2.203)
        (xy 25.079 2.221)
        (xy 25.062 2.237)
        (xy 25.045 2.251)
        (xy 25.027 2.266)
        (xy 25.007 2.278)
        (xy 24.987 2.29)
        (xy 24.966 2.302)
        (xy 24.946 2.312)
        (xy 24.923 2.32)
        (xy 24.902 2.328)
        (xy 24.879 2.335)
        (xy 24.858 2.34)
        (xy 24.835 2.346)
        (xy 24.812 2.348)
        (xy 24.787 2.35)
        (xy 24.765 2.351)
        (xy 24.74 2.35)
        (xy 24.716 2.348)
        (xy 24.693 2.346)
        (xy 24.67 2.34)
        (xy 24.649 2.335)
        (xy 24.626 2.328)
        (xy 24.604 2.322)
        (xy 24.582 2.312)
        (xy 24.562 2.302)
        (xy 24.542 2.291)
        (xy 24.521 2.278)
        (xy 24.502 2.266)
        (xy 24.484 2.251)
        (xy 24.466 2.237)
        (xy 24.449 2.221)
        (xy 24.434 2.203)
        (xy 24.418 2.186)
        (xy 24.405 2.167)
        (xy 24.391 2.149)
        (xy 24.379 2.129)
        (xy 24.367 2.109)
        (xy 24.358 2.088)
        (xy 24.348 2.065)
        (xy 24.341 2.044)
        (xy 24.335 2.021)
        (xy 24.329 2)
        (xy 24.324 1.976)
        (xy 24.321 1.954)
        (xy 24.321 1.93)
        (xy 24.319 1.907)
        (xy 24.765 1.907)
        (xy 24.765 1.903)
      )

      (stroke (width 0.001) (type solid)) (fill solid) (layer "B.Paste"))
    (fp_poly
      (pts
        (xy 24.765 3.173)
        (xy 24.319 3.173)
        (xy 24.321 3.151)
        (xy 24.321 3.127)
        (xy 24.324 3.105)
        (xy 24.329 3.081)
        (xy 24.335 3.06)
        (xy 24.341 3.037)
        (xy 24.348 3.016)
        (xy 24.358 2.993)
        (xy 24.367 2.972)
        (xy 24.379 2.952)
        (xy 24.391 2.932)
        (xy 24.405 2.913)
        (xy 24.418 2.895)
        (xy 24.434 2.877)
        (xy 24.449 2.86)
        (xy 24.466 2.844)
        (xy 24.484 2.83)
        (xy 24.502 2.815)
        (xy 24.521 2.802)
        (xy 24.542 2.79)
        (xy 24.562 2.778)
        (xy 24.582 2.768)
        (xy 24.604 2.759)
        (xy 24.626 2.752)
        (xy 24.649 2.746)
        (xy 24.67 2.741)
        (xy 24.693 2.735)
        (xy 24.716 2.733)
        (xy 24.74 2.731)
        (xy 24.765 2.73)
        (xy 24.787 2.731)
        (xy 24.812 2.733)
        (xy 24.835 2.735)
        (xy 24.858 2.741)
        (xy 24.879 2.746)
        (xy 24.902 2.752)
        (xy 24.923 2.76)
        (xy 24.946 2.768)
        (xy 24.966 2.779)
        (xy 24.987 2.79)
        (xy 25.007 2.802)
        (xy 25.027 2.815)
        (xy 25.045 2.83)
        (xy 25.062 2.844)
        (xy 25.079 2.86)
        (xy 25.095 2.877)
        (xy 25.111 2.895)
        (xy 25.124 2.913)
        (xy 25.138 2.933)
        (xy 25.149 2.952)
        (xy 25.161 2.973)
        (xy 25.172 2.995)
        (xy 25.179 3.016)
        (xy 25.187 3.037)
        (xy 25.194 3.06)
        (xy 25.199 3.082)
        (xy 25.204 3.105)
        (xy 25.207 3.129)
        (xy 25.208 3.153)
        (xy 25.21 3.175)
        (xy 25.208 3.198)
        (xy 25.207 3.222)
        (xy 25.204 3.246)
        (xy 25.199 3.268)
        (xy 25.194 3.29)
        (xy 25.187 3.314)
        (xy 25.179 3.335)
        (xy 25.172 3.356)
        (xy 25.161 3.377)
        (xy 25.149 3.397)
        (xy 25.138 3.417)
        (xy 25.124 3.437)
        (xy 25.111 3.455)
        (xy 25.095 3.473)
        (xy 25.079 3.491)
        (xy 25.062 3.506)
        (xy 25.045 3.521)
        (xy 25.027 3.536)
        (xy 25.007 3.548)
        (xy 24.987 3.56)
        (xy 24.966 3.572)
        (xy 24.946 3.582)
        (xy 24.923 3.59)
        (xy 24.902 3.598)
        (xy 24.879 3.605)
        (xy 24.858 3.61)
        (xy 24.835 3.616)
        (xy 24.812 3.618)
        (xy 24.787 3.62)
        (xy 24.765 3.621)
        (xy 24.74 3.62)
        (xy 24.716 3.618)
        (xy 24.693 3.616)
        (xy 24.67 3.61)
        (xy 24.649 3.605)
        (xy 24.626 3.598)
        (xy 24.604 3.592)
        (xy 24.582 3.582)
        (xy 24.562 3.572)
        (xy 24.542 3.561)
        (xy 24.521 3.548)
        (xy 24.502 3.536)
        (xy 24.484 3.521)
        (xy 24.466 3.506)
        (xy 24.449 3.491)
        (xy 24.434 3.473)
        (xy 24.418 3.456)
        (xy 24.405 3.437)
        (xy 24.391 3.419)
        (xy 24.379 3.399)
        (xy 24.367 3.379)
        (xy 24.358 3.358)
        (xy 24.348 3.335)
        (xy 24.341 3.314)
        (xy 24.335 3.291)
        (xy 24.329 3.27)
        (xy 24.324 3.246)
        (xy 24.321 3.223)
        (xy 24.321 3.199)
        (xy 24.319 3.178)
        (xy 24.765 3.178)
        (xy 24.765 3.173)
      )

      (stroke (width 0.001) (type solid)) (fill solid) (layer "B.Paste"))
    (fp_poly
      (pts
        (xy 24.765 4.443)
        (xy 24.319 4.443)
        (xy 24.321 4.422)
        (xy 24.321 4.398)
        (xy 24.324 4.374)
        (xy 24.329 4.351)
        (xy 24.335 4.329)
        (xy 24.341 4.308)
        (xy 24.348 4.286)
        (xy 24.358 4.263)
        (xy 24.367 4.242)
        (xy 24.379 4.223)
        (xy 24.391 4.202)
        (xy 24.405 4.183)
        (xy 24.418 4.164)
        (xy 24.434 4.148)
        (xy 24.449 4.13)
        (xy 24.466 4.114)
        (xy 24.484 4.1)
        (xy 24.502 4.085)
        (xy 24.521 4.072)
        (xy 24.542 4.06)
        (xy 24.562 4.048)
        (xy 24.582 4.039)
        (xy 24.604 4.029)
        (xy 24.626 4.023)
        (xy 24.649 4.015)
        (xy 24.67 4.01)
        (xy 24.693 4.005)
        (xy 24.716 4.002)
        (xy 24.74 4.002)
        (xy 24.765 4)
        (xy 24.787 4.002)
        (xy 24.812 4.002)
        (xy 24.835 4.005)
        (xy 24.858 4.01)
        (xy 24.879 4.015)
        (xy 24.902 4.023)
        (xy 24.923 4.031)
        (xy 24.946 4.039)
        (xy 24.966 4.05)
        (xy 24.987 4.06)
        (xy 25.007 4.072)
        (xy 25.027 4.085)
        (xy 25.045 4.1)
        (xy 25.062 4.114)
        (xy 25.079 4.13)
        (xy 25.095 4.148)
        (xy 25.111 4.165)
        (xy 25.124 4.183)
        (xy 25.138 4.204)
        (xy 25.149 4.223)
        (xy 25.161 4.244)
        (xy 25.172 4.265)
        (xy 25.179 4.286)
        (xy 25.187 4.308)
        (xy 25.194 4.33)
        (xy 25.199 4.353)
        (xy 25.204 4.375)
        (xy 25.207 4.398)
        (xy 25.208 4.422)
        (xy 25.21 4.446)
        (xy 25.208 4.468)
        (xy 25.207 4.492)
        (xy 25.204 4.515)
        (xy 25.199 4.539)
        (xy 25.194 4.56)
        (xy 25.187 4.584)
        (xy 25.179 4.604)
        (xy 25.172 4.627)
        (xy 25.161 4.648)
        (xy 25.149 4.669)
        (xy 25.138 4.688)
        (xy 25.124 4.707)
        (xy 25.111 4.725)
        (xy 25.095 4.744)
        (xy 25.079 4.76)
        (xy 25.062 4.776)
        (xy 25.045 4.792)
        (xy 25.027 4.805)
        (xy 25.007 4.818)
        (xy 24.987 4.83)
        (xy 24.966 4.842)
        (xy 24.946 4.853)
        (xy 24.923 4.861)
        (xy 24.902 4.869)
        (xy 24.879 4.875)
        (xy 24.858 4.88)
        (xy 24.835 4.885)
        (xy 24.812 4.888)
        (xy 24.787 4.89)
        (xy 24.765 4.89)
        (xy 24.74 4.89)
        (xy 24.716 4.888)
        (xy 24.693 4.885)
        (xy 24.67 4.88)
        (xy 24.649 4.875)
        (xy 24.626 4.869)
        (xy 24.604 4.861)
        (xy 24.582 4.853)
        (xy 24.562 4.842)
        (xy 24.542 4.832)
        (xy 24.521 4.818)
        (xy 24.502 4.805)
        (xy 24.484 4.792)
        (xy 24.466 4.776)
        (xy 24.449 4.76)
        (xy 24.434 4.744)
        (xy 24.418 4.726)
        (xy 24.405 4.707)
        (xy 24.391 4.688)
        (xy 24.379 4.669)
        (xy 24.367 4.648)
        (xy 24.358 4.627)
        (xy 24.348 4.606)
        (xy 24.341 4.584)
        (xy 24.335 4.561)
        (xy 24.329 4.539)
        (xy 24.324 4.516)
        (xy 24.321 4.494)
        (xy 24.321 4.47)
        (xy 24.319 4.447)
        (xy 24.765 4.447)
        (xy 24.765 4.443)
      )

      (stroke (width 0.001) (type solid)) (fill solid) (layer "B.Paste"))
    (fp_poly
      (pts
        (xy 24.765 5.713)
        (xy 24.319 5.713)
        (xy 24.321 5.691)
        (xy 24.321 5.667)
        (xy 24.324 5.645)
        (xy 24.329 5.622)
        (xy 24.335 5.6)
        (xy 24.341 5.577)
        (xy 24.348 5.555)
        (xy 24.358 5.534)
        (xy 24.367 5.512)
        (xy 24.379 5.492)
        (xy 24.391 5.473)
        (xy 24.405 5.454)
        (xy 24.418 5.435)
        (xy 24.434 5.417)
        (xy 24.449 5.401)
        (xy 24.466 5.385)
        (xy 24.484 5.369)
        (xy 24.502 5.356)
        (xy 24.521 5.342)
        (xy 24.542 5.329)
        (xy 24.562 5.318)
        (xy 24.582 5.308)
        (xy 24.604 5.3)
        (xy 24.626 5.292)
        (xy 24.649 5.286)
        (xy 24.67 5.281)
        (xy 24.693 5.276)
        (xy 24.716 5.273)
        (xy 24.74 5.271)
        (xy 24.765 5.27)
        (xy 24.787 5.271)
        (xy 24.812 5.273)
        (xy 24.835 5.276)
        (xy 24.858 5.281)
        (xy 24.879 5.286)
        (xy 24.902 5.292)
        (xy 24.923 5.3)
        (xy 24.946 5.308)
        (xy 24.966 5.319)
        (xy 24.987 5.33)
        (xy 25.007 5.342)
        (xy 25.027 5.356)
        (xy 25.045 5.369)
        (xy 25.062 5.385)
        (xy 25.079 5.401)
        (xy 25.095 5.417)
        (xy 25.111 5.435)
        (xy 25.124 5.454)
        (xy 25.138 5.473)
        (xy 25.149 5.492)
        (xy 25.161 5.513)
        (xy 25.172 5.534)
        (xy 25.179 5.556)
        (xy 25.187 5.577)
        (xy 25.194 5.6)
        (xy 25.199 5.622)
        (xy 25.204 5.645)
        (xy 25.207 5.669)
        (xy 25.208 5.693)
        (xy 25.21 5.715)
        (xy 25.208 5.739)
        (xy 25.207 5.762)
        (xy 25.204 5.786)
        (xy 25.199 5.808)
        (xy 25.194 5.83)
        (xy 25.187 5.853)
        (xy 25.179 5.874)
        (xy 25.172 5.896)
        (xy 25.161 5.917)
        (xy 25.149 5.938)
        (xy 25.138 5.957)
        (xy 25.124 5.978)
        (xy 25.111 5.995)
        (xy 25.095 6.013)
        (xy 25.079 6.031)
        (xy 25.062 6.047)
        (xy 25.045 6.061)
        (xy 25.027 6.076)
        (xy 25.007 6.088)
        (xy 24.987 6.1)
        (xy 24.966 6.111)
        (xy 24.946 6.122)
        (xy 24.923 6.13)
        (xy 24.902 6.138)
        (xy 24.879 6.145)
        (xy 24.858 6.151)
        (xy 24.835 6.156)
        (xy 24.812 6.159)
        (xy 24.787 6.159)
        (xy 24.765 6.161)
        (xy 24.74 6.159)
        (xy 24.716 6.159)
        (xy 24.693 6.156)
        (xy 24.67 6.151)
        (xy 24.649 6.145)
        (xy 24.626 6.138)
        (xy 24.604 6.132)
        (xy 24.582 6.122)
        (xy 24.562 6.112)
        (xy 24.542 6.101)
        (xy 24.521 6.088)
        (xy 24.502 6.076)
        (xy 24.484 6.061)
        (xy 24.466 6.047)
        (xy 24.449 6.031)
        (xy 24.434 6.013)
        (xy 24.418 5.997)
        (xy 24.405 5.978)
        (xy 24.391 5.959)
        (xy 24.379 5.938)
        (xy 24.367 5.919)
        (xy 24.358 5.898)
        (xy 24.348 5.875)
        (xy 24.341 5.853)
        (xy 24.335 5.832)
        (xy 24.329 5.81)
        (xy 24.324 5.786)
        (xy 24.321 5.763)
        (xy 24.321 5.739)
        (xy 24.319 5.718)
        (xy 24.765 5.718)
        (xy 24.765 5.713)
      )

      (stroke (width 0.001) (type solid)) (fill solid) (layer "B.Paste"))
    (fp_poly
      (pts
        (xy -24.766 -4.447)
        (xy -25.211 -4.446)
        (xy -25.209 -4.469)
        (xy -25.208 -4.493)
        (xy -25.205 -4.515)
        (xy -25.2 -4.538)
        (xy -25.195 -4.56)
        (xy -25.188 -4.583)
        (xy -25.182 -4.605)
        (xy -25.173 -4.626)
        (xy -25.162 -4.647)
        (xy -25.151 -4.668)
        (xy -25.139 -4.687)
        (xy -25.125 -4.706)
        (xy -25.112 -4.725)
        (xy -25.096 -4.743)
        (xy -25.08 -4.759)
        (xy -25.063 -4.775)
        (xy -25.046 -4.791)
        (xy -25.028 -4.804)
        (xy -25.008 -4.817)
        (xy -24.988 -4.831)
        (xy -24.968 -4.841)
        (xy -24.947 -4.852)
        (xy -24.926 -4.86)
        (xy -24.903 -4.868)
        (xy -24.881 -4.874)
        (xy -24.86 -4.879)
        (xy -24.836 -4.884)
        (xy -24.813 -4.887)
        (xy -24.79 -4.889)
        (xy -24.766 -4.889)
        (xy -24.743 -4.889)
        (xy -24.718 -4.887)
        (xy -24.695 -4.884)
        (xy -24.673 -4.879)
        (xy -24.65 -4.874)
        (xy -24.627 -4.868)
        (xy -24.607 -4.86)
        (xy -24.584 -4.852)
        (xy -24.563 -4.841)
        (xy -24.543 -4.829)
        (xy -24.523 -4.817)
        (xy -24.503 -4.804)
        (xy -24.485 -4.791)
        (xy -24.467 -4.775)
        (xy -24.45 -4.759)
        (xy -24.435 -4.743)
        (xy -24.419 -4.724)
        (xy -24.406 -4.706)
        (xy -24.392 -4.687)
        (xy -24.38 -4.668)
        (xy -24.369 -4.647)
        (xy -24.359 -4.626)
        (xy -24.351 -4.603)
        (xy -24.342 -4.583)
        (xy -24.336 -4.559)
        (xy -24.33 -4.538)
        (xy -24.325 -4.514)
        (xy -24.322 -4.491)
        (xy -24.322 -4.467)
        (xy -24.32 -4.445)
        (xy -24.322 -4.421)
        (xy -24.322 -4.397)
        (xy -24.325 -4.374)
        (xy -24.33 -4.352)
        (xy -24.336 -4.329)
        (xy -24.342 -4.307)
        (xy -24.351 -4.285)
        (xy -24.359 -4.264)
        (xy -24.369 -4.243)
        (xy -24.38 -4.222)
        (xy -24.392 -4.203)
        (xy -24.406 -4.182)
        (xy -24.419 -4.164)
        (xy -24.435 -4.147)
        (xy -24.45 -4.129)
        (xy -24.467 -4.113)
        (xy -24.485 -4.099)
        (xy -24.503 -4.084)
        (xy -24.523 -4.071)
        (xy -24.543 -4.059)
        (xy -24.563 -4.049)
        (xy -24.584 -4.038)
        (xy -24.607 -4.03)
        (xy -24.627 -4.022)
        (xy -24.65 -4.014)
        (xy -24.673 -4.009)
        (xy -24.695 -4.004)
        (xy -24.718 -4.001)
        (xy -24.743 -4.001)
        (xy -24.766 -3.999)
        (xy -24.79 -4.001)
        (xy -24.813 -4.001)
        (xy -24.836 -4.004)
        (xy -24.86 -4.009)
        (xy -24.881 -4.014)
        (xy -24.903 -4.022)
        (xy -24.926 -4.028)
        (xy -24.947 -4.038)
        (xy -24.968 -4.047)
        (xy -24.988 -4.059)
        (xy -25.008 -4.071)
        (xy -25.028 -4.084)
        (xy -25.046 -4.099)
        (xy -25.063 -4.113)
        (xy -25.08 -4.129)
        (xy -25.096 -4.147)
        (xy -25.112 -4.163)
        (xy -25.125 -4.182)
        (xy -25.139 -4.201)
        (xy -25.151 -4.222)
        (xy -25.162 -4.241)
        (xy -25.173 -4.262)
        (xy -25.182 -4.285)
        (xy -25.188 -4.307)
        (xy -25.195 -4.328)
        (xy -25.2 -4.35)
        (xy -25.205 -4.373)
        (xy -25.208 -4.397)
        (xy -25.209 -4.421)
        (xy -25.211 -4.442)
        (xy -24.766 -4.442)
        (xy -24.766 -4.446)
        (xy -24.766 -4.447)
      )

      (stroke (width 0.001) (type solid)) (fill solid) (layer "B.Paste"))
    (fp_poly
      (pts
        (xy -24.766 -1.907)
        (xy -25.211 -1.906)
        (xy -25.209 -1.929)
        (xy -25.208 -1.953)
        (xy -25.205 -1.975)
        (xy -25.2 -1.999)
        (xy -25.195 -2.02)
        (xy -25.188 -2.043)
        (xy -25.182 -2.064)
        (xy -25.173 -2.087)
        (xy -25.162 -2.108)
        (xy -25.151 -2.128)
        (xy -25.139 -2.148)
        (xy -25.125 -2.166)
        (xy -25.112 -2.185)
        (xy -25.096 -2.202)
        (xy -25.08 -2.22)
        (xy -25.063 -2.236)
        (xy -25.046 -2.25)
        (xy -25.028 -2.265)
        (xy -25.008 -2.277)
        (xy -24.988 -2.29)
        (xy -24.968 -2.301)
        (xy -24.947 -2.311)
        (xy -24.926 -2.321)
        (xy -24.903 -2.327)
        (xy -24.881 -2.334)
        (xy -24.86 -2.339)
        (xy -24.836 -2.345)
        (xy -24.813 -2.347)
        (xy -24.79 -2.349)
        (xy -24.766 -2.35)
        (xy -24.743 -2.349)
        (xy -24.718 -2.347)
        (xy -24.695 -2.345)
        (xy -24.673 -2.339)
        (xy -24.65 -2.334)
        (xy -24.627 -2.327)
        (xy -24.607 -2.319)
        (xy -24.584 -2.311)
        (xy -24.563 -2.301)
        (xy -24.543 -2.289)
        (xy -24.523 -2.277)
        (xy -24.503 -2.265)
        (xy -24.485 -2.25)
        (xy -24.467 -2.236)
        (xy -24.45 -2.22)
        (xy -24.435 -2.202)
        (xy -24.419 -2.185)
        (xy -24.406 -2.166)
        (xy -24.392 -2.146)
        (xy -24.38 -2.126)
        (xy -24.369 -2.107)
        (xy -24.359 -2.085)
        (xy -24.351 -2.064)
        (xy -24.342 -2.043)
        (xy -24.336 -2.019)
        (xy -24.33 -1.997)
        (xy -24.325 -1.975)
        (xy -24.322 -1.951)
        (xy -24.322 -1.927)
        (xy -24.32 -1.904)
        (xy -24.322 -1.881)
        (xy -24.322 -1.858)
        (xy -24.325 -1.834)
        (xy -24.33 -1.812)
        (xy -24.336 -1.789)
        (xy -24.342 -1.766)
        (xy -24.351 -1.745)
        (xy -24.359 -1.723)
        (xy -24.369 -1.703)
        (xy -24.38 -1.683)
        (xy -24.392 -1.662)
        (xy -24.406 -1.642)
        (xy -24.419 -1.624)
        (xy -24.435 -1.606)
        (xy -24.45 -1.59)
        (xy -24.467 -1.574)
        (xy -24.485 -1.558)
        (xy -24.503 -1.544)
        (xy -24.523 -1.531)
        (xy -24.543 -1.519)
        (xy -24.563 -1.508)
        (xy -24.584 -1.497)
        (xy -24.607 -1.489)
        (xy -24.627 -1.481)
        (xy -24.65 -1.475)
        (xy -24.673 -1.469)
        (xy -24.695 -1.465)
        (xy -24.718 -1.461)
        (xy -24.743 -1.461)
        (xy -24.766 -1.459)
        (xy -24.79 -1.461)
        (xy -24.813 -1.461)
        (xy -24.836 -1.465)
        (xy -24.86 -1.469)
        (xy -24.881 -1.475)
        (xy -24.903 -1.481)
        (xy -24.926 -1.489)
        (xy -24.947 -1.497)
        (xy -24.968 -1.507)
        (xy -24.988 -1.518)
        (xy -25.008 -1.531)
        (xy -25.028 -1.544)
        (xy -25.046 -1.558)
        (xy -25.063 -1.574)
        (xy -25.08 -1.59)
        (xy -25.096 -1.606)
        (xy -25.112 -1.624)
        (xy -25.125 -1.642)
        (xy -25.139 -1.661)
        (xy -25.151 -1.681)
        (xy -25.162 -1.701)
        (xy -25.173 -1.723)
        (xy -25.182 -1.745)
        (xy -25.188 -1.766)
        (xy -25.195 -1.788)
        (xy -25.2 -1.81)
        (xy -25.205 -1.834)
        (xy -25.208 -1.856)
        (xy -25.209 -1.88)
        (xy -25.211 -1.902)
        (xy -24.766 -1.902)
        (xy -24.766 -1.906)
        (xy -24.766 -1.907)
      )

      (stroke (width 0.001) (type solid)) (fill solid) (layer "B.Paste"))
    (fp_poly
      (pts
        (xy -24.766 -0.637)
        (xy -25.211 -0.636)
        (xy -25.209 -0.659)
        (xy -25.208 -0.683)
        (xy -25.205 -0.705)
        (xy -25.2 -0.728)
        (xy -25.195 -0.75)
        (xy -25.188 -0.773)
        (xy -25.182 -0.795)
        (xy -25.173 -0.816)
        (xy -25.162 -0.837)
        (xy -25.151 -0.857)
        (xy -25.139 -0.877)
        (xy -25.125 -0.897)
        (xy -25.112 -0.916)
        (xy -25.096 -0.933)
        (xy -25.08 -0.949)
        (xy -25.063 -0.965)
        (xy -25.046 -0.98)
        (xy -25.028 -0.994)
        (xy -25.008 -1.007)
        (xy -24.988 -1.02)
        (xy -24.968 -1.032)
        (xy -24.947 -1.042)
        (xy -24.926 -1.05)
        (xy -24.903 -1.058)
        (xy -24.881 -1.064)
        (xy -24.86 -1.07)
        (xy -24.836 -1.074)
        (xy -24.813 -1.078)
        (xy -24.79 -1.078)
        (xy -24.766 -1.08)
        (xy -24.743 -1.078)
        (xy -24.718 -1.078)
        (xy -24.695 -1.074)
        (xy -24.673 -1.07)
        (xy -24.65 -1.064)
        (xy -24.627 -1.058)
        (xy -24.607 -1.05)
        (xy -24.584 -1.042)
        (xy -24.563 -1.03)
        (xy -24.543 -1.019)
        (xy -24.523 -1.007)
        (xy -24.503 -0.994)
        (xy -24.485 -0.98)
        (xy -24.467 -0.965)
        (xy -24.45 -0.949)
        (xy -24.435 -0.933)
        (xy -24.419 -0.915)
        (xy -24.406 -0.897)
        (xy -24.392 -0.876)
        (xy -24.38 -0.856)
        (xy -24.369 -0.836)
        (xy -24.359 -0.815)
        (xy -24.351 -0.794)
        (xy -24.342 -0.773)
        (xy -24.336 -0.749)
        (xy -24.33 -0.727)
        (xy -24.325 -0.704)
        (xy -24.322 -0.682)
        (xy -24.322 -0.658)
        (xy -24.32 -0.634)
        (xy -24.322 -0.611)
        (xy -24.322 -0.587)
        (xy -24.325 -0.564)
        (xy -24.33 -0.542)
        (xy -24.336 -0.52)
        (xy -24.342 -0.496)
        (xy -24.351 -0.475)
        (xy -24.359 -0.454)
        (xy -24.369 -0.432)
        (xy -24.38 -0.412)
        (xy -24.392 -0.393)
        (xy -24.406 -0.372)
        (xy -24.419 -0.354)
        (xy -24.435 -0.337)
        (xy -24.45 -0.32)
        (xy -24.467 -0.303)
        (xy -24.485 -0.288)
        (xy -24.503 -0.275)
        (xy -24.523 -0.262)
        (xy -24.543 -0.249)
        (xy -24.563 -0.238)
        (xy -24.584 -0.228)
        (xy -24.607 -0.219)
        (xy -24.627 -0.211)
        (xy -24.65 -0.204)
        (xy -24.673 -0.2)
        (xy -24.695 -0.195)
        (xy -24.718 -0.192)
        (xy -24.743 -0.19)
        (xy -24.766 -0.189)
        (xy -24.79 -0.19)
        (xy -24.813 -0.192)
        (xy -24.836 -0.195)
        (xy -24.86 -0.2)
        (xy -24.881 -0.204)
        (xy -24.903 -0.211)
        (xy -24.926 -0.218)
        (xy -24.947 -0.228)
        (xy -24.968 -0.237)
        (xy -24.988 -0.248)
        (xy -25.008 -0.262)
        (xy -25.028 -0.275)
        (xy -25.046 -0.288)
        (xy -25.063 -0.303)
        (xy -25.08 -0.32)
        (xy -25.096 -0.337)
        (xy -25.112 -0.353)
        (xy -25.125 -0.372)
        (xy -25.139 -0.392)
        (xy -25.151 -0.411)
        (xy -25.162 -0.431)
        (xy -25.173 -0.453)
        (xy -25.182 -0.474)
        (xy -25.188 -0.496)
        (xy -25.195 -0.519)
        (xy -25.2 -0.541)
        (xy -25.205 -0.563)
        (xy -25.208 -0.586)
        (xy -25.209 -0.61)
        (xy -25.211 -0.631)
        (xy -24.766 -0.631)
        (xy -24.766 -0.636)
        (xy -24.766 -0.637)
      )

      (stroke (width 0.001) (type solid)) (fill solid) (layer "B.Paste"))
    (fp_poly
      (pts
        (xy -24.766 0.633)
        (xy -25.211 0.632)
        (xy -25.209 0.611)
        (xy -25.208 0.587)
        (xy -25.205 0.564)
        (xy -25.2 0.542)
        (xy -25.195 0.52)
        (xy -25.188 0.497)
        (xy -25.182 0.475)
        (xy -25.173 0.454)
        (xy -25.162 0.432)
        (xy -25.151 0.412)
        (xy -25.139 0.393)
        (xy -25.125 0.373)
        (xy -25.112 0.354)
        (xy -25.096 0.338)
        (xy -25.08 0.32)
        (xy -25.063 0.304)
        (xy -25.046 0.289)
        (xy -25.028 0.276)
        (xy -25.008 0.263)
        (xy -24.988 0.249)
        (xy -24.968 0.238)
        (xy -24.947 0.229)
        (xy -24.926 0.219)
        (xy -24.903 0.212)
        (xy -24.881 0.205)
        (xy -24.86 0.201)
        (xy -24.836 0.196)
        (xy -24.813 0.192)
        (xy -24.79 0.191)
        (xy -24.766 0.19)
        (xy -24.743 0.191)
        (xy -24.718 0.192)
        (xy -24.695 0.196)
        (xy -24.673 0.201)
        (xy -24.65 0.205)
        (xy -24.627 0.212)
        (xy -24.607 0.22)
        (xy -24.584 0.229)
        (xy -24.563 0.239)
        (xy -24.543 0.25)
        (xy -24.523 0.263)
        (xy -24.503 0.276)
        (xy -24.485 0.289)
        (xy -24.467 0.304)
        (xy -24.45 0.32)
        (xy -24.435 0.338)
        (xy -24.419 0.355)
        (xy -24.406 0.373)
        (xy -24.392 0.394)
        (xy -24.38 0.413)
        (xy -24.369 0.433)
        (xy -24.359 0.455)
        (xy -24.351 0.476)
        (xy -24.342 0.497)
        (xy -24.336 0.521)
        (xy -24.33 0.543)
        (xy -24.325 0.565)
        (xy -24.322 0.588)
        (xy -24.322 0.612)
        (xy -24.32 0.635)
        (xy -24.322 0.659)
        (xy -24.322 0.683)
        (xy -24.325 0.705)
        (xy -24.33 0.728)
        (xy -24.336 0.75)
        (xy -24.342 0.774)
        (xy -24.351 0.795)
        (xy -24.359 0.816)
        (xy -24.369 0.837)
        (xy -24.38 0.857)
        (xy -24.392 0.877)
        (xy -24.406 0.898)
        (xy -24.419 0.916)
        (xy -24.435 0.934)
        (xy -24.45 0.95)
        (xy -24.467 0.966)
        (xy -24.485 0.981)
        (xy -24.503 0.995)
        (xy -24.523 1.008)
        (xy -24.543 1.02)
        (xy -24.563 1.031)
        (xy -24.584 1.043)
        (xy -24.607 1.051)
        (xy -24.627 1.059)
        (xy -24.65 1.065)
        (xy -24.673 1.071)
        (xy -24.695 1.075)
        (xy -24.718 1.079)
        (xy -24.743 1.079)
        (xy -24.766 1.081)
        (xy -24.79 1.079)
        (xy -24.813 1.079)
        (xy -24.836 1.075)
        (xy -24.86 1.071)
        (xy -24.881 1.065)
        (xy -24.903 1.059)
        (xy -24.926 1.051)
        (xy -24.947 1.043)
        (xy -24.968 1.033)
        (xy -24.988 1.021)
        (xy -25.008 1.008)
        (xy -25.028 0.995)
        (xy -25.046 0.981)
        (xy -25.063 0.966)
        (xy -25.08 0.95)
        (xy -25.096 0.934)
        (xy -25.112 0.917)
        (xy -25.125 0.898)
        (xy -25.139 0.878)
        (xy -25.151 0.858)
        (xy -25.162 0.838)
        (xy -25.173 0.817)
        (xy -25.182 0.796)
        (xy -25.188 0.774)
        (xy -25.195 0.751)
        (xy -25.2 0.729)
        (xy -25.205 0.706)
        (xy -25.208 0.684)
        (xy -25.209 0.66)
        (xy -25.211 0.637)
        (xy -24.766 0.637)
        (xy -24.766 0.632)
        (xy -24.766 0.633)
      )

      (stroke (width 0.001) (type solid)) (fill solid) (layer "B.Paste"))
    (fp_poly
      (pts
        (xy -23.496 -4.447)
        (xy -23.941 -4.446)
        (xy -23.939 -4.469)
        (xy -23.938 -4.493)
        (xy -23.935 -4.515)
        (xy -23.93 -4.538)
        (xy -23.926 -4.56)
        (xy -23.918 -4.583)
        (xy -23.912 -4.605)
        (xy -23.903 -4.626)
        (xy -23.892 -4.647)
        (xy -23.881 -4.668)
        (xy -23.868 -4.687)
        (xy -23.855 -4.706)
        (xy -23.842 -4.725)
        (xy -23.827 -4.743)
        (xy -23.81 -4.759)
        (xy -23.793 -4.775)
        (xy -23.776 -4.791)
        (xy -23.758 -4.804)
        (xy -23.738 -4.817)
        (xy -23.718 -4.831)
        (xy -23.698 -4.841)
        (xy -23.677 -4.852)
        (xy -23.656 -4.86)
        (xy -23.633 -4.868)
        (xy -23.612 -4.874)
        (xy -23.589 -4.879)
        (xy -23.566 -4.884)
        (xy -23.543 -4.887)
        (xy -23.519 -4.889)
        (xy -23.496 -4.889)
        (xy -23.473 -4.889)
        (xy -23.448 -4.887)
        (xy -23.426 -4.884)
        (xy -23.403 -4.879)
        (xy -23.38 -4.874)
        (xy -23.357 -4.868)
        (xy -23.336 -4.86)
        (xy -23.314 -4.852)
        (xy -23.293 -4.841)
        (xy -23.273 -4.829)
        (xy -23.253 -4.817)
        (xy -23.234 -4.804)
        (xy -23.215 -4.791)
        (xy -23.197 -4.775)
        (xy -23.18 -4.759)
        (xy -23.165 -4.743)
        (xy -23.15 -4.724)
        (xy -23.136 -4.706)
        (xy -23.122 -4.687)
        (xy -23.11 -4.668)
        (xy -23.099 -4.647)
        (xy -23.089 -4.626)
        (xy -23.08 -4.603)
        (xy -23.072 -4.583)
        (xy -23.066 -4.559)
        (xy -23.06 -4.538)
        (xy -23.055 -4.514)
        (xy -23.052 -4.491)
        (xy -23.051 -4.467)
        (xy -23.051 -4.445)
        (xy -23.051 -4.421)
        (xy -23.052 -4.397)
        (xy -23.055 -4.374)
        (xy -23.06 -4.352)
        (xy -23.066 -4.329)
        (xy -23.072 -4.307)
        (xy -23.08 -4.285)
        (xy -23.089 -4.264)
        (xy -23.099 -4.243)
        (xy -23.11 -4.222)
        (xy -23.122 -4.203)
        (xy -23.136 -4.182)
        (xy -23.15 -4.164)
        (xy -23.165 -4.147)
        (xy -23.18 -4.129)
        (xy -23.197 -4.113)
        (xy -23.215 -4.099)
        (xy -23.234 -4.084)
        (xy -23.253 -4.071)
        (xy -23.273 -4.059)
        (xy -23.293 -4.049)
        (xy -23.314 -4.038)
        (xy -23.336 -4.03)
        (xy -23.357 -4.022)
        (xy -23.38 -4.014)
        (xy -23.403 -4.009)
        (xy -23.426 -4.004)
        (xy -23.448 -4.001)
        (xy -23.473 -4.001)
        (xy -23.496 -3.999)
        (xy -23.519 -4.001)
        (xy -23.543 -4.001)
        (xy -23.566 -4.004)
        (xy -23.589 -4.009)
        (xy -23.612 -4.014)
        (xy -23.633 -4.022)
        (xy -23.656 -4.028)
        (xy -23.677 -4.038)
        (xy -23.698 -4.047)
        (xy -23.718 -4.059)
        (xy -23.738 -4.071)
        (xy -23.758 -4.084)
        (xy -23.776 -4.099)
        (xy -23.793 -4.113)
        (xy -23.81 -4.129)
        (xy -23.827 -4.147)
        (xy -23.842 -4.163)
        (xy -23.855 -4.182)
        (xy -23.868 -4.201)
        (xy -23.881 -4.222)
        (xy -23.892 -4.241)
        (xy -23.903 -4.262)
        (xy -23.912 -4.285)
        (xy -23.918 -4.307)
        (xy -23.926 -4.328)
        (xy -23.93 -4.35)
        (xy -23.935 -4.373)
        (xy -23.938 -4.397)
        (xy -23.939 -4.421)
        (xy -23.941 -4.442)
        (xy -23.496 -4.442)
        (xy -23.496 -4.446)
        (xy -23.496 -4.447)
      )

      (stroke (width 0.001) (type solid)) (fill solid) (layer "B.Paste"))
    (fp_poly
      (pts
        (xy -23.496 -1.907)
        (xy -23.941 -1.906)
        (xy -23.939 -1.929)
        (xy -23.938 -1.953)
        (xy -23.935 -1.975)
        (xy -23.93 -1.999)
        (xy -23.926 -2.02)
        (xy -23.918 -2.043)
        (xy -23.912 -2.064)
        (xy -23.903 -2.087)
        (xy -23.892 -2.108)
        (xy -23.881 -2.128)
        (xy -23.868 -2.148)
        (xy -23.855 -2.166)
        (xy -23.842 -2.185)
        (xy -23.827 -2.202)
        (xy -23.81 -2.22)
        (xy -23.793 -2.236)
        (xy -23.776 -2.25)
        (xy -23.758 -2.265)
        (xy -23.738 -2.277)
        (xy -23.718 -2.29)
        (xy -23.698 -2.301)
        (xy -23.677 -2.311)
        (xy -23.656 -2.321)
        (xy -23.633 -2.327)
        (xy -23.612 -2.334)
        (xy -23.589 -2.339)
        (xy -23.566 -2.345)
        (xy -23.543 -2.347)
        (xy -23.519 -2.349)
        (xy -23.496 -2.35)
        (xy -23.473 -2.349)
        (xy -23.448 -2.347)
        (xy -23.426 -2.345)
        (xy -23.403 -2.339)
        (xy -23.38 -2.334)
        (xy -23.357 -2.327)
        (xy -23.336 -2.319)
        (xy -23.314 -2.311)
        (xy -23.293 -2.301)
        (xy -23.273 -2.289)
        (xy -23.253 -2.277)
        (xy -23.234 -2.265)
        (xy -23.215 -2.25)
        (xy -23.197 -2.236)
        (xy -23.18 -2.22)
        (xy -23.165 -2.202)
        (xy -23.15 -2.185)
        (xy -23.136 -2.166)
        (xy -23.122 -2.146)
        (xy -23.11 -2.126)
        (xy -23.099 -2.107)
        (xy -23.089 -2.085)
        (xy -23.08 -2.064)
        (xy -23.072 -2.043)
        (xy -23.066 -2.019)
        (xy -23.06 -1.997)
        (xy -23.055 -1.975)
        (xy -23.052 -1.951)
        (xy -23.051 -1.927)
        (xy -23.051 -1.904)
        (xy -23.051 -1.881)
        (xy -23.052 -1.858)
        (xy -23.055 -1.834)
        (xy -23.06 -1.812)
        (xy -23.066 -1.789)
        (xy -23.072 -1.766)
        (xy -23.08 -1.745)
        (xy -23.089 -1.723)
        (xy -23.099 -1.703)
        (xy -23.11 -1.683)
        (xy -23.122 -1.662)
        (xy -23.136 -1.642)
        (xy -23.15 -1.624)
        (xy -23.165 -1.606)
        (xy -23.18 -1.59)
        (xy -23.197 -1.574)
        (xy -23.215 -1.558)
        (xy -23.234 -1.544)
        (xy -23.253 -1.531)
        (xy -23.273 -1.519)
        (xy -23.293 -1.508)
        (xy -23.314 -1.497)
        (xy -23.336 -1.489)
        (xy -23.357 -1.481)
        (xy -23.38 -1.475)
        (xy -23.403 -1.469)
        (xy -23.426 -1.465)
        (xy -23.448 -1.461)
        (xy -23.473 -1.461)
        (xy -23.496 -1.459)
        (xy -23.519 -1.461)
        (xy -23.543 -1.461)
        (xy -23.566 -1.465)
        (xy -23.589 -1.469)
        (xy -23.612 -1.475)
        (xy -23.633 -1.481)
        (xy -23.656 -1.489)
        (xy -23.677 -1.497)
        (xy -23.698 -1.507)
        (xy -23.718 -1.518)
        (xy -23.738 -1.531)
        (xy -23.758 -1.544)
        (xy -23.776 -1.558)
        (xy -23.793 -1.574)
        (xy -23.81 -1.59)
        (xy -23.827 -1.606)
        (xy -23.842 -1.624)
        (xy -23.855 -1.642)
        (xy -23.868 -1.661)
        (xy -23.881 -1.681)
        (xy -23.892 -1.701)
        (xy -23.903 -1.723)
        (xy -23.912 -1.745)
        (xy -23.918 -1.766)
        (xy -23.926 -1.788)
        (xy -23.93 -1.81)
        (xy -23.935 -1.834)
        (xy -23.938 -1.856)
        (xy -23.939 -1.88)
        (xy -23.941 -1.902)
        (xy -23.496 -1.902)
        (xy -23.496 -1.906)
        (xy -23.496 -1.907)
      )

      (stroke (width 0.001) (type solid)) (fill solid) (layer "B.Paste"))
    (fp_poly
      (pts
        (xy -23.496 -0.637)
        (xy -23.941 -0.636)
        (xy -23.939 -0.659)
        (xy -23.938 -0.683)
        (xy -23.935 -0.705)
        (xy -23.93 -0.728)
        (xy -23.926 -0.75)
        (xy -23.918 -0.773)
        (xy -23.912 -0.795)
        (xy -23.903 -0.816)
        (xy -23.892 -0.837)
        (xy -23.881 -0.857)
        (xy -23.868 -0.877)
        (xy -23.855 -0.897)
        (xy -23.842 -0.916)
        (xy -23.827 -0.933)
        (xy -23.81 -0.949)
        (xy -23.793 -0.965)
        (xy -23.776 -0.98)
        (xy -23.758 -0.994)
        (xy -23.738 -1.007)
        (xy -23.718 -1.02)
        (xy -23.698 -1.032)
        (xy -23.677 -1.042)
        (xy -23.656 -1.05)
        (xy -23.633 -1.058)
        (xy -23.612 -1.064)
        (xy -23.589 -1.07)
        (xy -23.566 -1.074)
        (xy -23.543 -1.078)
        (xy -23.519 -1.078)
        (xy -23.496 -1.08)
        (xy -23.473 -1.078)
        (xy -23.448 -1.078)
        (xy -23.426 -1.074)
        (xy -23.403 -1.07)
        (xy -23.38 -1.064)
        (xy -23.357 -1.058)
        (xy -23.336 -1.05)
        (xy -23.314 -1.042)
        (xy -23.293 -1.03)
        (xy -23.273 -1.019)
        (xy -23.253 -1.007)
        (xy -23.234 -0.994)
        (xy -23.215 -0.98)
        (xy -23.197 -0.965)
        (xy -23.18 -0.949)
        (xy -23.165 -0.933)
        (xy -23.15 -0.915)
        (xy -23.136 -0.897)
        (xy -23.122 -0.876)
        (xy -23.11 -0.856)
        (xy -23.099 -0.836)
        (xy -23.089 -0.815)
        (xy -23.08 -0.794)
        (xy -23.072 -0.773)
        (xy -23.066 -0.749)
        (xy -23.06 -0.727)
        (xy -23.055 -0.704)
        (xy -23.052 -0.682)
        (xy -23.051 -0.658)
        (xy -23.051 -0.634)
        (xy -23.051 -0.611)
        (xy -23.052 -0.587)
        (xy -23.055 -0.564)
        (xy -23.06 -0.542)
        (xy -23.066 -0.52)
        (xy -23.072 -0.496)
        (xy -23.08 -0.475)
        (xy -23.089 -0.454)
        (xy -23.099 -0.432)
        (xy -23.11 -0.412)
        (xy -23.122 -0.393)
        (xy -23.136 -0.372)
        (xy -23.15 -0.354)
        (xy -23.165 -0.337)
        (xy -23.18 -0.32)
        (xy -23.197 -0.303)
        (xy -23.215 -0.288)
        (xy -23.234 -0.275)
        (xy -23.253 -0.262)
        (xy -23.273 -0.249)
        (xy -23.293 -0.238)
        (xy -23.314 -0.228)
        (xy -23.336 -0.219)
        (xy -23.357 -0.211)
        (xy -23.38 -0.204)
        (xy -23.403 -0.2)
        (xy -23.426 -0.195)
        (xy -23.448 -0.192)
        (xy -23.473 -0.19)
        (xy -23.496 -0.189)
        (xy -23.519 -0.19)
        (xy -23.543 -0.192)
        (xy -23.566 -0.195)
        (xy -23.589 -0.2)
        (xy -23.612 -0.204)
        (xy -23.633 -0.211)
        (xy -23.656 -0.218)
        (xy -23.677 -0.228)
        (xy -23.698 -0.237)
        (xy -23.718 -0.248)
        (xy -23.738 -0.262)
        (xy -23.758 -0.275)
        (xy -23.776 -0.288)
        (xy -23.793 -0.303)
        (xy -23.81 -0.32)
        (xy -23.827 -0.337)
        (xy -23.842 -0.353)
        (xy -23.855 -0.372)
        (xy -23.868 -0.392)
        (xy -23.881 -0.411)
        (xy -23.892 -0.431)
        (xy -23.903 -0.453)
        (xy -23.912 -0.474)
        (xy -23.918 -0.496)
        (xy -23.926 -0.519)
        (xy -23.93 -0.541)
        (xy -23.935 -0.563)
        (xy -23.938 -0.586)
        (xy -23.939 -0.61)
        (xy -23.941 -0.631)
        (xy -23.496 -0.631)
        (xy -23.496 -0.636)
        (xy -23.496 -0.637)
      )

      (stroke (width 0.001) (type solid)) (fill solid) (layer "B.Paste"))
    (fp_poly
      (pts
        (xy -23.496 0.633)
        (xy -23.941 0.632)
        (xy -23.939 0.611)
        (xy -23.938 0.587)
        (xy -23.935 0.564)
        (xy -23.93 0.542)
        (xy -23.926 0.52)
        (xy -23.918 0.497)
        (xy -23.912 0.475)
        (xy -23.903 0.454)
        (xy -23.892 0.432)
        (xy -23.881 0.412)
        (xy -23.868 0.393)
        (xy -23.855 0.373)
        (xy -23.842 0.354)
        (xy -23.827 0.338)
        (xy -23.81 0.32)
        (xy -23.793 0.304)
        (xy -23.776 0.289)
        (xy -23.758 0.276)
        (xy -23.738 0.263)
        (xy -23.718 0.249)
        (xy -23.698 0.238)
        (xy -23.677 0.229)
        (xy -23.656 0.219)
        (xy -23.633 0.212)
        (xy -23.612 0.205)
        (xy -23.589 0.201)
        (xy -23.566 0.196)
        (xy -23.543 0.192)
        (xy -23.519 0.191)
        (xy -23.496 0.19)
        (xy -23.473 0.191)
        (xy -23.448 0.192)
        (xy -23.426 0.196)
        (xy -23.403 0.201)
        (xy -23.38 0.205)
        (xy -23.357 0.212)
        (xy -23.336 0.22)
        (xy -23.314 0.229)
        (xy -23.293 0.239)
        (xy -23.273 0.25)
        (xy -23.253 0.263)
        (xy -23.234 0.276)
        (xy -23.215 0.289)
        (xy -23.197 0.304)
        (xy -23.18 0.32)
        (xy -23.165 0.338)
        (xy -23.15 0.355)
        (xy -23.136 0.373)
        (xy -23.122 0.394)
        (xy -23.11 0.413)
        (xy -23.099 0.433)
        (xy -23.089 0.455)
        (xy -23.08 0.476)
        (xy -23.072 0.497)
        (xy -23.066 0.521)
        (xy -23.06 0.543)
        (xy -23.055 0.565)
        (xy -23.052 0.588)
        (xy -23.051 0.612)
        (xy -23.051 0.635)
        (xy -23.051 0.659)
        (xy -23.052 0.683)
        (xy -23.055 0.705)
        (xy -23.06 0.728)
        (xy -23.066 0.75)
        (xy -23.072 0.774)
        (xy -23.08 0.795)
        (xy -23.089 0.816)
        (xy -23.099 0.837)
        (xy -23.11 0.857)
        (xy -23.122 0.877)
        (xy -23.136 0.898)
        (xy -23.15 0.916)
        (xy -23.165 0.934)
        (xy -23.18 0.95)
        (xy -23.197 0.966)
        (xy -23.215 0.981)
        (xy -23.234 0.995)
        (xy -23.253 1.008)
        (xy -23.273 1.02)
        (xy -23.293 1.031)
        (xy -23.314 1.043)
        (xy -23.336 1.051)
        (xy -23.357 1.059)
        (xy -23.38 1.065)
        (xy -23.403 1.071)
        (xy -23.426 1.075)
        (xy -23.448 1.079)
        (xy -23.473 1.079)
        (xy -23.496 1.081)
        (xy -23.519 1.079)
        (xy -23.543 1.079)
        (xy -23.566 1.075)
        (xy -23.589 1.071)
        (xy -23.612 1.065)
        (xy -23.633 1.059)
        (xy -23.656 1.051)
        (xy -23.677 1.043)
        (xy -23.698 1.033)
        (xy -23.718 1.021)
        (xy -23.738 1.008)
        (xy -23.758 0.995)
        (xy -23.776 0.981)
        (xy -23.793 0.966)
        (xy -23.81 0.95)
        (xy -23.827 0.934)
        (xy -23.842 0.917)
        (xy -23.855 0.898)
        (xy -23.868 0.878)
        (xy -23.881 0.858)
        (xy -23.892 0.838)
        (xy -23.903 0.817)
        (xy -23.912 0.796)
        (xy -23.918 0.774)
        (xy -23.926 0.751)
        (xy -23.93 0.729)
        (xy -23.935 0.706)
        (xy -23.938 0.684)
        (xy -23.939 0.66)
        (xy -23.941 0.637)
        (xy -23.496 0.637)
        (xy -23.496 0.632)
        (xy -23.496 0.633)
      )

      (stroke (width 0.001) (type solid)) (fill solid) (layer "B.Paste"))
    (fp_poly
      (pts
        (xy -22.226 -4.447)
        (xy -22.671 -4.446)
        (xy -22.67 -4.469)
        (xy -22.668 -4.493)
        (xy -22.665 -4.515)
        (xy -22.66 -4.538)
        (xy -22.656 -4.56)
        (xy -22.648 -4.583)
        (xy -22.641 -4.605)
        (xy -22.633 -4.626)
        (xy -22.622 -4.647)
        (xy -22.612 -4.668)
        (xy -22.598 -4.687)
        (xy -22.586 -4.706)
        (xy -22.572 -4.725)
        (xy -22.557 -4.743)
        (xy -22.54 -4.759)
        (xy -22.523 -4.775)
        (xy -22.506 -4.791)
        (xy -22.487 -4.804)
        (xy -22.468 -4.817)
        (xy -22.448 -4.831)
        (xy -22.429 -4.841)
        (xy -22.407 -4.852)
        (xy -22.386 -4.86)
        (xy -22.363 -4.868)
        (xy -22.342 -4.874)
        (xy -22.319 -4.879)
        (xy -22.296 -4.884)
        (xy -22.273 -4.887)
        (xy -22.249 -4.889)
        (xy -22.226 -4.889)
        (xy -22.203 -4.889)
        (xy -22.179 -4.887)
        (xy -22.156 -4.884)
        (xy -22.133 -4.879)
        (xy -22.11 -4.874)
        (xy -22.087 -4.868)
        (xy -22.066 -4.86)
        (xy -22.045 -4.852)
        (xy -22.023 -4.841)
        (xy -22.003 -4.829)
        (xy -21.984 -4.817)
        (xy -21.964 -4.804)
        (xy -21.945 -4.791)
        (xy -21.927 -4.775)
        (xy -21.91 -4.759)
        (xy -21.894 -4.743)
        (xy -21.88 -4.724)
        (xy -21.865 -4.706)
        (xy -21.852 -4.687)
        (xy -21.84 -4.668)
        (xy -21.83 -4.647)
        (xy -21.819 -4.626)
        (xy -21.81 -4.603)
        (xy -21.802 -4.583)
        (xy -21.796 -4.559)
        (xy -21.79 -4.538)
        (xy -21.785 -4.514)
        (xy -21.782 -4.491)
        (xy -21.781 -4.467)
        (xy -21.781 -4.445)
        (xy -21.781 -4.421)
        (xy -21.782 -4.397)
        (xy -21.785 -4.374)
        (xy -21.79 -4.352)
        (xy -21.796 -4.329)
        (xy -21.802 -4.307)
        (xy -21.81 -4.285)
        (xy -21.819 -4.264)
        (xy -21.83 -4.243)
        (xy -21.84 -4.222)
        (xy -21.852 -4.203)
        (xy -21.865 -4.182)
        (xy -21.88 -4.164)
        (xy -21.894 -4.147)
        (xy -21.91 -4.129)
        (xy -21.927 -4.113)
        (xy -21.945 -4.099)
        (xy -21.964 -4.084)
        (xy -21.984 -4.071)
        (xy -22.003 -4.059)
        (xy -22.023 -4.049)
        (xy -22.045 -4.038)
        (xy -22.066 -4.03)
        (xy -22.087 -4.022)
        (xy -22.11 -4.014)
        (xy -22.133 -4.009)
        (xy -22.156 -4.004)
        (xy -22.179 -4.001)
        (xy -22.203 -4.001)
        (xy -22.226 -3.999)
        (xy -22.249 -4.001)
        (xy -22.273 -4.001)
        (xy -22.296 -4.004)
        (xy -22.319 -4.009)
        (xy -22.342 -4.014)
        (xy -22.363 -4.022)
        (xy -22.386 -4.028)
        (xy -22.407 -4.038)
        (xy -22.429 -4.047)
        (xy -22.448 -4.059)
        (xy -22.468 -4.071)
        (xy -22.487 -4.084)
        (xy -22.506 -4.099)
        (xy -22.523 -4.113)
        (xy -22.54 -4.129)
        (xy -22.557 -4.147)
        (xy -22.572 -4.163)
        (xy -22.586 -4.182)
        (xy -22.598 -4.201)
        (xy -22.612 -4.222)
        (xy -22.622 -4.241)
        (xy -22.633 -4.262)
        (xy -22.641 -4.285)
        (xy -22.648 -4.307)
        (xy -22.656 -4.328)
        (xy -22.66 -4.35)
        (xy -22.665 -4.373)
        (xy -22.668 -4.397)
        (xy -22.67 -4.421)
        (xy -22.671 -4.442)
        (xy -22.226 -4.442)
        (xy -22.226 -4.446)
        (xy -22.226 -4.447)
      )

      (stroke (width 0.001) (type solid)) (fill solid) (layer "B.Paste"))
    (fp_poly
      (pts
        (xy -22.226 -1.907)
        (xy -22.671 -1.906)
        (xy -22.67 -1.929)
        (xy -22.668 -1.953)
        (xy -22.665 -1.975)
        (xy -22.66 -1.999)
        (xy -22.656 -2.02)
        (xy -22.648 -2.043)
        (xy -22.641 -2.064)
        (xy -22.633 -2.087)
        (xy -22.622 -2.108)
        (xy -22.612 -2.128)
        (xy -22.598 -2.148)
        (xy -22.586 -2.166)
        (xy -22.572 -2.185)
        (xy -22.557 -2.202)
        (xy -22.54 -2.22)
        (xy -22.523 -2.236)
        (xy -22.506 -2.25)
        (xy -22.487 -2.265)
        (xy -22.468 -2.277)
        (xy -22.448 -2.29)
        (xy -22.429 -2.301)
        (xy -22.407 -2.311)
        (xy -22.386 -2.321)
        (xy -22.363 -2.327)
        (xy -22.342 -2.334)
        (xy -22.319 -2.339)
        (xy -22.296 -2.345)
        (xy -22.273 -2.347)
        (xy -22.249 -2.349)
        (xy -22.226 -2.35)
        (xy -22.203 -2.349)
        (xy -22.179 -2.347)
        (xy -22.156 -2.345)
        (xy -22.133 -2.339)
        (xy -22.11 -2.334)
        (xy -22.087 -2.327)
        (xy -22.066 -2.319)
        (xy -22.045 -2.311)
        (xy -22.023 -2.301)
        (xy -22.003 -2.289)
        (xy -21.984 -2.277)
        (xy -21.964 -2.265)
        (xy -21.945 -2.25)
        (xy -21.927 -2.236)
        (xy -21.91 -2.22)
        (xy -21.894 -2.202)
        (xy -21.88 -2.185)
        (xy -21.865 -2.166)
        (xy -21.852 -2.146)
        (xy -21.84 -2.126)
        (xy -21.83 -2.107)
        (xy -21.819 -2.085)
        (xy -21.81 -2.064)
        (xy -21.802 -2.043)
        (xy -21.796 -2.019)
        (xy -21.79 -1.997)
        (xy -21.785 -1.975)
        (xy -21.782 -1.951)
        (xy -21.781 -1.927)
        (xy -21.781 -1.904)
        (xy -21.781 -1.881)
        (xy -21.782 -1.858)
        (xy -21.785 -1.834)
        (xy -21.79 -1.812)
        (xy -21.796 -1.789)
        (xy -21.802 -1.766)
        (xy -21.81 -1.745)
        (xy -21.819 -1.723)
        (xy -21.83 -1.703)
        (xy -21.84 -1.683)
        (xy -21.852 -1.662)
        (xy -21.865 -1.642)
        (xy -21.88 -1.624)
        (xy -21.894 -1.606)
        (xy -21.91 -1.59)
        (xy -21.927 -1.574)
        (xy -21.945 -1.558)
        (xy -21.964 -1.544)
        (xy -21.984 -1.531)
        (xy -22.003 -1.519)
        (xy -22.023 -1.508)
        (xy -22.045 -1.497)
        (xy -22.066 -1.489)
        (xy -22.087 -1.481)
        (xy -22.11 -1.475)
        (xy -22.133 -1.469)
        (xy -22.156 -1.465)
        (xy -22.179 -1.461)
        (xy -22.203 -1.461)
        (xy -22.226 -1.459)
        (xy -22.249 -1.461)
        (xy -22.273 -1.461)
        (xy -22.296 -1.465)
        (xy -22.319 -1.469)
        (xy -22.342 -1.475)
        (xy -22.363 -1.481)
        (xy -22.386 -1.489)
        (xy -22.407 -1.497)
        (xy -22.429 -1.507)
        (xy -22.448 -1.518)
        (xy -22.468 -1.531)
        (xy -22.487 -1.544)
        (xy -22.506 -1.558)
        (xy -22.523 -1.574)
        (xy -22.54 -1.59)
        (xy -22.557 -1.606)
        (xy -22.572 -1.624)
        (xy -22.586 -1.642)
        (xy -22.598 -1.661)
        (xy -22.612 -1.681)
        (xy -22.622 -1.701)
        (xy -22.633 -1.723)
        (xy -22.641 -1.745)
        (xy -22.648 -1.766)
        (xy -22.656 -1.788)
        (xy -22.66 -1.81)
        (xy -22.665 -1.834)
        (xy -22.668 -1.856)
        (xy -22.67 -1.88)
        (xy -22.671 -1.902)
        (xy -22.226 -1.902)
        (xy -22.226 -1.906)
        (xy -22.226 -1.907)
      )

      (stroke (width 0.001) (type solid)) (fill solid) (layer "B.Paste"))
    (fp_poly
      (pts
        (xy -22.226 -0.637)
        (xy -22.671 -0.636)
        (xy -22.67 -0.659)
        (xy -22.668 -0.683)
        (xy -22.665 -0.705)
        (xy -22.66 -0.728)
        (xy -22.656 -0.75)
        (xy -22.648 -0.773)
        (xy -22.641 -0.795)
        (xy -22.633 -0.816)
        (xy -22.622 -0.837)
        (xy -22.612 -0.857)
        (xy -22.598 -0.877)
        (xy -22.586 -0.897)
        (xy -22.572 -0.916)
        (xy -22.557 -0.933)
        (xy -22.54 -0.949)
        (xy -22.523 -0.965)
        (xy -22.506 -0.98)
        (xy -22.487 -0.994)
        (xy -22.468 -1.007)
        (xy -22.448 -1.02)
        (xy -22.429 -1.032)
        (xy -22.407 -1.042)
        (xy -22.386 -1.05)
        (xy -22.363 -1.058)
        (xy -22.342 -1.064)
        (xy -22.319 -1.07)
        (xy -22.296 -1.074)
        (xy -22.273 -1.078)
        (xy -22.249 -1.078)
        (xy -22.226 -1.08)
        (xy -22.203 -1.078)
        (xy -22.179 -1.078)
        (xy -22.156 -1.074)
        (xy -22.133 -1.07)
        (xy -22.11 -1.064)
        (xy -22.087 -1.058)
        (xy -22.066 -1.05)
        (xy -22.045 -1.042)
        (xy -22.023 -1.03)
        (xy -22.003 -1.019)
        (xy -21.984 -1.007)
        (xy -21.964 -0.994)
        (xy -21.945 -0.98)
        (xy -21.927 -0.965)
        (xy -21.91 -0.949)
        (xy -21.894 -0.933)
        (xy -21.88 -0.915)
        (xy -21.865 -0.897)
        (xy -21.852 -0.876)
        (xy -21.84 -0.856)
        (xy -21.83 -0.836)
        (xy -21.819 -0.815)
        (xy -21.81 -0.794)
        (xy -21.802 -0.773)
        (xy -21.796 -0.749)
        (xy -21.79 -0.727)
        (xy -21.785 -0.704)
        (xy -21.782 -0.682)
        (xy -21.781 -0.658)
        (xy -21.781 -0.634)
        (xy -21.781 -0.611)
        (xy -21.782 -0.587)
        (xy -21.785 -0.564)
        (xy -21.79 -0.542)
        (xy -21.796 -0.52)
        (xy -21.802 -0.496)
        (xy -21.81 -0.475)
        (xy -21.819 -0.454)
        (xy -21.83 -0.432)
        (xy -21.84 -0.412)
        (xy -21.852 -0.393)
        (xy -21.865 -0.372)
        (xy -21.88 -0.354)
        (xy -21.894 -0.337)
        (xy -21.91 -0.32)
        (xy -21.927 -0.303)
        (xy -21.945 -0.288)
        (xy -21.964 -0.275)
        (xy -21.984 -0.262)
        (xy -22.003 -0.249)
        (xy -22.023 -0.238)
        (xy -22.045 -0.228)
        (xy -22.066 -0.219)
        (xy -22.087 -0.211)
        (xy -22.11 -0.204)
        (xy -22.133 -0.2)
        (xy -22.156 -0.195)
        (xy -22.179 -0.192)
        (xy -22.203 -0.19)
        (xy -22.226 -0.189)
        (xy -22.249 -0.19)
        (xy -22.273 -0.192)
        (xy -22.296 -0.195)
        (xy -22.319 -0.2)
        (xy -22.342 -0.204)
        (xy -22.363 -0.211)
        (xy -22.386 -0.218)
        (xy -22.407 -0.228)
        (xy -22.429 -0.237)
        (xy -22.448 -0.248)
        (xy -22.468 -0.262)
        (xy -22.487 -0.275)
        (xy -22.506 -0.288)
        (xy -22.523 -0.303)
        (xy -22.54 -0.32)
        (xy -22.557 -0.337)
        (xy -22.572 -0.353)
        (xy -22.586 -0.372)
        (xy -22.598 -0.392)
        (xy -22.612 -0.411)
        (xy -22.622 -0.431)
        (xy -22.633 -0.453)
        (xy -22.641 -0.474)
        (xy -22.648 -0.496)
        (xy -22.656 -0.519)
        (xy -22.66 -0.541)
        (xy -22.665 -0.563)
        (xy -22.668 -0.586)
        (xy -22.67 -0.61)
        (xy -22.671 -0.631)
        (xy -22.226 -0.631)
        (xy -22.226 -0.636)
        (xy -22.226 -0.637)
      )

      (stroke (width 0.001) (type solid)) (fill solid) (layer "B.Paste"))
    (fp_poly
      (pts
        (xy -22.226 0.633)
        (xy -22.671 0.632)
        (xy -22.67 0.611)
        (xy -22.668 0.587)
        (xy -22.665 0.564)
        (xy -22.66 0.542)
        (xy -22.656 0.52)
        (xy -22.648 0.497)
        (xy -22.641 0.475)
        (xy -22.633 0.454)
        (xy -22.622 0.432)
        (xy -22.612 0.412)
        (xy -22.598 0.393)
        (xy -22.586 0.373)
        (xy -22.572 0.354)
        (xy -22.557 0.338)
        (xy -22.54 0.32)
        (xy -22.523 0.304)
        (xy -22.506 0.289)
        (xy -22.487 0.276)
        (xy -22.468 0.263)
        (xy -22.448 0.249)
        (xy -22.429 0.238)
        (xy -22.407 0.229)
        (xy -22.386 0.219)
        (xy -22.363 0.212)
        (xy -22.342 0.205)
        (xy -22.319 0.201)
        (xy -22.296 0.196)
        (xy -22.273 0.192)
        (xy -22.249 0.191)
        (xy -22.226 0.19)
        (xy -22.203 0.191)
        (xy -22.179 0.192)
        (xy -22.156 0.196)
        (xy -22.133 0.201)
        (xy -22.11 0.205)
        (xy -22.087 0.212)
        (xy -22.066 0.22)
        (xy -22.045 0.229)
        (xy -22.023 0.239)
        (xy -22.003 0.25)
        (xy -21.984 0.263)
        (xy -21.964 0.276)
        (xy -21.945 0.289)
        (xy -21.927 0.304)
        (xy -21.91 0.32)
        (xy -21.894 0.338)
        (xy -21.88 0.355)
        (xy -21.865 0.373)
        (xy -21.852 0.394)
        (xy -21.84 0.413)
        (xy -21.83 0.433)
        (xy -21.819 0.455)
        (xy -21.81 0.476)
        (xy -21.802 0.497)
        (xy -21.796 0.521)
        (xy -21.79 0.543)
        (xy -21.785 0.565)
        (xy -21.782 0.588)
        (xy -21.781 0.612)
        (xy -21.781 0.635)
        (xy -21.781 0.659)
        (xy -21.782 0.683)
        (xy -21.785 0.705)
        (xy -21.79 0.728)
        (xy -21.796 0.75)
        (xy -21.802 0.774)
        (xy -21.81 0.795)
        (xy -21.819 0.816)
        (xy -21.83 0.837)
        (xy -21.84 0.857)
        (xy -21.852 0.877)
        (xy -21.865 0.898)
        (xy -21.88 0.916)
        (xy -21.894 0.934)
        (xy -21.91 0.95)
        (xy -21.927 0.966)
        (xy -21.945 0.981)
        (xy -21.964 0.995)
        (xy -21.984 1.008)
        (xy -22.003 1.02)
        (xy -22.023 1.031)
        (xy -22.045 1.043)
        (xy -22.066 1.051)
        (xy -22.087 1.059)
        (xy -22.11 1.065)
        (xy -22.133 1.071)
        (xy -22.156 1.075)
        (xy -22.179 1.079)
        (xy -22.203 1.079)
        (xy -22.226 1.081)
        (xy -22.249 1.079)
        (xy -22.273 1.079)
        (xy -22.296 1.075)
        (xy -22.319 1.071)
        (xy -22.342 1.065)
        (xy -22.363 1.059)
        (xy -22.386 1.051)
        (xy -22.407 1.043)
        (xy -22.429 1.033)
        (xy -22.448 1.021)
        (xy -22.468 1.008)
        (xy -22.487 0.995)
        (xy -22.506 0.981)
        (xy -22.523 0.966)
        (xy -22.54 0.95)
        (xy -22.557 0.934)
        (xy -22.572 0.917)
        (xy -22.586 0.898)
        (xy -22.598 0.878)
        (xy -22.612 0.858)
        (xy -22.622 0.838)
        (xy -22.633 0.817)
        (xy -22.641 0.796)
        (xy -22.648 0.774)
        (xy -22.656 0.751)
        (xy -22.66 0.729)
        (xy -22.665 0.706)
        (xy -22.668 0.684)
        (xy -22.67 0.66)
        (xy -22.671 0.637)
        (xy -22.226 0.637)
        (xy -22.226 0.632)
        (xy -22.226 0.633)
      )

      (stroke (width 0.001) (type solid)) (fill solid) (layer "B.Paste"))
    (fp_poly
      (pts
        (xy -20.955 -4.447)
        (xy -21.4 -4.446)
        (xy -21.4 -4.469)
        (xy -21.398 -4.493)
        (xy -21.395 -4.515)
        (xy -21.391 -4.538)
        (xy -21.386 -4.56)
        (xy -21.378 -4.583)
        (xy -21.371 -4.605)
        (xy -21.362 -4.626)
        (xy -21.352 -4.647)
        (xy -21.342 -4.668)
        (xy -21.328 -4.687)
        (xy -21.316 -4.706)
        (xy -21.301 -4.725)
        (xy -21.287 -4.743)
        (xy -21.27 -4.759)
        (xy -21.253 -4.775)
        (xy -21.237 -4.791)
        (xy -21.217 -4.804)
        (xy -21.198 -4.817)
        (xy -21.179 -4.831)
        (xy -21.159 -4.841)
        (xy -21.138 -4.852)
        (xy -21.115 -4.86)
        (xy -21.093 -4.868)
        (xy -21.072 -4.874)
        (xy -21.049 -4.879)
        (xy -21.026 -4.884)
        (xy -21.003 -4.887)
        (xy -20.979 -4.889)
        (xy -20.955 -4.889)
        (xy -20.932 -4.889)
        (xy -20.909 -4.887)
        (xy -20.886 -4.884)
        (xy -20.862 -4.879)
        (xy -20.84 -4.874)
        (xy -20.817 -4.868)
        (xy -20.796 -4.86)
        (xy -20.775 -4.852)
        (xy -20.753 -4.841)
        (xy -20.734 -4.829)
        (xy -20.714 -4.817)
        (xy -20.694 -4.804)
        (xy -20.676 -4.791)
        (xy -20.657 -4.775)
        (xy -20.641 -4.759)
        (xy -20.624 -4.743)
        (xy -20.61 -4.724)
        (xy -20.595 -4.706)
        (xy -20.583 -4.687)
        (xy -20.57 -4.668)
        (xy -20.56 -4.647)
        (xy -20.548 -4.626)
        (xy -20.54 -4.603)
        (xy -20.532 -4.583)
        (xy -20.525 -4.559)
        (xy -20.52 -4.538)
        (xy -20.516 -4.514)
        (xy -20.513 -4.491)
        (xy -20.511 -4.467)
        (xy -20.511 -4.445)
        (xy -20.511 -4.421)
        (xy -20.513 -4.397)
        (xy -20.516 -4.374)
        (xy -20.52 -4.352)
        (xy -20.525 -4.329)
        (xy -20.532 -4.307)
        (xy -20.54 -4.285)
        (xy -20.548 -4.264)
        (xy -20.56 -4.243)
        (xy -20.57 -4.222)
        (xy -20.583 -4.203)
        (xy -20.595 -4.182)
        (xy -20.61 -4.164)
        (xy -20.624 -4.147)
        (xy -20.641 -4.129)
        (xy -20.657 -4.113)
        (xy -20.676 -4.099)
        (xy -20.694 -4.084)
        (xy -20.714 -4.071)
        (xy -20.734 -4.059)
        (xy -20.753 -4.049)
        (xy -20.775 -4.038)
        (xy -20.796 -4.03)
        (xy -20.817 -4.022)
        (xy -20.84 -4.014)
        (xy -20.862 -4.009)
        (xy -20.886 -4.004)
        (xy -20.909 -4.001)
        (xy -20.932 -4.001)
        (xy -20.955 -3.999)
        (xy -20.979 -4.001)
        (xy -21.003 -4.001)
        (xy -21.026 -4.004)
        (xy -21.049 -4.009)
        (xy -21.072 -4.014)
        (xy -21.093 -4.022)
        (xy -21.115 -4.028)
        (xy -21.138 -4.038)
        (xy -21.159 -4.047)
        (xy -21.179 -4.059)
        (xy -21.198 -4.071)
        (xy -21.217 -4.084)
        (xy -21.237 -4.099)
        (xy -21.253 -4.113)
        (xy -21.27 -4.129)
        (xy -21.287 -4.147)
        (xy -21.301 -4.163)
        (xy -21.316 -4.182)
        (xy -21.328 -4.201)
        (xy -21.342 -4.222)
        (xy -21.352 -4.241)
        (xy -21.362 -4.262)
        (xy -21.371 -4.285)
        (xy -21.378 -4.307)
        (xy -21.386 -4.328)
        (xy -21.391 -4.35)
        (xy -21.395 -4.373)
        (xy -21.398 -4.397)
        (xy -21.4 -4.421)
        (xy -21.4 -4.442)
        (xy -20.955 -4.442)
        (xy -20.955 -4.446)
        (xy -20.955 -4.447)
      )

      (stroke (width 0.001) (type solid)) (fill solid) (layer "B.Paste"))
    (fp_poly
      (pts
        (xy -20.955 -1.907)
        (xy -21.4 -1.906)
        (xy -21.4 -1.929)
        (xy -21.398 -1.953)
        (xy -21.395 -1.975)
        (xy -21.391 -1.999)
        (xy -21.386 -2.02)
        (xy -21.378 -2.043)
        (xy -21.371 -2.064)
        (xy -21.362 -2.087)
        (xy -21.352 -2.108)
        (xy -21.342 -2.128)
        (xy -21.328 -2.148)
        (xy -21.316 -2.166)
        (xy -21.301 -2.185)
        (xy -21.287 -2.202)
        (xy -21.27 -2.22)
        (xy -21.253 -2.236)
        (xy -21.237 -2.25)
        (xy -21.217 -2.265)
        (xy -21.198 -2.277)
        (xy -21.179 -2.29)
        (xy -21.159 -2.301)
        (xy -21.138 -2.311)
        (xy -21.115 -2.321)
        (xy -21.093 -2.327)
        (xy -21.072 -2.334)
        (xy -21.049 -2.339)
        (xy -21.026 -2.345)
        (xy -21.003 -2.347)
        (xy -20.979 -2.349)
        (xy -20.955 -2.35)
        (xy -20.932 -2.349)
        (xy -20.909 -2.347)
        (xy -20.886 -2.345)
        (xy -20.862 -2.339)
        (xy -20.84 -2.334)
        (xy -20.817 -2.327)
        (xy -20.796 -2.319)
        (xy -20.775 -2.311)
        (xy -20.753 -2.301)
        (xy -20.734 -2.289)
        (xy -20.714 -2.277)
        (xy -20.694 -2.265)
        (xy -20.676 -2.25)
        (xy -20.657 -2.236)
        (xy -20.641 -2.22)
        (xy -20.624 -2.202)
        (xy -20.61 -2.185)
        (xy -20.595 -2.166)
        (xy -20.583 -2.146)
        (xy -20.57 -2.128)
        (xy -20.56 -2.107)
        (xy -20.548 -2.085)
        (xy -20.54 -2.064)
        (xy -20.532 -2.043)
        (xy -20.525 -2.019)
        (xy -20.52 -1.997)
        (xy -20.516 -1.975)
        (xy -20.513 -1.951)
        (xy -20.511 -1.927)
        (xy -20.511 -1.904)
        (xy -20.511 -1.881)
        (xy -20.513 -1.858)
        (xy -20.516 -1.834)
        (xy -20.52 -1.812)
        (xy -20.525 -1.789)
        (xy -20.532 -1.766)
        (xy -20.54 -1.745)
        (xy -20.548 -1.723)
        (xy -20.56 -1.703)
        (xy -20.57 -1.681)
        (xy -20.583 -1.662)
        (xy -20.595 -1.642)
        (xy -20.61 -1.624)
        (xy -20.624 -1.606)
        (xy -20.641 -1.59)
        (xy -20.657 -1.574)
        (xy -20.676 -1.558)
        (xy -20.694 -1.544)
        (xy -20.714 -1.531)
        (xy -20.734 -1.519)
        (xy -20.753 -1.508)
        (xy -20.775 -1.497)
        (xy -20.796 -1.489)
        (xy -20.817 -1.481)
        (xy -20.84 -1.475)
        (xy -20.862 -1.469)
        (xy -20.886 -1.465)
        (xy -20.909 -1.461)
        (xy -20.932 -1.461)
        (xy -20.955 -1.459)
        (xy -20.979 -1.461)
        (xy -21.003 -1.461)
        (xy -21.026 -1.465)
        (xy -21.049 -1.469)
        (xy -21.072 -1.475)
        (xy -21.093 -1.481)
        (xy -21.115 -1.489)
        (xy -21.138 -1.497)
        (xy -21.159 -1.507)
        (xy -21.179 -1.518)
        (xy -21.198 -1.531)
        (xy -21.217 -1.544)
        (xy -21.237 -1.558)
        (xy -21.253 -1.574)
        (xy -21.27 -1.59)
        (xy -21.287 -1.606)
        (xy -21.301 -1.624)
        (xy -21.316 -1.642)
        (xy -21.328 -1.661)
        (xy -21.342 -1.681)
        (xy -21.352 -1.701)
        (xy -21.362 -1.723)
        (xy -21.371 -1.745)
        (xy -21.378 -1.766)
        (xy -21.386 -1.788)
        (xy -21.391 -1.81)
        (xy -21.395 -1.834)
        (xy -21.398 -1.856)
        (xy -21.4 -1.88)
        (xy -21.4 -1.902)
        (xy -20.955 -1.902)
        (xy -20.955 -1.906)
        (xy -20.955 -1.907)
      )

      (stroke (width 0.001) (type solid)) (fill solid) (layer "B.Paste"))
    (fp_poly
      (pts
        (xy -20.955 -0.637)
        (xy -21.4 -0.636)
        (xy -21.4 -0.659)
        (xy -21.398 -0.683)
        (xy -21.395 -0.705)
        (xy -21.391 -0.728)
        (xy -21.386 -0.75)
        (xy -21.378 -0.773)
        (xy -21.371 -0.795)
        (xy -21.362 -0.816)
        (xy -21.352 -0.837)
        (xy -21.342 -0.857)
        (xy -21.328 -0.877)
        (xy -21.316 -0.897)
        (xy -21.301 -0.916)
        (xy -21.287 -0.933)
        (xy -21.27 -0.949)
        (xy -21.253 -0.965)
        (xy -21.237 -0.98)
        (xy -21.217 -0.994)
        (xy -21.198 -1.007)
        (xy -21.179 -1.02)
        (xy -21.159 -1.032)
        (xy -21.138 -1.042)
        (xy -21.115 -1.05)
        (xy -21.093 -1.058)
        (xy -21.072 -1.064)
        (xy -21.049 -1.07)
        (xy -21.026 -1.074)
        (xy -21.003 -1.078)
        (xy -20.979 -1.078)
        (xy -20.955 -1.08)
        (xy -20.932 -1.078)
        (xy -20.909 -1.078)
        (xy -20.886 -1.074)
        (xy -20.862 -1.07)
        (xy -20.84 -1.064)
        (xy -20.817 -1.058)
        (xy -20.796 -1.05)
        (xy -20.775 -1.042)
        (xy -20.753 -1.03)
        (xy -20.734 -1.019)
        (xy -20.714 -1.007)
        (xy -20.694 -0.994)
        (xy -20.676 -0.98)
        (xy -20.657 -0.965)
        (xy -20.641 -0.949)
        (xy -20.624 -0.933)
        (xy -20.61 -0.915)
        (xy -20.595 -0.897)
        (xy -20.583 -0.876)
        (xy -20.57 -0.857)
        (xy -20.56 -0.836)
        (xy -20.548 -0.815)
        (xy -20.54 -0.794)
        (xy -20.532 -0.773)
        (xy -20.525 -0.749)
        (xy -20.52 -0.727)
        (xy -20.516 -0.704)
        (xy -20.513 -0.682)
        (xy -20.511 -0.658)
        (xy -20.511 -0.634)
        (xy -20.511 -0.611)
        (xy -20.513 -0.587)
        (xy -20.516 -0.564)
        (xy -20.52 -0.542)
        (xy -20.525 -0.52)
        (xy -20.532 -0.496)
        (xy -20.54 -0.475)
        (xy -20.548 -0.454)
        (xy -20.56 -0.432)
        (xy -20.57 -0.411)
        (xy -20.583 -0.393)
        (xy -20.595 -0.372)
        (xy -20.61 -0.354)
        (xy -20.624 -0.337)
        (xy -20.641 -0.32)
        (xy -20.657 -0.303)
        (xy -20.676 -0.288)
        (xy -20.694 -0.275)
        (xy -20.714 -0.262)
        (xy -20.734 -0.249)
        (xy -20.753 -0.238)
        (xy -20.775 -0.228)
        (xy -20.796 -0.219)
        (xy -20.817 -0.211)
        (xy -20.84 -0.204)
        (xy -20.862 -0.2)
        (xy -20.886 -0.195)
        (xy -20.909 -0.192)
        (xy -20.932 -0.19)
        (xy -20.955 -0.189)
        (xy -20.979 -0.19)
        (xy -21.003 -0.192)
        (xy -21.026 -0.195)
        (xy -21.049 -0.2)
        (xy -21.072 -0.204)
        (xy -21.093 -0.211)
        (xy -21.115 -0.218)
        (xy -21.138 -0.228)
        (xy -21.159 -0.237)
        (xy -21.179 -0.248)
        (xy -21.198 -0.262)
        (xy -21.217 -0.275)
        (xy -21.237 -0.288)
        (xy -21.253 -0.303)
        (xy -21.27 -0.32)
        (xy -21.287 -0.337)
        (xy -21.301 -0.353)
        (xy -21.316 -0.372)
        (xy -21.328 -0.392)
        (xy -21.342 -0.411)
        (xy -21.352 -0.431)
        (xy -21.362 -0.453)
        (xy -21.371 -0.474)
        (xy -21.378 -0.496)
        (xy -21.386 -0.519)
        (xy -21.391 -0.541)
        (xy -21.395 -0.563)
        (xy -21.398 -0.586)
        (xy -21.4 -0.61)
        (xy -21.4 -0.631)
        (xy -20.955 -0.631)
        (xy -20.955 -0.636)
        (xy -20.955 -0.637)
      )

      (stroke (width 0.001) (type solid)) (fill solid) (layer "B.Paste"))
    (fp_poly
      (pts
        (xy -20.955 0.633)
        (xy -21.4 0.632)
        (xy -21.4 0.611)
        (xy -21.398 0.587)
        (xy -21.395 0.564)
        (xy -21.391 0.542)
        (xy -21.386 0.52)
        (xy -21.378 0.497)
        (xy -21.371 0.475)
        (xy -21.362 0.454)
        (xy -21.352 0.432)
        (xy -21.342 0.412)
        (xy -21.328 0.393)
        (xy -21.316 0.373)
        (xy -21.301 0.354)
        (xy -21.287 0.338)
        (xy -21.27 0.32)
        (xy -21.253 0.304)
        (xy -21.237 0.289)
        (xy -21.217 0.276)
        (xy -21.198 0.263)
        (xy -21.179 0.249)
        (xy -21.159 0.238)
        (xy -21.138 0.229)
        (xy -21.115 0.219)
        (xy -21.093 0.212)
        (xy -21.072 0.205)
        (xy -21.049 0.201)
        (xy -21.026 0.196)
        (xy -21.003 0.192)
        (xy -20.979 0.191)
        (xy -20.955 0.19)
        (xy -20.932 0.191)
        (xy -20.909 0.192)
        (xy -20.886 0.196)
        (xy -20.862 0.201)
        (xy -20.84 0.205)
        (xy -20.817 0.212)
        (xy -20.796 0.22)
        (xy -20.775 0.229)
        (xy -20.753 0.239)
        (xy -20.734 0.25)
        (xy -20.714 0.263)
        (xy -20.694 0.276)
        (xy -20.676 0.289)
        (xy -20.657 0.304)
        (xy -20.641 0.32)
        (xy -20.624 0.338)
        (xy -20.61 0.355)
        (xy -20.595 0.373)
        (xy -20.583 0.394)
        (xy -20.57 0.412)
        (xy -20.56 0.433)
        (xy -20.548 0.455)
        (xy -20.54 0.476)
        (xy -20.532 0.497)
        (xy -20.525 0.521)
        (xy -20.52 0.543)
        (xy -20.516 0.565)
        (xy -20.513 0.588)
        (xy -20.511 0.612)
        (xy -20.511 0.635)
        (xy -20.511 0.659)
        (xy -20.513 0.683)
        (xy -20.516 0.705)
        (xy -20.52 0.728)
        (xy -20.525 0.75)
        (xy -20.532 0.774)
        (xy -20.54 0.795)
        (xy -20.548 0.816)
        (xy -20.56 0.837)
        (xy -20.57 0.858)
        (xy -20.583 0.877)
        (xy -20.595 0.898)
        (xy -20.61 0.916)
        (xy -20.624 0.934)
        (xy -20.641 0.95)
        (xy -20.657 0.966)
        (xy -20.676 0.981)
        (xy -20.694 0.995)
        (xy -20.714 1.008)
        (xy -20.734 1.02)
        (xy -20.753 1.031)
        (xy -20.775 1.043)
        (xy -20.796 1.051)
        (xy -20.817 1.059)
        (xy -20.84 1.065)
        (xy -20.862 1.071)
        (xy -20.886 1.075)
        (xy -20.909 1.079)
        (xy -20.932 1.079)
        (xy -20.955 1.081)
        (xy -20.979 1.079)
        (xy -21.003 1.079)
        (xy -21.026 1.075)
        (xy -21.049 1.071)
        (xy -21.072 1.065)
        (xy -21.093 1.059)
        (xy -21.115 1.051)
        (xy -21.138 1.043)
        (xy -21.159 1.033)
        (xy -21.179 1.021)
        (xy -21.198 1.008)
        (xy -21.217 0.995)
        (xy -21.237 0.981)
        (xy -21.253 0.966)
        (xy -21.27 0.95)
        (xy -21.287 0.934)
        (xy -21.301 0.917)
        (xy -21.316 0.898)
        (xy -21.328 0.878)
        (xy -21.342 0.858)
        (xy -21.352 0.838)
        (xy -21.362 0.817)
        (xy -21.371 0.796)
        (xy -21.378 0.774)
        (xy -21.386 0.751)
        (xy -21.391 0.729)
        (xy -21.395 0.706)
        (xy -21.398 0.684)
        (xy -21.4 0.66)
        (xy -21.4 0.637)
        (xy -20.955 0.637)
        (xy -20.955 0.632)
        (xy -20.955 0.633)
      )

      (stroke (width 0.001) (type solid)) (fill solid) (layer "B.Paste"))
    (fp_poly
      (pts
        (xy -19.685 -4.447)
        (xy -20.13 -4.446)
        (xy -20.13 -4.469)
        (xy -20.128 -4.493)
        (xy -20.125 -4.515)
        (xy -20.121 -4.538)
        (xy -20.115 -4.56)
        (xy -20.109 -4.583)
        (xy -20.101 -4.605)
        (xy -20.092 -4.626)
        (xy -20.083 -4.647)
        (xy -20.072 -4.668)
        (xy -20.058 -4.687)
        (xy -20.046 -4.706)
        (xy -20.031 -4.725)
        (xy -20.016 -4.743)
        (xy -20 -4.759)
        (xy -19.984 -4.775)
        (xy -19.967 -4.791)
        (xy -19.947 -4.804)
        (xy -19.929 -4.817)
        (xy -19.909 -4.831)
        (xy -19.889 -4.841)
        (xy -19.868 -4.852)
        (xy -19.845 -4.86)
        (xy -19.823 -4.868)
        (xy -19.801 -4.874)
        (xy -19.779 -4.879)
        (xy -19.756 -4.884)
        (xy -19.734 -4.887)
        (xy -19.709 -4.889)
        (xy -19.685 -4.889)
        (xy -19.662 -4.889)
        (xy -19.639 -4.887)
        (xy -19.615 -4.884)
        (xy -19.592 -4.879)
        (xy -19.57 -4.874)
        (xy -19.548 -4.868)
        (xy -19.526 -4.86)
        (xy -19.505 -4.852)
        (xy -19.484 -4.841)
        (xy -19.462 -4.829)
        (xy -19.444 -4.817)
        (xy -19.423 -4.804)
        (xy -19.406 -4.791)
        (xy -19.388 -4.775)
        (xy -19.371 -4.759)
        (xy -19.354 -4.743)
        (xy -19.339 -4.724)
        (xy -19.325 -4.706)
        (xy -19.313 -4.687)
        (xy -19.301 -4.668)
        (xy -19.29 -4.647)
        (xy -19.278 -4.626)
        (xy -19.27 -4.603)
        (xy -19.263 -4.583)
        (xy -19.255 -4.559)
        (xy -19.25 -4.538)
        (xy -19.246 -4.514)
        (xy -19.243 -4.491)
        (xy -19.241 -4.467)
        (xy -19.24 -4.445)
        (xy -19.241 -4.421)
        (xy -19.243 -4.397)
        (xy -19.246 -4.374)
        (xy -19.25 -4.352)
        (xy -19.255 -4.329)
        (xy -19.263 -4.307)
        (xy -19.27 -4.285)
        (xy -19.278 -4.264)
        (xy -19.29 -4.243)
        (xy -19.301 -4.222)
        (xy -19.313 -4.203)
        (xy -19.325 -4.182)
        (xy -19.339 -4.164)
        (xy -19.354 -4.147)
        (xy -19.371 -4.129)
        (xy -19.388 -4.113)
        (xy -19.406 -4.099)
        (xy -19.423 -4.084)
        (xy -19.444 -4.071)
        (xy -19.462 -4.059)
        (xy -19.484 -4.049)
        (xy -19.505 -4.038)
        (xy -19.526 -4.03)
        (xy -19.548 -4.022)
        (xy -19.57 -4.014)
        (xy -19.592 -4.009)
        (xy -19.615 -4.004)
        (xy -19.639 -4.001)
        (xy -19.662 -4.001)
        (xy -19.685 -3.999)
        (xy -19.709 -4.001)
        (xy -19.734 -4.001)
        (xy -19.756 -4.004)
        (xy -19.779 -4.009)
        (xy -19.801 -4.014)
        (xy -19.823 -4.022)
        (xy -19.845 -4.028)
        (xy -19.868 -4.038)
        (xy -19.889 -4.047)
        (xy -19.909 -4.059)
        (xy -19.929 -4.071)
        (xy -19.947 -4.084)
        (xy -19.967 -4.099)
        (xy -19.984 -4.113)
        (xy -20 -4.129)
        (xy -20.016 -4.147)
        (xy -20.031 -4.163)
        (xy -20.046 -4.182)
        (xy -20.058 -4.201)
        (xy -20.072 -4.222)
        (xy -20.083 -4.241)
        (xy -20.092 -4.262)
        (xy -20.101 -4.285)
        (xy -20.109 -4.307)
        (xy -20.115 -4.328)
        (xy -20.121 -4.35)
        (xy -20.125 -4.373)
        (xy -20.128 -4.397)
        (xy -20.13 -4.421)
        (xy -20.13 -4.442)
        (xy -19.685 -4.442)
        (xy -19.685 -4.446)
        (xy -19.685 -4.447)
      )

      (stroke (width 0.001) (type solid)) (fill solid) (layer "B.Paste"))
    (fp_poly
      (pts
        (xy -19.685 -1.907)
        (xy -20.13 -1.906)
        (xy -20.13 -1.929)
        (xy -20.128 -1.953)
        (xy -20.125 -1.975)
        (xy -20.121 -1.999)
        (xy -20.115 -2.02)
        (xy -20.109 -2.043)
        (xy -20.101 -2.064)
        (xy -20.092 -2.087)
        (xy -20.083 -2.108)
        (xy -20.072 -2.128)
        (xy -20.058 -2.148)
        (xy -20.046 -2.166)
        (xy -20.031 -2.185)
        (xy -20.016 -2.202)
        (xy -20 -2.22)
        (xy -19.984 -2.236)
        (xy -19.967 -2.25)
        (xy -19.947 -2.265)
        (xy -19.929 -2.277)
        (xy -19.909 -2.29)
        (xy -19.889 -2.301)
        (xy -19.868 -2.311)
        (xy -19.845 -2.321)
        (xy -19.823 -2.327)
        (xy -19.801 -2.334)
        (xy -19.779 -2.339)
        (xy -19.756 -2.345)
        (xy -19.734 -2.347)
        (xy -19.709 -2.349)
        (xy -19.685 -2.35)
        (xy -19.662 -2.349)
        (xy -19.639 -2.347)
        (xy -19.615 -2.345)
        (xy -19.592 -2.339)
        (xy -19.57 -2.334)
        (xy -19.548 -2.327)
        (xy -19.526 -2.319)
        (xy -19.505 -2.311)
        (xy -19.484 -2.301)
        (xy -19.462 -2.289)
        (xy -19.444 -2.277)
        (xy -19.423 -2.265)
        (xy -19.406 -2.25)
        (xy -19.388 -2.236)
        (xy -19.371 -2.22)
        (xy -19.354 -2.202)
        (xy -19.339 -2.185)
        (xy -19.325 -2.166)
        (xy -19.313 -2.146)
        (xy -19.301 -2.126)
        (xy -19.29 -2.107)
        (xy -19.278 -2.085)
        (xy -19.27 -2.064)
        (xy -19.263 -2.043)
        (xy -19.255 -2.019)
        (xy -19.25 -1.997)
        (xy -19.246 -1.975)
        (xy -19.243 -1.951)
        (xy -19.241 -1.927)
        (xy -19.24 -1.904)
        (xy -19.241 -1.881)
        (xy -19.243 -1.858)
        (xy -19.246 -1.834)
        (xy -19.25 -1.812)
        (xy -19.255 -1.789)
        (xy -19.263 -1.766)
        (xy -19.27 -1.745)
        (xy -19.278 -1.723)
        (xy -19.29 -1.703)
        (xy -19.301 -1.683)
        (xy -19.313 -1.662)
        (xy -19.325 -1.642)
        (xy -19.339 -1.624)
        (xy -19.354 -1.606)
        (xy -19.371 -1.59)
        (xy -19.388 -1.574)
        (xy -19.406 -1.558)
        (xy -19.423 -1.544)
        (xy -19.444 -1.531)
        (xy -19.462 -1.519)
        (xy -19.484 -1.508)
        (xy -19.505 -1.497)
        (xy -19.526 -1.489)
        (xy -19.548 -1.481)
        (xy -19.57 -1.475)
        (xy -19.592 -1.469)
        (xy -19.615 -1.465)
        (xy -19.639 -1.461)
        (xy -19.662 -1.461)
        (xy -19.685 -1.459)
        (xy -19.709 -1.461)
        (xy -19.734 -1.461)
        (xy -19.756 -1.465)
        (xy -19.779 -1.469)
        (xy -19.801 -1.475)
        (xy -19.823 -1.481)
        (xy -19.845 -1.489)
        (xy -19.868 -1.497)
        (xy -19.889 -1.507)
        (xy -19.909 -1.518)
        (xy -19.929 -1.531)
        (xy -19.947 -1.544)
        (xy -19.967 -1.558)
        (xy -19.984 -1.574)
        (xy -20 -1.59)
        (xy -20.016 -1.606)
        (xy -20.031 -1.624)
        (xy -20.046 -1.642)
        (xy -20.058 -1.661)
        (xy -20.072 -1.681)
        (xy -20.083 -1.701)
        (xy -20.092 -1.723)
        (xy -20.101 -1.745)
        (xy -20.109 -1.766)
        (xy -20.115 -1.788)
        (xy -20.121 -1.81)
        (xy -20.125 -1.834)
        (xy -20.128 -1.856)
        (xy -20.13 -1.88)
        (xy -20.13 -1.902)
        (xy -19.685 -1.902)
        (xy -19.685 -1.906)
        (xy -19.685 -1.907)
      )

      (stroke (width 0.001) (type solid)) (fill solid) (layer "B.Paste"))
    (fp_poly
      (pts
        (xy -19.685 -0.637)
        (xy -20.13 -0.636)
        (xy -20.13 -0.659)
        (xy -20.128 -0.683)
        (xy -20.125 -0.705)
        (xy -20.121 -0.728)
        (xy -20.115 -0.75)
        (xy -20.109 -0.773)
        (xy -20.101 -0.795)
        (xy -20.092 -0.816)
        (xy -20.083 -0.837)
        (xy -20.072 -0.857)
        (xy -20.058 -0.877)
        (xy -20.046 -0.897)
        (xy -20.031 -0.916)
        (xy -20.016 -0.933)
        (xy -20 -0.949)
        (xy -19.984 -0.965)
        (xy -19.967 -0.98)
        (xy -19.947 -0.994)
        (xy -19.929 -1.007)
        (xy -19.909 -1.02)
        (xy -19.889 -1.032)
        (xy -19.868 -1.042)
        (xy -19.845 -1.05)
        (xy -19.823 -1.058)
        (xy -19.801 -1.064)
        (xy -19.779 -1.07)
        (xy -19.756 -1.074)
        (xy -19.734 -1.078)
        (xy -19.709 -1.078)
        (xy -19.685 -1.08)
        (xy -19.662 -1.078)
        (xy -19.639 -1.078)
        (xy -19.615 -1.074)
        (xy -19.592 -1.07)
        (xy -19.57 -1.064)
        (xy -19.548 -1.058)
        (xy -19.526 -1.05)
        (xy -19.505 -1.042)
        (xy -19.484 -1.03)
        (xy -19.462 -1.019)
        (xy -19.444 -1.007)
        (xy -19.423 -0.994)
        (xy -19.406 -0.98)
        (xy -19.388 -0.965)
        (xy -19.371 -0.949)
        (xy -19.354 -0.933)
        (xy -19.339 -0.915)
        (xy -19.325 -0.897)
        (xy -19.313 -0.876)
        (xy -19.301 -0.856)
        (xy -19.29 -0.836)
        (xy -19.278 -0.815)
        (xy -19.27 -0.794)
        (xy -19.263 -0.773)
        (xy -19.255 -0.749)
        (xy -19.25 -0.727)
        (xy -19.246 -0.704)
        (xy -19.243 -0.682)
        (xy -19.241 -0.658)
        (xy -19.24 -0.634)
        (xy -19.241 -0.611)
        (xy -19.243 -0.587)
        (xy -19.246 -0.564)
        (xy -19.25 -0.542)
        (xy -19.255 -0.52)
        (xy -19.263 -0.496)
        (xy -19.27 -0.475)
        (xy -19.278 -0.454)
        (xy -19.29 -0.432)
        (xy -19.301 -0.412)
        (xy -19.313 -0.393)
        (xy -19.325 -0.372)
        (xy -19.339 -0.354)
        (xy -19.354 -0.337)
        (xy -19.371 -0.32)
        (xy -19.388 -0.303)
        (xy -19.406 -0.288)
        (xy -19.423 -0.275)
        (xy -19.444 -0.262)
        (xy -19.462 -0.249)
        (xy -19.484 -0.238)
        (xy -19.505 -0.228)
        (xy -19.526 -0.219)
        (xy -19.548 -0.211)
        (xy -19.57 -0.204)
        (xy -19.592 -0.2)
        (xy -19.615 -0.195)
        (xy -19.639 -0.192)
        (xy -19.662 -0.19)
        (xy -19.685 -0.189)
        (xy -19.709 -0.19)
        (xy -19.734 -0.192)
        (xy -19.756 -0.195)
        (xy -19.779 -0.2)
        (xy -19.801 -0.204)
        (xy -19.823 -0.211)
        (xy -19.845 -0.218)
        (xy -19.868 -0.228)
        (xy -19.889 -0.237)
        (xy -19.909 -0.248)
        (xy -19.929 -0.262)
        (xy -19.947 -0.275)
        (xy -19.967 -0.288)
        (xy -19.984 -0.303)
        (xy -20 -0.32)
        (xy -20.016 -0.337)
        (xy -20.031 -0.353)
        (xy -20.046 -0.372)
        (xy -20.058 -0.392)
        (xy -20.072 -0.411)
        (xy -20.083 -0.431)
        (xy -20.092 -0.453)
        (xy -20.101 -0.474)
        (xy -20.109 -0.496)
        (xy -20.115 -0.519)
        (xy -20.121 -0.541)
        (xy -20.125 -0.563)
        (xy -20.128 -0.586)
        (xy -20.13 -0.61)
        (xy -20.13 -0.631)
        (xy -19.685 -0.631)
        (xy -19.685 -0.636)
        (xy -19.685 -0.637)
      )

      (stroke (width 0.001) (type solid)) (fill solid) (layer "B.Paste"))
    (fp_poly
      (pts
        (xy -19.685 0.633)
        (xy -20.13 0.632)
        (xy -20.13 0.611)
        (xy -20.128 0.587)
        (xy -20.125 0.564)
        (xy -20.121 0.542)
        (xy -20.115 0.52)
        (xy -20.109 0.497)
        (xy -20.101 0.475)
        (xy -20.092 0.454)
        (xy -20.083 0.432)
        (xy -20.072 0.412)
        (xy -20.058 0.393)
        (xy -20.046 0.373)
        (xy -20.031 0.354)
        (xy -20.016 0.338)
        (xy -20 0.32)
        (xy -19.984 0.304)
        (xy -19.967 0.289)
        (xy -19.947 0.276)
        (xy -19.929 0.263)
        (xy -19.909 0.249)
        (xy -19.889 0.238)
        (xy -19.868 0.229)
        (xy -19.845 0.219)
        (xy -19.823 0.212)
        (xy -19.801 0.205)
        (xy -19.779 0.201)
        (xy -19.756 0.196)
        (xy -19.734 0.192)
        (xy -19.709 0.191)
        (xy -19.685 0.19)
        (xy -19.662 0.191)
        (xy -19.639 0.192)
        (xy -19.615 0.196)
        (xy -19.592 0.201)
        (xy -19.57 0.205)
        (xy -19.548 0.212)
        (xy -19.526 0.22)
        (xy -19.505 0.229)
        (xy -19.484 0.239)
        (xy -19.462 0.25)
        (xy -19.444 0.263)
        (xy -19.423 0.276)
        (xy -19.406 0.289)
        (xy -19.388 0.304)
        (xy -19.371 0.32)
        (xy -19.354 0.338)
        (xy -19.339 0.355)
        (xy -19.325 0.373)
        (xy -19.313 0.394)
        (xy -19.301 0.413)
        (xy -19.29 0.433)
        (xy -19.278 0.455)
        (xy -19.27 0.476)
        (xy -19.263 0.497)
        (xy -19.255 0.521)
        (xy -19.25 0.543)
        (xy -19.246 0.565)
        (xy -19.243 0.588)
        (xy -19.241 0.612)
        (xy -19.24 0.635)
        (xy -19.241 0.659)
        (xy -19.243 0.683)
        (xy -19.246 0.705)
        (xy -19.25 0.728)
        (xy -19.255 0.75)
        (xy -19.263 0.774)
        (xy -19.27 0.795)
        (xy -19.278 0.816)
        (xy -19.29 0.837)
        (xy -19.301 0.857)
        (xy -19.313 0.877)
        (xy -19.325 0.898)
        (xy -19.339 0.916)
        (xy -19.354 0.934)
        (xy -19.371 0.95)
        (xy -19.388 0.966)
        (xy -19.406 0.981)
        (xy -19.423 0.995)
        (xy -19.444 1.008)
        (xy -19.462 1.02)
        (xy -19.484 1.031)
        (xy -19.505 1.043)
        (xy -19.526 1.051)
        (xy -19.548 1.059)
        (xy -19.57 1.065)
        (xy -19.592 1.071)
        (xy -19.615 1.075)
        (xy -19.639 1.079)
        (xy -19.662 1.079)
        (xy -19.685 1.081)
        (xy -19.709 1.079)
        (xy -19.734 1.079)
        (xy -19.756 1.075)
        (xy -19.779 1.071)
        (xy -19.801 1.065)
        (xy -19.823 1.059)
        (xy -19.845 1.051)
        (xy -19.868 1.043)
        (xy -19.889 1.033)
        (xy -19.909 1.021)
        (xy -19.929 1.008)
        (xy -19.947 0.995)
        (xy -19.967 0.981)
        (xy -19.984 0.966)
        (xy -20 0.95)
        (xy -20.016 0.934)
        (xy -20.031 0.917)
        (xy -20.046 0.898)
        (xy -20.058 0.878)
        (xy -20.072 0.858)
        (xy -20.083 0.838)
        (xy -20.092 0.817)
        (xy -20.101 0.796)
        (xy -20.109 0.774)
        (xy -20.115 0.751)
        (xy -20.121 0.729)
        (xy -20.125 0.706)
        (xy -20.128 0.684)
        (xy -20.13 0.66)
        (xy -20.13 0.637)
        (xy -19.685 0.637)
        (xy -19.685 0.632)
        (xy -19.685 0.633)
      )

      (stroke (width 0.001) (type solid)) (fill solid) (layer "B.Paste"))
    (fp_poly
      (pts
        (xy -18.415 -4.447)
        (xy -18.86 -4.446)
        (xy -18.86 -4.469)
        (xy -18.859 -4.493)
        (xy -18.856 -4.515)
        (xy -18.851 -4.538)
        (xy -18.845 -4.56)
        (xy -18.839 -4.583)
        (xy -18.831 -4.605)
        (xy -18.822 -4.626)
        (xy -18.813 -4.647)
        (xy -18.801 -4.668)
        (xy -18.788 -4.687)
        (xy -18.775 -4.706)
        (xy -18.761 -4.725)
        (xy -18.746 -4.743)
        (xy -18.731 -4.759)
        (xy -18.714 -4.775)
        (xy -18.697 -4.791)
        (xy -18.677 -4.804)
        (xy -18.659 -4.817)
        (xy -18.639 -4.831)
        (xy -18.618 -4.841)
        (xy -18.598 -4.852)
        (xy -18.575 -4.86)
        (xy -18.554 -4.868)
        (xy -18.531 -4.874)
        (xy -18.509 -4.879)
        (xy -18.487 -4.884)
        (xy -18.464 -4.887)
        (xy -18.439 -4.889)
        (xy -18.415 -4.889)
        (xy -18.392 -4.889)
        (xy -18.368 -4.887)
        (xy -18.345 -4.884)
        (xy -18.322 -4.879)
        (xy -18.301 -4.874)
        (xy -18.278 -4.868)
        (xy -18.256 -4.86)
        (xy -18.235 -4.852)
        (xy -18.214 -4.841)
        (xy -18.192 -4.829)
        (xy -18.173 -4.817)
        (xy -18.153 -4.804)
        (xy -18.136 -4.791)
        (xy -18.118 -4.775)
        (xy -18.101 -4.759)
        (xy -18.084 -4.743)
        (xy -18.069 -4.724)
        (xy -18.055 -4.706)
        (xy -18.043 -4.687)
        (xy -18.031 -4.668)
        (xy -18.019 -4.647)
        (xy -18.008 -4.626)
        (xy -18 -4.603)
        (xy -17.993 -4.583)
        (xy -17.985 -4.559)
        (xy -17.981 -4.538)
        (xy -17.976 -4.514)
        (xy -17.973 -4.491)
        (xy -17.971 -4.467)
        (xy -17.97 -4.445)
        (xy -17.971 -4.421)
        (xy -17.973 -4.397)
        (xy -17.976 -4.374)
        (xy -17.981 -4.352)
        (xy -17.985 -4.329)
        (xy -17.993 -4.307)
        (xy -18 -4.285)
        (xy -18.008 -4.264)
        (xy -18.019 -4.243)
        (xy -18.031 -4.222)
        (xy -18.043 -4.203)
        (xy -18.055 -4.182)
        (xy -18.069 -4.164)
        (xy -18.084 -4.147)
        (xy -18.101 -4.129)
        (xy -18.118 -4.113)
        (xy -18.136 -4.099)
        (xy -18.153 -4.084)
        (xy -18.173 -4.071)
        (xy -18.192 -4.059)
        (xy -18.214 -4.049)
        (xy -18.235 -4.038)
        (xy -18.256 -4.03)
        (xy -18.278 -4.022)
        (xy -18.301 -4.014)
        (xy -18.322 -4.009)
        (xy -18.345 -4.004)
        (xy -18.368 -4.001)
        (xy -18.392 -4.001)
        (xy -18.415 -3.999)
        (xy -18.439 -4.001)
        (xy -18.464 -4.001)
        (xy -18.487 -4.004)
        (xy -18.509 -4.009)
        (xy -18.531 -4.014)
        (xy -18.554 -4.022)
        (xy -18.575 -4.028)
        (xy -18.598 -4.038)
        (xy -18.618 -4.047)
        (xy -18.639 -4.059)
        (xy -18.659 -4.071)
        (xy -18.677 -4.084)
        (xy -18.697 -4.099)
        (xy -18.714 -4.113)
        (xy -18.731 -4.129)
        (xy -18.746 -4.147)
        (xy -18.761 -4.163)
        (xy -18.775 -4.182)
        (xy -18.788 -4.201)
        (xy -18.801 -4.222)
        (xy -18.813 -4.241)
        (xy -18.822 -4.262)
        (xy -18.831 -4.285)
        (xy -18.839 -4.307)
        (xy -18.845 -4.328)
        (xy -18.851 -4.35)
        (xy -18.856 -4.373)
        (xy -18.859 -4.397)
        (xy -18.86 -4.421)
        (xy -18.86 -4.442)
        (xy -18.415 -4.442)
        (xy -18.415 -4.446)
        (xy -18.415 -4.447)
      )

      (stroke (width 0.001) (type solid)) (fill solid) (layer "B.Paste"))
    (fp_poly
      (pts
        (xy -18.415 -1.907)
        (xy -18.86 -1.906)
        (xy -18.86 -1.929)
        (xy -18.859 -1.953)
        (xy -18.856 -1.975)
        (xy -18.851 -1.999)
        (xy -18.845 -2.02)
        (xy -18.839 -2.043)
        (xy -18.831 -2.064)
        (xy -18.822 -2.087)
        (xy -18.813 -2.108)
        (xy -18.801 -2.128)
        (xy -18.788 -2.148)
        (xy -18.775 -2.166)
        (xy -18.761 -2.185)
        (xy -18.746 -2.202)
        (xy -18.731 -2.22)
        (xy -18.714 -2.236)
        (xy -18.697 -2.25)
        (xy -18.677 -2.265)
        (xy -18.659 -2.277)
        (xy -18.639 -2.29)
        (xy -18.618 -2.301)
        (xy -18.598 -2.311)
        (xy -18.575 -2.321)
        (xy -18.554 -2.327)
        (xy -18.531 -2.334)
        (xy -18.509 -2.339)
        (xy -18.487 -2.345)
        (xy -18.464 -2.347)
        (xy -18.439 -2.349)
        (xy -18.415 -2.35)
        (xy -18.392 -2.349)
        (xy -18.368 -2.347)
        (xy -18.345 -2.345)
        (xy -18.322 -2.339)
        (xy -18.301 -2.334)
        (xy -18.278 -2.327)
        (xy -18.256 -2.319)
        (xy -18.235 -2.311)
        (xy -18.214 -2.301)
        (xy -18.192 -2.289)
        (xy -18.173 -2.277)
        (xy -18.153 -2.265)
        (xy -18.136 -2.25)
        (xy -18.118 -2.236)
        (xy -18.101 -2.22)
        (xy -18.084 -2.202)
        (xy -18.069 -2.185)
        (xy -18.055 -2.166)
        (xy -18.043 -2.146)
        (xy -18.031 -2.126)
        (xy -18.019 -2.107)
        (xy -18.008 -2.085)
        (xy -18 -2.064)
        (xy -17.993 -2.043)
        (xy -17.985 -2.019)
        (xy -17.981 -1.997)
        (xy -17.976 -1.975)
        (xy -17.973 -1.951)
        (xy -17.971 -1.927)
        (xy -17.97 -1.904)
        (xy -17.971 -1.881)
        (xy -17.973 -1.858)
        (xy -17.976 -1.834)
        (xy -17.981 -1.812)
        (xy -17.985 -1.789)
        (xy -17.993 -1.766)
        (xy -18 -1.745)
        (xy -18.008 -1.723)
        (xy -18.019 -1.703)
        (xy -18.031 -1.683)
        (xy -18.043 -1.662)
        (xy -18.055 -1.642)
        (xy -18.069 -1.624)
        (xy -18.084 -1.606)
        (xy -18.101 -1.59)
        (xy -18.118 -1.574)
        (xy -18.136 -1.558)
        (xy -18.153 -1.544)
        (xy -18.173 -1.531)
        (xy -18.192 -1.519)
        (xy -18.214 -1.508)
        (xy -18.235 -1.497)
        (xy -18.256 -1.489)
        (xy -18.278 -1.481)
        (xy -18.301 -1.475)
        (xy -18.322 -1.469)
        (xy -18.345 -1.465)
        (xy -18.368 -1.461)
        (xy -18.392 -1.461)
        (xy -18.415 -1.459)
        (xy -18.439 -1.461)
        (xy -18.464 -1.461)
        (xy -18.487 -1.465)
        (xy -18.509 -1.469)
        (xy -18.531 -1.475)
        (xy -18.554 -1.481)
        (xy -18.575 -1.489)
        (xy -18.598 -1.497)
        (xy -18.618 -1.507)
        (xy -18.639 -1.518)
        (xy -18.659 -1.531)
        (xy -18.677 -1.544)
        (xy -18.697 -1.558)
        (xy -18.714 -1.574)
        (xy -18.731 -1.59)
        (xy -18.746 -1.606)
        (xy -18.761 -1.624)
        (xy -18.775 -1.642)
        (xy -18.788 -1.661)
        (xy -18.801 -1.681)
        (xy -18.813 -1.701)
        (xy -18.822 -1.723)
        (xy -18.831 -1.745)
        (xy -18.839 -1.766)
        (xy -18.845 -1.788)
        (xy -18.851 -1.81)
        (xy -18.856 -1.834)
        (xy -18.859 -1.856)
        (xy -18.86 -1.88)
        (xy -18.86 -1.902)
        (xy -18.415 -1.902)
        (xy -18.415 -1.906)
        (xy -18.415 -1.907)
      )

      (stroke (width 0.001) (type solid)) (fill solid) (layer "B.Paste"))
    (fp_poly
      (pts
        (xy -18.415 -0.637)
        (xy -18.86 -0.636)
        (xy -18.86 -0.659)
        (xy -18.859 -0.683)
        (xy -18.856 -0.705)
        (xy -18.851 -0.728)
        (xy -18.845 -0.75)
        (xy -18.839 -0.773)
        (xy -18.831 -0.795)
        (xy -18.822 -0.816)
        (xy -18.813 -0.837)
        (xy -18.801 -0.857)
        (xy -18.788 -0.877)
        (xy -18.775 -0.897)
        (xy -18.761 -0.916)
        (xy -18.746 -0.933)
        (xy -18.731 -0.949)
        (xy -18.714 -0.965)
        (xy -18.697 -0.98)
        (xy -18.677 -0.994)
        (xy -18.659 -1.007)
        (xy -18.639 -1.02)
        (xy -18.618 -1.032)
        (xy -18.598 -1.042)
        (xy -18.575 -1.05)
        (xy -18.554 -1.058)
        (xy -18.531 -1.064)
        (xy -18.509 -1.07)
        (xy -18.487 -1.074)
        (xy -18.464 -1.078)
        (xy -18.439 -1.078)
        (xy -18.415 -1.08)
        (xy -18.392 -1.078)
        (xy -18.368 -1.078)
        (xy -18.345 -1.074)
        (xy -18.322 -1.07)
        (xy -18.301 -1.064)
        (xy -18.278 -1.058)
        (xy -18.256 -1.05)
        (xy -18.235 -1.042)
        (xy -18.214 -1.03)
        (xy -18.192 -1.019)
        (xy -18.173 -1.007)
        (xy -18.153 -0.994)
        (xy -18.136 -0.98)
        (xy -18.118 -0.965)
        (xy -18.101 -0.949)
        (xy -18.084 -0.933)
        (xy -18.069 -0.915)
        (xy -18.055 -0.897)
        (xy -18.043 -0.876)
        (xy -18.031 -0.856)
        (xy -18.019 -0.836)
        (xy -18.008 -0.815)
        (xy -18 -0.794)
        (xy -17.993 -0.773)
        (xy -17.985 -0.749)
        (xy -17.981 -0.727)
        (xy -17.976 -0.704)
        (xy -17.973 -0.682)
        (xy -17.971 -0.658)
        (xy -17.97 -0.634)
        (xy -17.971 -0.611)
        (xy -17.973 -0.587)
        (xy -17.976 -0.564)
        (xy -17.981 -0.542)
        (xy -17.985 -0.52)
        (xy -17.993 -0.496)
        (xy -18 -0.475)
        (xy -18.008 -0.454)
        (xy -18.019 -0.432)
        (xy -18.031 -0.412)
        (xy -18.043 -0.393)
        (xy -18.055 -0.372)
        (xy -18.069 -0.354)
        (xy -18.084 -0.337)
        (xy -18.101 -0.32)
        (xy -18.118 -0.303)
        (xy -18.136 -0.288)
        (xy -18.153 -0.275)
        (xy -18.173 -0.262)
        (xy -18.192 -0.249)
        (xy -18.214 -0.238)
        (xy -18.235 -0.228)
        (xy -18.256 -0.219)
        (xy -18.278 -0.211)
        (xy -18.301 -0.204)
        (xy -18.322 -0.2)
        (xy -18.345 -0.195)
        (xy -18.368 -0.192)
        (xy -18.392 -0.19)
        (xy -18.415 -0.189)
        (xy -18.439 -0.19)
        (xy -18.464 -0.192)
        (xy -18.487 -0.195)
        (xy -18.509 -0.2)
        (xy -18.531 -0.204)
        (xy -18.554 -0.211)
        (xy -18.575 -0.218)
        (xy -18.598 -0.228)
        (xy -18.618 -0.237)
        (xy -18.639 -0.248)
        (xy -18.659 -0.262)
        (xy -18.677 -0.275)
        (xy -18.697 -0.288)
        (xy -18.714 -0.303)
        (xy -18.731 -0.32)
        (xy -18.746 -0.337)
        (xy -18.761 -0.353)
        (xy -18.775 -0.372)
        (xy -18.788 -0.392)
        (xy -18.801 -0.411)
        (xy -18.813 -0.431)
        (xy -18.822 -0.453)
        (xy -18.831 -0.474)
        (xy -18.839 -0.496)
        (xy -18.845 -0.519)
        (xy -18.851 -0.541)
        (xy -18.856 -0.563)
        (xy -18.859 -0.586)
        (xy -18.86 -0.61)
        (xy -18.86 -0.631)
        (xy -18.415 -0.631)
        (xy -18.415 -0.636)
        (xy -18.415 -0.637)
      )

      (stroke (width 0.001) (type solid)) (fill solid) (layer "B.Paste"))
    (fp_poly
      (pts
        (xy -18.415 0.633)
        (xy -18.86 0.632)
        (xy -18.86 0.611)
        (xy -18.859 0.587)
        (xy -18.856 0.564)
        (xy -18.851 0.542)
        (xy -18.845 0.52)
        (xy -18.839 0.497)
        (xy -18.831 0.475)
        (xy -18.822 0.454)
        (xy -18.813 0.432)
        (xy -18.801 0.412)
        (xy -18.788 0.393)
        (xy -18.775 0.373)
        (xy -18.761 0.354)
        (xy -18.746 0.338)
        (xy -18.731 0.32)
        (xy -18.714 0.304)
        (xy -18.697 0.289)
        (xy -18.677 0.276)
        (xy -18.659 0.263)
        (xy -18.639 0.249)
        (xy -18.618 0.238)
        (xy -18.598 0.229)
        (xy -18.575 0.219)
        (xy -18.554 0.212)
        (xy -18.531 0.205)
        (xy -18.509 0.201)
        (xy -18.487 0.196)
        (xy -18.464 0.192)
        (xy -18.439 0.191)
        (xy -18.415 0.19)
        (xy -18.392 0.191)
        (xy -18.368 0.192)
        (xy -18.345 0.196)
        (xy -18.322 0.201)
        (xy -18.301 0.205)
        (xy -18.278 0.212)
        (xy -18.256 0.22)
        (xy -18.235 0.229)
        (xy -18.214 0.239)
        (xy -18.192 0.25)
        (xy -18.173 0.263)
        (xy -18.153 0.276)
        (xy -18.136 0.289)
        (xy -18.118 0.304)
        (xy -18.101 0.32)
        (xy -18.084 0.338)
        (xy -18.069 0.355)
        (xy -18.055 0.373)
        (xy -18.043 0.394)
        (xy -18.031 0.413)
        (xy -18.019 0.433)
        (xy -18.008 0.455)
        (xy -18 0.476)
        (xy -17.993 0.497)
        (xy -17.985 0.521)
        (xy -17.981 0.543)
        (xy -17.976 0.565)
        (xy -17.973 0.588)
        (xy -17.971 0.612)
        (xy -17.97 0.635)
        (xy -17.971 0.659)
        (xy -17.973 0.683)
        (xy -17.976 0.705)
        (xy -17.981 0.728)
        (xy -17.985 0.75)
        (xy -17.993 0.774)
        (xy -18 0.795)
        (xy -18.008 0.816)
        (xy -18.019 0.837)
        (xy -18.031 0.857)
        (xy -18.043 0.877)
        (xy -18.055 0.898)
        (xy -18.069 0.916)
        (xy -18.084 0.934)
        (xy -18.101 0.95)
        (xy -18.118 0.966)
        (xy -18.136 0.981)
        (xy -18.153 0.995)
        (xy -18.173 1.008)
        (xy -18.192 1.02)
        (xy -18.214 1.031)
        (xy -18.235 1.043)
        (xy -18.256 1.051)
        (xy -18.278 1.059)
        (xy -18.301 1.065)
        (xy -18.322 1.071)
        (xy -18.345 1.075)
        (xy -18.368 1.079)
        (xy -18.392 1.079)
        (xy -18.415 1.081)
        (xy -18.439 1.079)
        (xy -18.464 1.079)
        (xy -18.487 1.075)
        (xy -18.509 1.071)
        (xy -18.531 1.065)
        (xy -18.554 1.059)
        (xy -18.575 1.051)
        (xy -18.598 1.043)
        (xy -18.618 1.033)
        (xy -18.639 1.021)
        (xy -18.659 1.008)
        (xy -18.677 0.995)
        (xy -18.697 0.981)
        (xy -18.714 0.966)
        (xy -18.731 0.95)
        (xy -18.746 0.934)
        (xy -18.761 0.917)
        (xy -18.775 0.898)
        (xy -18.788 0.878)
        (xy -18.801 0.858)
        (xy -18.813 0.838)
        (xy -18.822 0.817)
        (xy -18.831 0.796)
        (xy -18.839 0.774)
        (xy -18.845 0.751)
        (xy -18.851 0.729)
        (xy -18.856 0.706)
        (xy -18.859 0.684)
        (xy -18.86 0.66)
        (xy -18.86 0.637)
        (xy -18.415 0.637)
        (xy -18.415 0.632)
        (xy -18.415 0.633)
      )

      (stroke (width 0.001) (type solid)) (fill solid) (layer "B.Paste"))
    (fp_poly
      (pts
        (xy -17.145 -4.447)
        (xy -17.59 -4.446)
        (xy -17.589 -4.469)
        (xy -17.589 -4.493)
        (xy -17.586 -4.515)
        (xy -17.58 -4.538)
        (xy -17.575 -4.56)
        (xy -17.569 -4.583)
        (xy -17.561 -4.605)
        (xy -17.552 -4.626)
        (xy -17.543 -4.647)
        (xy -17.531 -4.668)
        (xy -17.519 -4.687)
        (xy -17.505 -4.706)
        (xy -17.491 -4.725)
        (xy -17.476 -4.743)
        (xy -17.461 -4.759)
        (xy -17.444 -4.775)
        (xy -17.426 -4.791)
        (xy -17.407 -4.804)
        (xy -17.389 -4.817)
        (xy -17.368 -4.831)
        (xy -17.348 -4.841)
        (xy -17.328 -4.852)
        (xy -17.305 -4.86)
        (xy -17.284 -4.868)
        (xy -17.261 -4.874)
        (xy -17.24 -4.879)
        (xy -17.217 -4.884)
        (xy -17.194 -4.887)
        (xy -17.17 -4.889)
        (xy -17.145 -4.889)
        (xy -17.122 -4.889)
        (xy -17.098 -4.887)
        (xy -17.075 -4.884)
        (xy -17.052 -4.879)
        (xy -17.031 -4.874)
        (xy -17.008 -4.868)
        (xy -16.987 -4.86)
        (xy -16.964 -4.852)
        (xy -16.944 -4.841)
        (xy -16.923 -4.829)
        (xy -16.903 -4.817)
        (xy -16.883 -4.804)
        (xy -16.865 -4.791)
        (xy -16.848 -4.775)
        (xy -16.83 -4.759)
        (xy -16.814 -4.743)
        (xy -16.799 -4.724)
        (xy -16.785 -4.706)
        (xy -16.772 -4.687)
        (xy -16.761 -4.668)
        (xy -16.749 -4.647)
        (xy -16.738 -4.626)
        (xy -16.731 -4.603)
        (xy -16.723 -4.583)
        (xy -16.715 -4.559)
        (xy -16.711 -4.538)
        (xy -16.705 -4.514)
        (xy -16.703 -4.491)
        (xy -16.702 -4.467)
        (xy -16.7 -4.445)
        (xy -16.702 -4.421)
        (xy -16.703 -4.397)
        (xy -16.705 -4.374)
        (xy -16.711 -4.352)
        (xy -16.715 -4.329)
        (xy -16.723 -4.307)
        (xy -16.731 -4.285)
        (xy -16.738 -4.264)
        (xy -16.749 -4.243)
        (xy -16.761 -4.222)
        (xy -16.772 -4.203)
        (xy -16.785 -4.182)
        (xy -16.799 -4.164)
        (xy -16.814 -4.147)
        (xy -16.83 -4.129)
        (xy -16.848 -4.113)
        (xy -16.865 -4.099)
        (xy -16.883 -4.084)
        (xy -16.903 -4.071)
        (xy -16.923 -4.059)
        (xy -16.944 -4.049)
        (xy -16.964 -4.038)
        (xy -16.987 -4.03)
        (xy -17.008 -4.022)
        (xy -17.031 -4.014)
        (xy -17.052 -4.009)
        (xy -17.075 -4.004)
        (xy -17.098 -4.001)
        (xy -17.122 -4.001)
        (xy -17.145 -3.999)
        (xy -17.17 -4.001)
        (xy -17.194 -4.001)
        (xy -17.217 -4.004)
        (xy -17.24 -4.009)
        (xy -17.261 -4.014)
        (xy -17.284 -4.022)
        (xy -17.305 -4.028)
        (xy -17.328 -4.038)
        (xy -17.348 -4.047)
        (xy -17.368 -4.059)
        (xy -17.389 -4.071)
        (xy -17.407 -4.084)
        (xy -17.426 -4.099)
        (xy -17.444 -4.113)
        (xy -17.461 -4.129)
        (xy -17.476 -4.147)
        (xy -17.491 -4.163)
        (xy -17.505 -4.182)
        (xy -17.519 -4.201)
        (xy -17.531 -4.222)
        (xy -17.543 -4.241)
        (xy -17.552 -4.262)
        (xy -17.561 -4.285)
        (xy -17.569 -4.307)
        (xy -17.575 -4.328)
        (xy -17.58 -4.35)
        (xy -17.586 -4.373)
        (xy -17.589 -4.397)
        (xy -17.589 -4.421)
        (xy -17.59 -4.442)
        (xy -17.145 -4.442)
        (xy -17.145 -4.446)
        (xy -17.145 -4.447)
      )

      (stroke (width 0.001) (type solid)) (fill solid) (layer "B.Paste"))
    (fp_poly
      (pts
        (xy -17.145 -1.907)
        (xy -17.59 -1.906)
        (xy -17.589 -1.929)
        (xy -17.589 -1.953)
        (xy -17.586 -1.975)
        (xy -17.58 -1.999)
        (xy -17.575 -2.02)
        (xy -17.569 -2.043)
        (xy -17.561 -2.064)
        (xy -17.552 -2.087)
        (xy -17.543 -2.108)
        (xy -17.531 -2.128)
        (xy -17.519 -2.148)
        (xy -17.505 -2.166)
        (xy -17.491 -2.185)
        (xy -17.476 -2.202)
        (xy -17.461 -2.22)
        (xy -17.444 -2.236)
        (xy -17.426 -2.25)
        (xy -17.407 -2.265)
        (xy -17.389 -2.277)
        (xy -17.368 -2.29)
        (xy -17.348 -2.301)
        (xy -17.328 -2.311)
        (xy -17.305 -2.321)
        (xy -17.284 -2.327)
        (xy -17.261 -2.334)
        (xy -17.24 -2.339)
        (xy -17.217 -2.345)
        (xy -17.194 -2.347)
        (xy -17.17 -2.349)
        (xy -17.145 -2.35)
        (xy -17.122 -2.349)
        (xy -17.098 -2.347)
        (xy -17.075 -2.345)
        (xy -17.052 -2.339)
        (xy -17.031 -2.334)
        (xy -17.008 -2.327)
        (xy -16.987 -2.319)
        (xy -16.964 -2.311)
        (xy -16.944 -2.301)
        (xy -16.923 -2.289)
        (xy -16.903 -2.277)
        (xy -16.883 -2.265)
        (xy -16.865 -2.25)
        (xy -16.848 -2.236)
        (xy -16.83 -2.22)
        (xy -16.814 -2.202)
        (xy -16.799 -2.185)
        (xy -16.785 -2.166)
        (xy -16.772 -2.146)
        (xy -16.761 -2.126)
        (xy -16.749 -2.107)
        (xy -16.738 -2.085)
        (xy -16.731 -2.064)
        (xy -16.723 -2.043)
        (xy -16.715 -2.019)
        (xy -16.711 -1.997)
        (xy -16.705 -1.975)
        (xy -16.703 -1.951)
        (xy -16.702 -1.927)
        (xy -16.7 -1.904)
        (xy -16.702 -1.881)
        (xy -16.703 -1.858)
        (xy -16.705 -1.834)
        (xy -16.711 -1.812)
        (xy -16.715 -1.789)
        (xy -16.723 -1.766)
        (xy -16.731 -1.745)
        (xy -16.738 -1.723)
        (xy -16.749 -1.703)
        (xy -16.761 -1.683)
        (xy -16.772 -1.662)
        (xy -16.785 -1.642)
        (xy -16.799 -1.624)
        (xy -16.814 -1.606)
        (xy -16.83 -1.59)
        (xy -16.848 -1.574)
        (xy -16.865 -1.558)
        (xy -16.883 -1.544)
        (xy -16.903 -1.531)
        (xy -16.923 -1.519)
        (xy -16.944 -1.508)
        (xy -16.964 -1.497)
        (xy -16.987 -1.489)
        (xy -17.008 -1.481)
        (xy -17.031 -1.475)
        (xy -17.052 -1.469)
        (xy -17.075 -1.465)
        (xy -17.098 -1.461)
        (xy -17.122 -1.461)
        (xy -17.145 -1.459)
        (xy -17.17 -1.461)
        (xy -17.194 -1.461)
        (xy -17.217 -1.465)
        (xy -17.24 -1.469)
        (xy -17.261 -1.475)
        (xy -17.284 -1.481)
        (xy -17.305 -1.489)
        (xy -17.328 -1.497)
        (xy -17.348 -1.507)
        (xy -17.368 -1.518)
        (xy -17.389 -1.531)
        (xy -17.407 -1.544)
        (xy -17.426 -1.558)
        (xy -17.444 -1.574)
        (xy -17.461 -1.59)
        (xy -17.476 -1.606)
        (xy -17.491 -1.624)
        (xy -17.505 -1.642)
        (xy -17.519 -1.661)
        (xy -17.531 -1.681)
        (xy -17.543 -1.701)
        (xy -17.552 -1.723)
        (xy -17.561 -1.745)
        (xy -17.569 -1.766)
        (xy -17.575 -1.788)
        (xy -17.58 -1.81)
        (xy -17.586 -1.834)
        (xy -17.589 -1.856)
        (xy -17.589 -1.88)
        (xy -17.59 -1.902)
        (xy -17.145 -1.902)
        (xy -17.145 -1.906)
        (xy -17.145 -1.907)
      )

      (stroke (width 0.001) (type solid)) (fill solid) (layer "B.Paste"))
    (fp_poly
      (pts
        (xy -17.145 -0.637)
        (xy -17.59 -0.636)
        (xy -17.589 -0.659)
        (xy -17.589 -0.683)
        (xy -17.586 -0.705)
        (xy -17.58 -0.728)
        (xy -17.575 -0.75)
        (xy -17.569 -0.773)
        (xy -17.561 -0.795)
        (xy -17.552 -0.816)
        (xy -17.543 -0.837)
        (xy -17.531 -0.857)
        (xy -17.519 -0.877)
        (xy -17.505 -0.897)
        (xy -17.491 -0.916)
        (xy -17.476 -0.933)
        (xy -17.461 -0.949)
        (xy -17.444 -0.965)
        (xy -17.426 -0.98)
        (xy -17.407 -0.994)
        (xy -17.389 -1.007)
        (xy -17.368 -1.02)
        (xy -17.348 -1.032)
        (xy -17.328 -1.042)
        (xy -17.305 -1.05)
        (xy -17.284 -1.058)
        (xy -17.261 -1.064)
        (xy -17.24 -1.07)
        (xy -17.217 -1.074)
        (xy -17.194 -1.078)
        (xy -17.17 -1.078)
        (xy -17.145 -1.08)
        (xy -17.122 -1.078)
        (xy -17.098 -1.078)
        (xy -17.075 -1.074)
        (xy -17.052 -1.07)
        (xy -17.031 -1.064)
        (xy -17.008 -1.058)
        (xy -16.987 -1.05)
        (xy -16.964 -1.042)
        (xy -16.944 -1.03)
        (xy -16.923 -1.019)
        (xy -16.903 -1.007)
        (xy -16.883 -0.994)
        (xy -16.865 -0.98)
        (xy -16.848 -0.965)
        (xy -16.83 -0.949)
        (xy -16.814 -0.933)
        (xy -16.799 -0.915)
        (xy -16.785 -0.897)
        (xy -16.772 -0.876)
        (xy -16.761 -0.856)
        (xy -16.749 -0.836)
        (xy -16.738 -0.815)
        (xy -16.731 -0.794)
        (xy -16.723 -0.773)
        (xy -16.715 -0.749)
        (xy -16.711 -0.727)
        (xy -16.705 -0.704)
        (xy -16.703 -0.682)
        (xy -16.702 -0.658)
        (xy -16.7 -0.634)
        (xy -16.702 -0.611)
        (xy -16.703 -0.587)
        (xy -16.705 -0.564)
        (xy -16.711 -0.542)
        (xy -16.715 -0.52)
        (xy -16.723 -0.496)
        (xy -16.731 -0.475)
        (xy -16.738 -0.454)
        (xy -16.749 -0.432)
        (xy -16.761 -0.412)
        (xy -16.772 -0.393)
        (xy -16.785 -0.372)
        (xy -16.799 -0.354)
        (xy -16.814 -0.337)
        (xy -16.83 -0.32)
        (xy -16.848 -0.303)
        (xy -16.865 -0.288)
        (xy -16.883 -0.275)
        (xy -16.903 -0.262)
        (xy -16.923 -0.249)
        (xy -16.944 -0.238)
        (xy -16.964 -0.228)
        (xy -16.987 -0.219)
        (xy -17.008 -0.211)
        (xy -17.031 -0.204)
        (xy -17.052 -0.2)
        (xy -17.075 -0.195)
        (xy -17.098 -0.192)
        (xy -17.122 -0.19)
        (xy -17.145 -0.189)
        (xy -17.17 -0.19)
        (xy -17.194 -0.192)
        (xy -17.217 -0.195)
        (xy -17.24 -0.2)
        (xy -17.261 -0.204)
        (xy -17.284 -0.211)
        (xy -17.305 -0.218)
        (xy -17.328 -0.228)
        (xy -17.348 -0.237)
        (xy -17.368 -0.248)
        (xy -17.389 -0.262)
        (xy -17.407 -0.275)
        (xy -17.426 -0.288)
        (xy -17.444 -0.303)
        (xy -17.461 -0.32)
        (xy -17.476 -0.337)
        (xy -17.491 -0.353)
        (xy -17.505 -0.372)
        (xy -17.519 -0.392)
        (xy -17.531 -0.411)
        (xy -17.543 -0.431)
        (xy -17.552 -0.453)
        (xy -17.561 -0.474)
        (xy -17.569 -0.496)
        (xy -17.575 -0.519)
        (xy -17.58 -0.541)
        (xy -17.586 -0.563)
        (xy -17.589 -0.586)
        (xy -17.589 -0.61)
        (xy -17.59 -0.631)
        (xy -17.145 -0.631)
        (xy -17.145 -0.636)
        (xy -17.145 -0.637)
      )

      (stroke (width 0.001) (type solid)) (fill solid) (layer "B.Paste"))
    (fp_poly
      (pts
        (xy -17.145 0.633)
        (xy -17.59 0.632)
        (xy -17.589 0.611)
        (xy -17.589 0.587)
        (xy -17.586 0.564)
        (xy -17.58 0.542)
        (xy -17.575 0.52)
        (xy -17.569 0.497)
        (xy -17.561 0.475)
        (xy -17.552 0.454)
        (xy -17.543 0.432)
        (xy -17.531 0.412)
        (xy -17.519 0.393)
        (xy -17.505 0.373)
        (xy -17.491 0.354)
        (xy -17.476 0.338)
        (xy -17.461 0.32)
        (xy -17.444 0.304)
        (xy -17.426 0.289)
        (xy -17.407 0.276)
        (xy -17.389 0.263)
        (xy -17.368 0.249)
        (xy -17.348 0.238)
        (xy -17.328 0.229)
        (xy -17.305 0.219)
        (xy -17.284 0.212)
        (xy -17.261 0.205)
        (xy -17.24 0.201)
        (xy -17.217 0.196)
        (xy -17.194 0.192)
        (xy -17.17 0.191)
        (xy -17.145 0.19)
        (xy -17.122 0.191)
        (xy -17.098 0.192)
        (xy -17.075 0.196)
        (xy -17.052 0.201)
        (xy -17.031 0.205)
        (xy -17.008 0.212)
        (xy -16.987 0.22)
        (xy -16.964 0.229)
        (xy -16.944 0.239)
        (xy -16.923 0.25)
        (xy -16.903 0.263)
        (xy -16.883 0.276)
        (xy -16.865 0.289)
        (xy -16.848 0.304)
        (xy -16.83 0.32)
        (xy -16.814 0.338)
        (xy -16.799 0.355)
        (xy -16.785 0.373)
        (xy -16.772 0.394)
        (xy -16.761 0.413)
        (xy -16.749 0.433)
        (xy -16.738 0.455)
        (xy -16.731 0.476)
        (xy -16.723 0.497)
        (xy -16.715 0.521)
        (xy -16.711 0.543)
        (xy -16.705 0.565)
        (xy -16.703 0.588)
        (xy -16.702 0.612)
        (xy -16.7 0.635)
        (xy -16.702 0.659)
        (xy -16.703 0.683)
        (xy -16.705 0.705)
        (xy -16.711 0.728)
        (xy -16.715 0.75)
        (xy -16.723 0.774)
        (xy -16.731 0.795)
        (xy -16.738 0.816)
        (xy -16.749 0.837)
        (xy -16.761 0.857)
        (xy -16.772 0.877)
        (xy -16.785 0.898)
        (xy -16.799 0.916)
        (xy -16.814 0.934)
        (xy -16.83 0.95)
        (xy -16.848 0.966)
        (xy -16.865 0.981)
        (xy -16.883 0.995)
        (xy -16.903 1.008)
        (xy -16.923 1.02)
        (xy -16.944 1.031)
        (xy -16.964 1.043)
        (xy -16.987 1.051)
        (xy -17.008 1.059)
        (xy -17.031 1.065)
        (xy -17.052 1.071)
        (xy -17.075 1.075)
        (xy -17.098 1.079)
        (xy -17.122 1.079)
        (xy -17.145 1.081)
        (xy -17.17 1.079)
        (xy -17.194 1.079)
        (xy -17.217 1.075)
        (xy -17.24 1.071)
        (xy -17.261 1.065)
        (xy -17.284 1.059)
        (xy -17.305 1.051)
        (xy -17.328 1.043)
        (xy -17.348 1.033)
        (xy -17.368 1.021)
        (xy -17.389 1.008)
        (xy -17.407 0.995)
        (xy -17.426 0.981)
        (xy -17.444 0.966)
        (xy -17.461 0.95)
        (xy -17.476 0.934)
        (xy -17.491 0.917)
        (xy -17.505 0.898)
        (xy -17.519 0.878)
        (xy -17.531 0.858)
        (xy -17.543 0.838)
        (xy -17.552 0.817)
        (xy -17.561 0.796)
        (xy -17.569 0.774)
        (xy -17.575 0.751)
        (xy -17.58 0.729)
        (xy -17.586 0.706)
        (xy -17.589 0.684)
        (xy -17.589 0.66)
        (xy -17.59 0.637)
        (xy -17.145 0.637)
        (xy -17.145 0.632)
        (xy -17.145 0.633)
      )

      (stroke (width 0.001) (type solid)) (fill solid) (layer "B.Paste"))
    (fp_poly
      (pts
        (xy -15.875 -4.447)
        (xy -16.32 -4.446)
        (xy -16.319 -4.469)
        (xy -16.319 -4.493)
        (xy -16.316 -4.515)
        (xy -16.31 -4.538)
        (xy -16.305 -4.56)
        (xy -16.298 -4.583)
        (xy -16.292 -4.605)
        (xy -16.282 -4.626)
        (xy -16.272 -4.647)
        (xy -16.261 -4.668)
        (xy -16.249 -4.687)
        (xy -16.235 -4.706)
        (xy -16.221 -4.725)
        (xy -16.206 -4.743)
        (xy -16.191 -4.759)
        (xy -16.173 -4.775)
        (xy -16.156 -4.791)
        (xy -16.138 -4.804)
        (xy -16.118 -4.817)
        (xy -16.098 -4.831)
        (xy -16.078 -4.841)
        (xy -16.057 -4.852)
        (xy -16.035 -4.86)
        (xy -16.014 -4.868)
        (xy -15.991 -4.874)
        (xy -15.969 -4.879)
        (xy -15.946 -4.884)
        (xy -15.923 -4.887)
        (xy -15.899 -4.889)
        (xy -15.875 -4.889)
        (xy -15.852 -4.889)
        (xy -15.828 -4.887)
        (xy -15.805 -4.884)
        (xy -15.782 -4.879)
        (xy -15.76 -4.874)
        (xy -15.737 -4.868)
        (xy -15.716 -4.86)
        (xy -15.695 -4.852)
        (xy -15.673 -4.841)
        (xy -15.652 -4.829)
        (xy -15.633 -4.817)
        (xy -15.613 -4.804)
        (xy -15.596 -4.791)
        (xy -15.577 -4.775)
        (xy -15.561 -4.759)
        (xy -15.545 -4.743)
        (xy -15.529 -4.724)
        (xy -15.516 -4.706)
        (xy -15.503 -4.687)
        (xy -15.49 -4.668)
        (xy -15.479 -4.647)
        (xy -15.468 -4.626)
        (xy -15.461 -4.603)
        (xy -15.452 -4.583)
        (xy -15.445 -4.559)
        (xy -15.44 -4.538)
        (xy -15.436 -4.514)
        (xy -15.433 -4.491)
        (xy -15.431 -4.467)
        (xy -15.43 -4.445)
        (xy -15.431 -4.421)
        (xy -15.433 -4.397)
        (xy -15.436 -4.374)
        (xy -15.44 -4.352)
        (xy -15.445 -4.329)
        (xy -15.452 -4.307)
        (xy -15.461 -4.285)
        (xy -15.468 -4.264)
        (xy -15.479 -4.243)
        (xy -15.49 -4.222)
        (xy -15.503 -4.203)
        (xy -15.516 -4.182)
        (xy -15.529 -4.164)
        (xy -15.545 -4.147)
        (xy -15.561 -4.129)
        (xy -15.577 -4.113)
        (xy -15.596 -4.099)
        (xy -15.613 -4.084)
        (xy -15.633 -4.071)
        (xy -15.652 -4.059)
        (xy -15.673 -4.049)
        (xy -15.695 -4.038)
        (xy -15.716 -4.03)
        (xy -15.737 -4.022)
        (xy -15.76 -4.014)
        (xy -15.782 -4.009)
        (xy -15.805 -4.004)
        (xy -15.828 -4.001)
        (xy -15.852 -4.001)
        (xy -15.875 -3.999)
        (xy -15.899 -4.001)
        (xy -15.923 -4.001)
        (xy -15.946 -4.004)
        (xy -15.969 -4.009)
        (xy -15.991 -4.014)
        (xy -16.014 -4.022)
        (xy -16.035 -4.028)
        (xy -16.057 -4.038)
        (xy -16.078 -4.047)
        (xy -16.098 -4.059)
        (xy -16.118 -4.071)
        (xy -16.138 -4.084)
        (xy -16.156 -4.099)
        (xy -16.173 -4.113)
        (xy -16.191 -4.129)
        (xy -16.206 -4.147)
        (xy -16.221 -4.163)
        (xy -16.235 -4.182)
        (xy -16.249 -4.201)
        (xy -16.261 -4.222)
        (xy -16.272 -4.241)
        (xy -16.282 -4.262)
        (xy -16.292 -4.285)
        (xy -16.298 -4.307)
        (xy -16.305 -4.328)
        (xy -16.31 -4.35)
        (xy -16.316 -4.373)
        (xy -16.319 -4.397)
        (xy -16.319 -4.421)
        (xy -16.32 -4.442)
        (xy -15.875 -4.442)
        (xy -15.875 -4.446)
        (xy -15.875 -4.447)
      )

      (stroke (width 0.001) (type solid)) (fill solid) (layer "B.Paste"))
    (fp_poly
      (pts
        (xy -15.875 -1.907)
        (xy -16.32 -1.906)
        (xy -16.319 -1.929)
        (xy -16.319 -1.953)
        (xy -16.316 -1.975)
        (xy -16.31 -1.999)
        (xy -16.305 -2.02)
        (xy -16.298 -2.043)
        (xy -16.292 -2.064)
        (xy -16.282 -2.087)
        (xy -16.272 -2.108)
        (xy -16.261 -2.128)
        (xy -16.249 -2.148)
        (xy -16.235 -2.166)
        (xy -16.221 -2.185)
        (xy -16.206 -2.202)
        (xy -16.191 -2.22)
        (xy -16.173 -2.236)
        (xy -16.156 -2.25)
        (xy -16.138 -2.265)
        (xy -16.118 -2.277)
        (xy -16.098 -2.29)
        (xy -16.078 -2.301)
        (xy -16.057 -2.311)
        (xy -16.035 -2.321)
        (xy -16.014 -2.327)
        (xy -15.991 -2.334)
        (xy -15.969 -2.339)
        (xy -15.946 -2.345)
        (xy -15.923 -2.347)
        (xy -15.899 -2.349)
        (xy -15.875 -2.35)
        (xy -15.852 -2.349)
        (xy -15.828 -2.347)
        (xy -15.805 -2.345)
        (xy -15.782 -2.339)
        (xy -15.76 -2.334)
        (xy -15.737 -2.327)
        (xy -15.716 -2.319)
        (xy -15.695 -2.311)
        (xy -15.673 -2.301)
        (xy -15.652 -2.289)
        (xy -15.633 -2.277)
        (xy -15.613 -2.265)
        (xy -15.596 -2.25)
        (xy -15.577 -2.236)
        (xy -15.561 -2.22)
        (xy -15.545 -2.202)
        (xy -15.529 -2.185)
        (xy -15.516 -2.166)
        (xy -15.503 -2.146)
        (xy -15.49 -2.126)
        (xy -15.479 -2.107)
        (xy -15.468 -2.085)
        (xy -15.461 -2.064)
        (xy -15.452 -2.043)
        (xy -15.445 -2.019)
        (xy -15.44 -1.997)
        (xy -15.436 -1.975)
        (xy -15.433 -1.951)
        (xy -15.431 -1.927)
        (xy -15.43 -1.904)
        (xy -15.431 -1.881)
        (xy -15.433 -1.858)
        (xy -15.436 -1.834)
        (xy -15.44 -1.812)
        (xy -15.445 -1.789)
        (xy -15.452 -1.766)
        (xy -15.461 -1.745)
        (xy -15.468 -1.723)
        (xy -15.479 -1.703)
        (xy -15.49 -1.683)
        (xy -15.503 -1.662)
        (xy -15.516 -1.642)
        (xy -15.529 -1.624)
        (xy -15.545 -1.606)
        (xy -15.561 -1.59)
        (xy -15.577 -1.574)
        (xy -15.596 -1.558)
        (xy -15.613 -1.544)
        (xy -15.633 -1.531)
        (xy -15.652 -1.519)
        (xy -15.673 -1.508)
        (xy -15.695 -1.497)
        (xy -15.716 -1.489)
        (xy -15.737 -1.481)
        (xy -15.76 -1.475)
        (xy -15.782 -1.469)
        (xy -15.805 -1.465)
        (xy -15.828 -1.461)
        (xy -15.852 -1.461)
        (xy -15.875 -1.459)
        (xy -15.899 -1.461)
        (xy -15.923 -1.461)
        (xy -15.946 -1.465)
        (xy -15.969 -1.469)
        (xy -15.991 -1.475)
        (xy -16.014 -1.481)
        (xy -16.035 -1.489)
        (xy -16.057 -1.497)
        (xy -16.078 -1.507)
        (xy -16.098 -1.518)
        (xy -16.118 -1.531)
        (xy -16.138 -1.544)
        (xy -16.156 -1.558)
        (xy -16.173 -1.574)
        (xy -16.191 -1.59)
        (xy -16.206 -1.606)
        (xy -16.221 -1.624)
        (xy -16.235 -1.642)
        (xy -16.249 -1.661)
        (xy -16.261 -1.681)
        (xy -16.272 -1.701)
        (xy -16.282 -1.723)
        (xy -16.292 -1.745)
        (xy -16.298 -1.766)
        (xy -16.305 -1.788)
        (xy -16.31 -1.81)
        (xy -16.316 -1.834)
        (xy -16.319 -1.856)
        (xy -16.319 -1.88)
        (xy -16.32 -1.902)
        (xy -15.875 -1.902)
        (xy -15.875 -1.906)
        (xy -15.875 -1.907)
      )

      (stroke (width 0.001) (type solid)) (fill solid) (layer "B.Paste"))
    (fp_poly
      (pts
        (xy -15.875 -0.637)
        (xy -16.32 -0.636)
        (xy -16.319 -0.659)
        (xy -16.319 -0.683)
        (xy -16.316 -0.705)
        (xy -16.31 -0.728)
        (xy -16.305 -0.75)
        (xy -16.298 -0.773)
        (xy -16.292 -0.795)
        (xy -16.282 -0.816)
        (xy -16.272 -0.837)
        (xy -16.261 -0.857)
        (xy -16.249 -0.877)
        (xy -16.235 -0.897)
        (xy -16.221 -0.916)
        (xy -16.206 -0.933)
        (xy -16.191 -0.949)
        (xy -16.173 -0.965)
        (xy -16.156 -0.98)
        (xy -16.138 -0.994)
        (xy -16.118 -1.007)
        (xy -16.098 -1.02)
        (xy -16.078 -1.032)
        (xy -16.057 -1.042)
        (xy -16.035 -1.05)
        (xy -16.014 -1.058)
        (xy -15.991 -1.064)
        (xy -15.969 -1.07)
        (xy -15.946 -1.074)
        (xy -15.923 -1.078)
        (xy -15.899 -1.078)
        (xy -15.875 -1.08)
        (xy -15.852 -1.078)
        (xy -15.828 -1.078)
        (xy -15.805 -1.074)
        (xy -15.782 -1.07)
        (xy -15.76 -1.064)
        (xy -15.737 -1.058)
        (xy -15.716 -1.05)
        (xy -15.695 -1.042)
        (xy -15.673 -1.03)
        (xy -15.652 -1.019)
        (xy -15.633 -1.007)
        (xy -15.613 -0.994)
        (xy -15.596 -0.98)
        (xy -15.577 -0.965)
        (xy -15.561 -0.949)
        (xy -15.545 -0.933)
        (xy -15.529 -0.915)
        (xy -15.516 -0.897)
        (xy -15.503 -0.876)
        (xy -15.49 -0.856)
        (xy -15.479 -0.836)
        (xy -15.468 -0.815)
        (xy -15.461 -0.794)
        (xy -15.452 -0.773)
        (xy -15.445 -0.749)
        (xy -15.44 -0.727)
        (xy -15.436 -0.704)
        (xy -15.433 -0.682)
        (xy -15.431 -0.658)
        (xy -15.43 -0.634)
        (xy -15.431 -0.611)
        (xy -15.433 -0.587)
        (xy -15.436 -0.564)
        (xy -15.44 -0.542)
        (xy -15.445 -0.52)
        (xy -15.452 -0.496)
        (xy -15.461 -0.475)
        (xy -15.468 -0.454)
        (xy -15.479 -0.432)
        (xy -15.49 -0.412)
        (xy -15.503 -0.393)
        (xy -15.516 -0.372)
        (xy -15.529 -0.354)
        (xy -15.545 -0.337)
        (xy -15.561 -0.32)
        (xy -15.577 -0.303)
        (xy -15.596 -0.288)
        (xy -15.613 -0.275)
        (xy -15.633 -0.262)
        (xy -15.652 -0.249)
        (xy -15.673 -0.238)
        (xy -15.695 -0.228)
        (xy -15.716 -0.219)
        (xy -15.737 -0.211)
        (xy -15.76 -0.204)
        (xy -15.782 -0.2)
        (xy -15.805 -0.195)
        (xy -15.828 -0.192)
        (xy -15.852 -0.19)
        (xy -15.875 -0.189)
        (xy -15.899 -0.19)
        (xy -15.923 -0.192)
        (xy -15.946 -0.195)
        (xy -15.969 -0.2)
        (xy -15.991 -0.204)
        (xy -16.014 -0.211)
        (xy -16.035 -0.218)
        (xy -16.057 -0.228)
        (xy -16.078 -0.237)
        (xy -16.098 -0.248)
        (xy -16.118 -0.262)
        (xy -16.138 -0.275)
        (xy -16.156 -0.288)
        (xy -16.173 -0.303)
        (xy -16.191 -0.32)
        (xy -16.206 -0.337)
        (xy -16.221 -0.353)
        (xy -16.235 -0.372)
        (xy -16.249 -0.392)
        (xy -16.261 -0.411)
        (xy -16.272 -0.431)
        (xy -16.282 -0.453)
        (xy -16.292 -0.474)
        (xy -16.298 -0.496)
        (xy -16.305 -0.519)
        (xy -16.31 -0.541)
        (xy -16.316 -0.563)
        (xy -16.319 -0.586)
        (xy -16.319 -0.61)
        (xy -16.32 -0.631)
        (xy -15.875 -0.631)
        (xy -15.875 -0.636)
        (xy -15.875 -0.637)
      )

      (stroke (width 0.001) (type solid)) (fill solid) (layer "B.Paste"))
    (fp_poly
      (pts
        (xy -15.875 0.633)
        (xy -16.32 0.632)
        (xy -16.319 0.611)
        (xy -16.319 0.587)
        (xy -16.316 0.564)
        (xy -16.31 0.542)
        (xy -16.305 0.52)
        (xy -16.298 0.497)
        (xy -16.292 0.475)
        (xy -16.282 0.454)
        (xy -16.272 0.432)
        (xy -16.261 0.412)
        (xy -16.249 0.393)
        (xy -16.235 0.373)
        (xy -16.221 0.354)
        (xy -16.206 0.338)
        (xy -16.191 0.32)
        (xy -16.173 0.304)
        (xy -16.156 0.289)
        (xy -16.138 0.276)
        (xy -16.118 0.263)
        (xy -16.098 0.249)
        (xy -16.078 0.238)
        (xy -16.057 0.229)
        (xy -16.035 0.219)
        (xy -16.014 0.212)
        (xy -15.991 0.205)
        (xy -15.969 0.201)
        (xy -15.946 0.196)
        (xy -15.923 0.192)
        (xy -15.899 0.191)
        (xy -15.875 0.19)
        (xy -15.852 0.191)
        (xy -15.828 0.192)
        (xy -15.805 0.196)
        (xy -15.782 0.201)
        (xy -15.76 0.205)
        (xy -15.737 0.212)
        (xy -15.716 0.22)
        (xy -15.695 0.229)
        (xy -15.673 0.239)
        (xy -15.652 0.25)
        (xy -15.633 0.263)
        (xy -15.613 0.276)
        (xy -15.596 0.289)
        (xy -15.577 0.304)
        (xy -15.561 0.32)
        (xy -15.545 0.338)
        (xy -15.529 0.355)
        (xy -15.516 0.373)
        (xy -15.503 0.394)
        (xy -15.49 0.413)
        (xy -15.479 0.433)
        (xy -15.468 0.455)
        (xy -15.461 0.476)
        (xy -15.452 0.497)
        (xy -15.445 0.521)
        (xy -15.44 0.543)
        (xy -15.436 0.565)
        (xy -15.433 0.588)
        (xy -15.431 0.612)
        (xy -15.43 0.635)
        (xy -15.431 0.659)
        (xy -15.433 0.683)
        (xy -15.436 0.705)
        (xy -15.44 0.728)
        (xy -15.445 0.75)
        (xy -15.452 0.774)
        (xy -15.461 0.795)
        (xy -15.468 0.816)
        (xy -15.479 0.837)
        (xy -15.49 0.857)
        (xy -15.503 0.877)
        (xy -15.516 0.898)
        (xy -15.529 0.916)
        (xy -15.545 0.934)
        (xy -15.561 0.95)
        (xy -15.577 0.966)
        (xy -15.596 0.981)
        (xy -15.613 0.995)
        (xy -15.633 1.008)
        (xy -15.652 1.02)
        (xy -15.673 1.031)
        (xy -15.695 1.043)
        (xy -15.716 1.051)
        (xy -15.737 1.059)
        (xy -15.76 1.065)
        (xy -15.782 1.071)
        (xy -15.805 1.075)
        (xy -15.828 1.079)
        (xy -15.852 1.079)
        (xy -15.875 1.081)
        (xy -15.899 1.079)
        (xy -15.923 1.079)
        (xy -15.946 1.075)
        (xy -15.969 1.071)
        (xy -15.991 1.065)
        (xy -16.014 1.059)
        (xy -16.035 1.051)
        (xy -16.057 1.043)
        (xy -16.078 1.033)
        (xy -16.098 1.021)
        (xy -16.118 1.008)
        (xy -16.138 0.995)
        (xy -16.156 0.981)
        (xy -16.173 0.966)
        (xy -16.191 0.95)
        (xy -16.206 0.934)
        (xy -16.221 0.917)
        (xy -16.235 0.898)
        (xy -16.249 0.878)
        (xy -16.261 0.858)
        (xy -16.272 0.838)
        (xy -16.282 0.817)
        (xy -16.292 0.796)
        (xy -16.298 0.774)
        (xy -16.305 0.751)
        (xy -16.31 0.729)
        (xy -16.316 0.706)
        (xy -16.319 0.684)
        (xy -16.319 0.66)
        (xy -16.32 0.637)
        (xy -15.875 0.637)
        (xy -15.875 0.632)
        (xy -15.875 0.633)
      )

      (stroke (width 0.001) (type solid)) (fill solid) (layer "B.Paste"))
    (fp_poly
      (pts
        (xy -14.606 -4.447)
        (xy -15.051 -4.446)
        (xy -15.049 -4.469)
        (xy -15.048 -4.493)
        (xy -15.045 -4.515)
        (xy -15.04 -4.538)
        (xy -15.035 -4.56)
        (xy -15.029 -4.583)
        (xy -15.022 -4.605)
        (xy -15.013 -4.626)
        (xy -15.003 -4.647)
        (xy -14.991 -4.668)
        (xy -14.978 -4.687)
        (xy -14.965 -4.706)
        (xy -14.952 -4.725)
        (xy -14.936 -4.743)
        (xy -14.92 -4.759)
        (xy -14.904 -4.775)
        (xy -14.886 -4.791)
        (xy -14.868 -4.804)
        (xy -14.849 -4.817)
        (xy -14.828 -4.831)
        (xy -14.808 -4.841)
        (xy -14.788 -4.852)
        (xy -14.766 -4.86)
        (xy -14.744 -4.868)
        (xy -14.721 -4.874)
        (xy -14.699 -4.879)
        (xy -14.676 -4.884)
        (xy -14.654 -4.887)
        (xy -14.629 -4.889)
        (xy -14.606 -4.889)
        (xy -14.583 -4.889)
        (xy -14.558 -4.887)
        (xy -14.535 -4.884)
        (xy -14.513 -4.879)
        (xy -14.49 -4.874)
        (xy -14.468 -4.868)
        (xy -14.446 -4.86)
        (xy -14.424 -4.852)
        (xy -14.404 -4.841)
        (xy -14.383 -4.829)
        (xy -14.363 -4.817)
        (xy -14.343 -4.804)
        (xy -14.325 -4.791)
        (xy -14.308 -4.775)
        (xy -14.29 -4.759)
        (xy -14.274 -4.743)
        (xy -14.26 -4.724)
        (xy -14.245 -4.706)
        (xy -14.232 -4.687)
        (xy -14.221 -4.668)
        (xy -14.209 -4.647)
        (xy -14.199 -4.626)
        (xy -14.19 -4.603)
        (xy -14.183 -4.583)
        (xy -14.176 -4.559)
        (xy -14.17 -4.538)
        (xy -14.165 -4.514)
        (xy -14.163 -4.491)
        (xy -14.161 -4.467)
        (xy -14.16 -4.445)
        (xy -14.161 -4.421)
        (xy -14.163 -4.397)
        (xy -14.165 -4.374)
        (xy -14.17 -4.352)
        (xy -14.176 -4.329)
        (xy -14.183 -4.307)
        (xy -14.19 -4.285)
        (xy -14.199 -4.264)
        (xy -14.209 -4.243)
        (xy -14.221 -4.222)
        (xy -14.232 -4.203)
        (xy -14.245 -4.182)
        (xy -14.26 -4.164)
        (xy -14.274 -4.147)
        (xy -14.29 -4.129)
        (xy -14.308 -4.113)
        (xy -14.325 -4.099)
        (xy -14.343 -4.084)
        (xy -14.363 -4.071)
        (xy -14.383 -4.059)
        (xy -14.404 -4.049)
        (xy -14.424 -4.038)
        (xy -14.446 -4.03)
        (xy -14.468 -4.022)
        (xy -14.49 -4.014)
        (xy -14.513 -4.009)
        (xy -14.535 -4.004)
        (xy -14.558 -4.001)
        (xy -14.583 -4.001)
        (xy -14.606 -3.999)
        (xy -14.629 -4.001)
        (xy -14.654 -4.001)
        (xy -14.676 -4.004)
        (xy -14.699 -4.009)
        (xy -14.721 -4.014)
        (xy -14.744 -4.022)
        (xy -14.766 -4.028)
        (xy -14.788 -4.038)
        (xy -14.808 -4.047)
        (xy -14.828 -4.059)
        (xy -14.849 -4.071)
        (xy -14.868 -4.084)
        (xy -14.886 -4.099)
        (xy -14.904 -4.113)
        (xy -14.92 -4.129)
        (xy -14.936 -4.147)
        (xy -14.952 -4.163)
        (xy -14.965 -4.182)
        (xy -14.978 -4.201)
        (xy -14.991 -4.222)
        (xy -15.003 -4.241)
        (xy -15.013 -4.262)
        (xy -15.022 -4.285)
        (xy -15.029 -4.307)
        (xy -15.035 -4.328)
        (xy -15.04 -4.35)
        (xy -15.045 -4.373)
        (xy -15.048 -4.397)
        (xy -15.049 -4.421)
        (xy -15.051 -4.442)
        (xy -14.606 -4.442)
        (xy -14.606 -4.446)
        (xy -14.606 -4.447)
      )

      (stroke (width 0.001) (type solid)) (fill solid) (layer "B.Paste"))
    (fp_poly
      (pts
        (xy -14.606 -1.907)
        (xy -15.051 -1.906)
        (xy -15.049 -1.929)
        (xy -15.048 -1.953)
        (xy -15.045 -1.975)
        (xy -15.04 -1.999)
        (xy -15.035 -2.02)
        (xy -15.029 -2.043)
        (xy -15.022 -2.064)
        (xy -15.013 -2.087)
        (xy -15.003 -2.108)
        (xy -14.991 -2.128)
        (xy -14.978 -2.148)
        (xy -14.965 -2.166)
        (xy -14.952 -2.185)
        (xy -14.936 -2.202)
        (xy -14.92 -2.22)
        (xy -14.904 -2.236)
        (xy -14.886 -2.25)
        (xy -14.868 -2.265)
        (xy -14.849 -2.277)
        (xy -14.828 -2.29)
        (xy -14.808 -2.301)
        (xy -14.788 -2.311)
        (xy -14.766 -2.321)
        (xy -14.744 -2.327)
        (xy -14.721 -2.334)
        (xy -14.699 -2.339)
        (xy -14.676 -2.345)
        (xy -14.654 -2.347)
        (xy -14.629 -2.349)
        (xy -14.606 -2.35)
        (xy -14.583 -2.349)
        (xy -14.558 -2.347)
        (xy -14.535 -2.345)
        (xy -14.513 -2.339)
        (xy -14.49 -2.334)
        (xy -14.468 -2.327)
        (xy -14.446 -2.319)
        (xy -14.424 -2.311)
        (xy -14.404 -2.301)
        (xy -14.383 -2.289)
        (xy -14.363 -2.277)
        (xy -14.343 -2.265)
        (xy -14.325 -2.25)
        (xy -14.308 -2.236)
        (xy -14.29 -2.22)
        (xy -14.274 -2.202)
        (xy -14.26 -2.185)
        (xy -14.245 -2.166)
        (xy -14.232 -2.146)
        (xy -14.221 -2.126)
        (xy -14.209 -2.107)
        (xy -14.199 -2.085)
        (xy -14.19 -2.064)
        (xy -14.183 -2.043)
        (xy -14.176 -2.019)
        (xy -14.17 -1.997)
        (xy -14.165 -1.975)
        (xy -14.163 -1.951)
        (xy -14.161 -1.927)
        (xy -14.16 -1.904)
        (xy -14.161 -1.881)
        (xy -14.163 -1.858)
        (xy -14.165 -1.834)
        (xy -14.17 -1.812)
        (xy -14.176 -1.789)
        (xy -14.183 -1.766)
        (xy -14.19 -1.745)
        (xy -14.199 -1.723)
        (xy -14.209 -1.703)
        (xy -14.221 -1.683)
        (xy -14.232 -1.662)
        (xy -14.245 -1.642)
        (xy -14.26 -1.624)
        (xy -14.274 -1.606)
        (xy -14.29 -1.59)
        (xy -14.308 -1.574)
        (xy -14.325 -1.558)
        (xy -14.343 -1.544)
        (xy -14.363 -1.531)
        (xy -14.383 -1.519)
        (xy -14.404 -1.508)
        (xy -14.424 -1.497)
        (xy -14.446 -1.489)
        (xy -14.468 -1.481)
        (xy -14.49 -1.475)
        (xy -14.513 -1.469)
        (xy -14.535 -1.465)
        (xy -14.558 -1.461)
        (xy -14.583 -1.461)
        (xy -14.606 -1.459)
        (xy -14.629 -1.461)
        (xy -14.654 -1.461)
        (xy -14.676 -1.465)
        (xy -14.699 -1.469)
        (xy -14.721 -1.475)
        (xy -14.744 -1.481)
        (xy -14.766 -1.489)
        (xy -14.788 -1.497)
        (xy -14.808 -1.507)
        (xy -14.828 -1.518)
        (xy -14.849 -1.531)
        (xy -14.868 -1.544)
        (xy -14.886 -1.558)
        (xy -14.904 -1.574)
        (xy -14.92 -1.59)
        (xy -14.936 -1.606)
        (xy -14.952 -1.624)
        (xy -14.965 -1.642)
        (xy -14.978 -1.661)
        (xy -14.991 -1.681)
        (xy -15.003 -1.701)
        (xy -15.013 -1.723)
        (xy -15.022 -1.745)
        (xy -15.029 -1.766)
        (xy -15.035 -1.788)
        (xy -15.04 -1.81)
        (xy -15.045 -1.834)
        (xy -15.048 -1.856)
        (xy -15.049 -1.88)
        (xy -15.051 -1.902)
        (xy -14.606 -1.902)
        (xy -14.606 -1.906)
        (xy -14.606 -1.907)
      )

      (stroke (width 0.001) (type solid)) (fill solid) (layer "B.Paste"))
    (fp_poly
      (pts
        (xy -14.606 -0.637)
        (xy -15.051 -0.636)
        (xy -15.049 -0.659)
        (xy -15.048 -0.683)
        (xy -15.045 -0.705)
        (xy -15.04 -0.728)
        (xy -15.035 -0.75)
        (xy -15.029 -0.773)
        (xy -15.022 -0.795)
        (xy -15.013 -0.816)
        (xy -15.003 -0.837)
        (xy -14.991 -0.857)
        (xy -14.978 -0.877)
        (xy -14.965 -0.897)
        (xy -14.952 -0.916)
        (xy -14.936 -0.933)
        (xy -14.92 -0.949)
        (xy -14.904 -0.965)
        (xy -14.886 -0.98)
        (xy -14.868 -0.994)
        (xy -14.849 -1.007)
        (xy -14.828 -1.02)
        (xy -14.808 -1.032)
        (xy -14.788 -1.042)
        (xy -14.766 -1.05)
        (xy -14.744 -1.058)
        (xy -14.721 -1.064)
        (xy -14.699 -1.07)
        (xy -14.676 -1.074)
        (xy -14.654 -1.078)
        (xy -14.629 -1.078)
        (xy -14.606 -1.08)
        (xy -14.583 -1.078)
        (xy -14.558 -1.078)
        (xy -14.535 -1.074)
        (xy -14.513 -1.07)
        (xy -14.49 -1.064)
        (xy -14.468 -1.058)
        (xy -14.446 -1.05)
        (xy -14.424 -1.042)
        (xy -14.404 -1.03)
        (xy -14.383 -1.019)
        (xy -14.363 -1.007)
        (xy -14.343 -0.994)
        (xy -14.325 -0.98)
        (xy -14.308 -0.965)
        (xy -14.29 -0.949)
        (xy -14.274 -0.933)
        (xy -14.26 -0.915)
        (xy -14.245 -0.897)
        (xy -14.232 -0.876)
        (xy -14.221 -0.856)
        (xy -14.209 -0.836)
        (xy -14.199 -0.815)
        (xy -14.19 -0.794)
        (xy -14.183 -0.773)
        (xy -14.176 -0.749)
        (xy -14.17 -0.727)
        (xy -14.165 -0.704)
        (xy -14.163 -0.682)
        (xy -14.161 -0.658)
        (xy -14.16 -0.634)
        (xy -14.161 -0.611)
        (xy -14.163 -0.587)
        (xy -14.165 -0.564)
        (xy -14.17 -0.542)
        (xy -14.176 -0.52)
        (xy -14.183 -0.496)
        (xy -14.19 -0.475)
        (xy -14.199 -0.454)
        (xy -14.209 -0.432)
        (xy -14.221 -0.412)
        (xy -14.232 -0.393)
        (xy -14.245 -0.372)
        (xy -14.26 -0.354)
        (xy -14.274 -0.337)
        (xy -14.29 -0.32)
        (xy -14.308 -0.303)
        (xy -14.325 -0.288)
        (xy -14.343 -0.275)
        (xy -14.363 -0.262)
        (xy -14.383 -0.249)
        (xy -14.404 -0.238)
        (xy -14.424 -0.228)
        (xy -14.446 -0.219)
        (xy -14.468 -0.211)
        (xy -14.49 -0.204)
        (xy -14.513 -0.2)
        (xy -14.535 -0.195)
        (xy -14.558 -0.192)
        (xy -14.583 -0.19)
        (xy -14.606 -0.189)
        (xy -14.629 -0.19)
        (xy -14.654 -0.192)
        (xy -14.676 -0.195)
        (xy -14.699 -0.2)
        (xy -14.721 -0.204)
        (xy -14.744 -0.211)
        (xy -14.766 -0.218)
        (xy -14.788 -0.228)
        (xy -14.808 -0.237)
        (xy -14.828 -0.248)
        (xy -14.849 -0.262)
        (xy -14.868 -0.275)
        (xy -14.886 -0.288)
        (xy -14.904 -0.303)
        (xy -14.92 -0.32)
        (xy -14.936 -0.337)
        (xy -14.952 -0.353)
        (xy -14.965 -0.372)
        (xy -14.978 -0.392)
        (xy -14.991 -0.411)
        (xy -15.003 -0.431)
        (xy -15.013 -0.453)
        (xy -15.022 -0.474)
        (xy -15.029 -0.496)
        (xy -15.035 -0.519)
        (xy -15.04 -0.541)
        (xy -15.045 -0.563)
        (xy -15.048 -0.586)
        (xy -15.049 -0.61)
        (xy -15.051 -0.631)
        (xy -14.606 -0.631)
        (xy -14.606 -0.636)
        (xy -14.606 -0.637)
      )

      (stroke (width 0.001) (type solid)) (fill solid) (layer "B.Paste"))
    (fp_poly
      (pts
        (xy -14.606 0.633)
        (xy -15.051 0.632)
        (xy -15.049 0.611)
        (xy -15.048 0.587)
        (xy -15.045 0.564)
        (xy -15.04 0.542)
        (xy -15.035 0.52)
        (xy -15.029 0.497)
        (xy -15.022 0.475)
        (xy -15.013 0.454)
        (xy -15.003 0.432)
        (xy -14.991 0.412)
        (xy -14.978 0.393)
        (xy -14.965 0.373)
        (xy -14.952 0.354)
        (xy -14.936 0.338)
        (xy -14.92 0.32)
        (xy -14.904 0.304)
        (xy -14.886 0.289)
        (xy -14.868 0.276)
        (xy -14.849 0.263)
        (xy -14.828 0.249)
        (xy -14.808 0.238)
        (xy -14.788 0.229)
        (xy -14.766 0.219)
        (xy -14.744 0.212)
        (xy -14.721 0.205)
        (xy -14.699 0.201)
        (xy -14.676 0.196)
        (xy -14.654 0.192)
        (xy -14.629 0.191)
        (xy -14.606 0.19)
        (xy -14.583 0.191)
        (xy -14.558 0.192)
        (xy -14.535 0.196)
        (xy -14.513 0.201)
        (xy -14.49 0.205)
        (xy -14.468 0.212)
        (xy -14.446 0.22)
        (xy -14.424 0.229)
        (xy -14.404 0.239)
        (xy -14.383 0.25)
        (xy -14.363 0.263)
        (xy -14.343 0.276)
        (xy -14.325 0.289)
        (xy -14.308 0.304)
        (xy -14.29 0.32)
        (xy -14.274 0.338)
        (xy -14.26 0.355)
        (xy -14.245 0.373)
        (xy -14.232 0.394)
        (xy -14.221 0.413)
        (xy -14.209 0.433)
        (xy -14.199 0.455)
        (xy -14.19 0.476)
        (xy -14.183 0.497)
        (xy -14.176 0.521)
        (xy -14.17 0.543)
        (xy -14.165 0.565)
        (xy -14.163 0.588)
        (xy -14.161 0.612)
        (xy -14.16 0.635)
        (xy -14.161 0.659)
        (xy -14.163 0.683)
        (xy -14.165 0.705)
        (xy -14.17 0.728)
        (xy -14.176 0.75)
        (xy -14.183 0.774)
        (xy -14.19 0.795)
        (xy -14.199 0.816)
        (xy -14.209 0.837)
        (xy -14.221 0.857)
        (xy -14.232 0.877)
        (xy -14.245 0.898)
        (xy -14.26 0.916)
        (xy -14.274 0.934)
        (xy -14.29 0.95)
        (xy -14.308 0.966)
        (xy -14.325 0.981)
        (xy -14.343 0.995)
        (xy -14.363 1.008)
        (xy -14.383 1.02)
        (xy -14.404 1.031)
        (xy -14.424 1.043)
        (xy -14.446 1.051)
        (xy -14.468 1.059)
        (xy -14.49 1.065)
        (xy -14.513 1.071)
        (xy -14.535 1.075)
        (xy -14.558 1.079)
        (xy -14.583 1.079)
        (xy -14.606 1.081)
        (xy -14.629 1.079)
        (xy -14.654 1.079)
        (xy -14.676 1.075)
        (xy -14.699 1.071)
        (xy -14.721 1.065)
        (xy -14.744 1.059)
        (xy -14.766 1.051)
        (xy -14.788 1.043)
        (xy -14.808 1.033)
        (xy -14.828 1.021)
        (xy -14.849 1.008)
        (xy -14.868 0.995)
        (xy -14.886 0.981)
        (xy -14.904 0.966)
        (xy -14.92 0.95)
        (xy -14.936 0.934)
        (xy -14.952 0.917)
        (xy -14.965 0.898)
        (xy -14.978 0.878)
        (xy -14.991 0.858)
        (xy -15.003 0.838)
        (xy -15.013 0.817)
        (xy -15.022 0.796)
        (xy -15.029 0.774)
        (xy -15.035 0.751)
        (xy -15.04 0.729)
        (xy -15.045 0.706)
        (xy -15.048 0.684)
        (xy -15.049 0.66)
        (xy -15.051 0.637)
        (xy -14.606 0.637)
        (xy -14.606 0.632)
        (xy -14.606 0.633)
      )

      (stroke (width 0.001) (type solid)) (fill solid) (layer "B.Paste"))
    (fp_poly
      (pts
        (xy -13.336 -4.447)
        (xy -13.78 -4.446)
        (xy -13.779 -4.469)
        (xy -13.779 -4.493)
        (xy -13.776 -4.515)
        (xy -13.77 -4.538)
        (xy -13.766 -4.56)
        (xy -13.758 -4.583)
        (xy -13.751 -4.605)
        (xy -13.743 -4.626)
        (xy -13.732 -4.647)
        (xy -13.721 -4.668)
        (xy -13.708 -4.687)
        (xy -13.695 -4.706)
        (xy -13.681 -4.725)
        (xy -13.667 -4.743)
        (xy -13.651 -4.759)
        (xy -13.633 -4.775)
        (xy -13.616 -4.791)
        (xy -13.597 -4.804)
        (xy -13.578 -4.817)
        (xy -13.558 -4.831)
        (xy -13.538 -4.841)
        (xy -13.517 -4.852)
        (xy -13.495 -4.86)
        (xy -13.474 -4.868)
        (xy -13.452 -4.874)
        (xy -13.429 -4.879)
        (xy -13.407 -4.884)
        (xy -13.383 -4.887)
        (xy -13.359 -4.889)
        (xy -13.336 -4.889)
        (xy -13.312 -4.889)
        (xy -13.288 -4.887)
        (xy -13.266 -4.884)
        (xy -13.243 -4.879)
        (xy -13.221 -4.874)
        (xy -13.197 -4.868)
        (xy -13.176 -4.86)
        (xy -13.154 -4.852)
        (xy -13.133 -4.841)
        (xy -13.113 -4.829)
        (xy -13.093 -4.817)
        (xy -13.074 -4.804)
        (xy -13.055 -4.791)
        (xy -13.038 -4.775)
        (xy -13.02 -4.759)
        (xy -13.004 -4.743)
        (xy -12.99 -4.724)
        (xy -12.975 -4.706)
        (xy -12.962 -4.687)
        (xy -12.95 -4.668)
        (xy -12.939 -4.647)
        (xy -12.929 -4.626)
        (xy -12.92 -4.603)
        (xy -12.913 -4.583)
        (xy -12.905 -4.559)
        (xy -12.901 -4.538)
        (xy -12.895 -4.514)
        (xy -12.892 -4.491)
        (xy -12.891 -4.467)
        (xy -12.891 -4.445)
        (xy -12.891 -4.421)
        (xy -12.892 -4.397)
        (xy -12.895 -4.374)
        (xy -12.901 -4.352)
        (xy -12.905 -4.329)
        (xy -12.913 -4.307)
        (xy -12.92 -4.285)
        (xy -12.929 -4.264)
        (xy -12.939 -4.243)
        (xy -12.95 -4.222)
        (xy -12.962 -4.203)
        (xy -12.975 -4.182)
        (xy -12.99 -4.164)
        (xy -13.004 -4.147)
        (xy -13.02 -4.129)
        (xy -13.038 -4.113)
        (xy -13.055 -4.099)
        (xy -13.074 -4.084)
        (xy -13.093 -4.071)
        (xy -13.113 -4.059)
        (xy -13.133 -4.049)
        (xy -13.154 -4.038)
        (xy -13.176 -4.03)
        (xy -13.197 -4.022)
        (xy -13.221 -4.014)
        (xy -13.243 -4.009)
        (xy -13.266 -4.004)
        (xy -13.288 -4.001)
        (xy -13.312 -4.001)
        (xy -13.336 -3.999)
        (xy -13.359 -4.001)
        (xy -13.383 -4.001)
        (xy -13.407 -4.004)
        (xy -13.429 -4.009)
        (xy -13.452 -4.014)
        (xy -13.474 -4.022)
        (xy -13.495 -4.028)
        (xy -13.517 -4.038)
        (xy -13.538 -4.047)
        (xy -13.558 -4.059)
        (xy -13.578 -4.071)
        (xy -13.597 -4.084)
        (xy -13.616 -4.099)
        (xy -13.633 -4.113)
        (xy -13.651 -4.129)
        (xy -13.667 -4.147)
        (xy -13.681 -4.163)
        (xy -13.695 -4.182)
        (xy -13.708 -4.201)
        (xy -13.721 -4.222)
        (xy -13.732 -4.241)
        (xy -13.743 -4.262)
        (xy -13.751 -4.285)
        (xy -13.758 -4.307)
        (xy -13.766 -4.328)
        (xy -13.77 -4.35)
        (xy -13.776 -4.373)
        (xy -13.779 -4.397)
        (xy -13.779 -4.421)
        (xy -13.78 -4.442)
        (xy -13.336 -4.442)
        (xy -13.336 -4.446)
        (xy -13.336 -4.447)
      )

      (stroke (width 0.001) (type solid)) (fill solid) (layer "B.Paste"))
    (fp_poly
      (pts
        (xy -13.336 -1.907)
        (xy -13.78 -1.906)
        (xy -13.779 -1.929)
        (xy -13.779 -1.953)
        (xy -13.776 -1.975)
        (xy -13.77 -1.999)
        (xy -13.766 -2.02)
        (xy -13.758 -2.043)
        (xy -13.751 -2.064)
        (xy -13.743 -2.087)
        (xy -13.732 -2.108)
        (xy -13.721 -2.128)
        (xy -13.708 -2.148)
        (xy -13.695 -2.166)
        (xy -13.681 -2.185)
        (xy -13.667 -2.202)
        (xy -13.651 -2.22)
        (xy -13.633 -2.236)
        (xy -13.616 -2.25)
        (xy -13.597 -2.265)
        (xy -13.578 -2.277)
        (xy -13.558 -2.29)
        (xy -13.538 -2.301)
        (xy -13.517 -2.311)
        (xy -13.495 -2.321)
        (xy -13.474 -2.327)
        (xy -13.452 -2.334)
        (xy -13.429 -2.339)
        (xy -13.407 -2.345)
        (xy -13.383 -2.347)
        (xy -13.359 -2.349)
        (xy -13.336 -2.35)
        (xy -13.312 -2.349)
        (xy -13.288 -2.347)
        (xy -13.266 -2.345)
        (xy -13.243 -2.339)
        (xy -13.221 -2.334)
        (xy -13.197 -2.327)
        (xy -13.176 -2.319)
        (xy -13.154 -2.311)
        (xy -13.133 -2.301)
        (xy -13.113 -2.289)
        (xy -13.093 -2.277)
        (xy -13.074 -2.265)
        (xy -13.055 -2.25)
        (xy -13.038 -2.236)
        (xy -13.02 -2.22)
        (xy -13.004 -2.202)
        (xy -12.99 -2.185)
        (xy -12.975 -2.166)
        (xy -12.962 -2.146)
        (xy -12.95 -2.126)
        (xy -12.939 -2.107)
        (xy -12.929 -2.085)
        (xy -12.92 -2.064)
        (xy -12.913 -2.043)
        (xy -12.905 -2.019)
        (xy -12.901 -1.997)
        (xy -12.895 -1.975)
        (xy -12.892 -1.951)
        (xy -12.891 -1.927)
        (xy -12.891 -1.904)
        (xy -12.891 -1.881)
        (xy -12.892 -1.858)
        (xy -12.895 -1.834)
        (xy -12.901 -1.812)
        (xy -12.905 -1.789)
        (xy -12.913 -1.766)
        (xy -12.92 -1.745)
        (xy -12.929 -1.723)
        (xy -12.939 -1.703)
        (xy -12.95 -1.683)
        (xy -12.962 -1.662)
        (xy -12.975 -1.642)
        (xy -12.99 -1.624)
        (xy -13.004 -1.606)
        (xy -13.02 -1.59)
        (xy -13.038 -1.574)
        (xy -13.055 -1.558)
        (xy -13.074 -1.544)
        (xy -13.093 -1.531)
        (xy -13.113 -1.519)
        (xy -13.133 -1.508)
        (xy -13.154 -1.497)
        (xy -13.176 -1.489)
        (xy -13.197 -1.481)
        (xy -13.221 -1.475)
        (xy -13.243 -1.469)
        (xy -13.266 -1.465)
        (xy -13.288 -1.461)
        (xy -13.312 -1.461)
        (xy -13.336 -1.459)
        (xy -13.359 -1.461)
        (xy -13.383 -1.461)
        (xy -13.407 -1.465)
        (xy -13.429 -1.469)
        (xy -13.452 -1.475)
        (xy -13.474 -1.481)
        (xy -13.495 -1.489)
        (xy -13.517 -1.497)
        (xy -13.538 -1.507)
        (xy -13.558 -1.518)
        (xy -13.578 -1.531)
        (xy -13.597 -1.544)
        (xy -13.616 -1.558)
        (xy -13.633 -1.574)
        (xy -13.651 -1.59)
        (xy -13.667 -1.606)
        (xy -13.681 -1.624)
        (xy -13.695 -1.642)
        (xy -13.708 -1.661)
        (xy -13.721 -1.681)
        (xy -13.732 -1.701)
        (xy -13.743 -1.723)
        (xy -13.751 -1.745)
        (xy -13.758 -1.766)
        (xy -13.766 -1.788)
        (xy -13.77 -1.81)
        (xy -13.776 -1.834)
        (xy -13.779 -1.856)
        (xy -13.779 -1.88)
        (xy -13.78 -1.902)
        (xy -13.336 -1.902)
        (xy -13.336 -1.906)
        (xy -13.336 -1.907)
      )

      (stroke (width 0.001) (type solid)) (fill solid) (layer "B.Paste"))
    (fp_poly
      (pts
        (xy -13.336 -0.637)
        (xy -13.78 -0.636)
        (xy -13.779 -0.659)
        (xy -13.779 -0.683)
        (xy -13.776 -0.705)
        (xy -13.77 -0.728)
        (xy -13.766 -0.75)
        (xy -13.758 -0.773)
        (xy -13.751 -0.795)
        (xy -13.743 -0.816)
        (xy -13.732 -0.837)
        (xy -13.721 -0.857)
        (xy -13.708 -0.877)
        (xy -13.695 -0.897)
        (xy -13.681 -0.916)
        (xy -13.667 -0.933)
        (xy -13.651 -0.949)
        (xy -13.633 -0.965)
        (xy -13.616 -0.98)
        (xy -13.597 -0.994)
        (xy -13.578 -1.007)
        (xy -13.558 -1.02)
        (xy -13.538 -1.032)
        (xy -13.517 -1.042)
        (xy -13.495 -1.05)
        (xy -13.474 -1.058)
        (xy -13.452 -1.064)
        (xy -13.429 -1.07)
        (xy -13.407 -1.074)
        (xy -13.383 -1.078)
        (xy -13.359 -1.078)
        (xy -13.336 -1.08)
        (xy -13.312 -1.078)
        (xy -13.288 -1.078)
        (xy -13.266 -1.074)
        (xy -13.243 -1.07)
        (xy -13.221 -1.064)
        (xy -13.197 -1.058)
        (xy -13.176 -1.05)
        (xy -13.154 -1.042)
        (xy -13.133 -1.03)
        (xy -13.113 -1.019)
        (xy -13.093 -1.007)
        (xy -13.074 -0.994)
        (xy -13.055 -0.98)
        (xy -13.038 -0.965)
        (xy -13.02 -0.949)
        (xy -13.004 -0.933)
        (xy -12.99 -0.915)
        (xy -12.975 -0.897)
        (xy -12.962 -0.876)
        (xy -12.95 -0.856)
        (xy -12.939 -0.836)
        (xy -12.929 -0.815)
        (xy -12.92 -0.794)
        (xy -12.913 -0.773)
        (xy -12.905 -0.749)
        (xy -12.901 -0.727)
        (xy -12.895 -0.704)
        (xy -12.892 -0.682)
        (xy -12.891 -0.658)
        (xy -12.891 -0.634)
        (xy -12.891 -0.611)
        (xy -12.892 -0.587)
        (xy -12.895 -0.564)
        (xy -12.901 -0.542)
        (xy -12.905 -0.52)
        (xy -12.913 -0.496)
        (xy -12.92 -0.475)
        (xy -12.929 -0.454)
        (xy -12.939 -0.432)
        (xy -12.95 -0.412)
        (xy -12.962 -0.393)
        (xy -12.975 -0.372)
        (xy -12.99 -0.354)
        (xy -13.004 -0.337)
        (xy -13.02 -0.32)
        (xy -13.038 -0.303)
        (xy -13.055 -0.288)
        (xy -13.074 -0.275)
        (xy -13.093 -0.262)
        (xy -13.113 -0.249)
        (xy -13.133 -0.238)
        (xy -13.154 -0.228)
        (xy -13.176 -0.219)
        (xy -13.197 -0.211)
        (xy -13.221 -0.204)
        (xy -13.243 -0.2)
        (xy -13.266 -0.195)
        (xy -13.288 -0.192)
        (xy -13.312 -0.19)
        (xy -13.336 -0.189)
        (xy -13.359 -0.19)
        (xy -13.383 -0.192)
        (xy -13.407 -0.195)
        (xy -13.429 -0.2)
        (xy -13.452 -0.204)
        (xy -13.474 -0.211)
        (xy -13.495 -0.218)
        (xy -13.517 -0.228)
        (xy -13.538 -0.237)
        (xy -13.558 -0.248)
        (xy -13.578 -0.262)
        (xy -13.597 -0.275)
        (xy -13.616 -0.288)
        (xy -13.633 -0.303)
        (xy -13.651 -0.32)
        (xy -13.667 -0.337)
        (xy -13.681 -0.353)
        (xy -13.695 -0.372)
        (xy -13.708 -0.392)
        (xy -13.721 -0.411)
        (xy -13.732 -0.431)
        (xy -13.743 -0.453)
        (xy -13.751 -0.474)
        (xy -13.758 -0.496)
        (xy -13.766 -0.519)
        (xy -13.77 -0.541)
        (xy -13.776 -0.563)
        (xy -13.779 -0.586)
        (xy -13.779 -0.61)
        (xy -13.78 -0.631)
        (xy -13.336 -0.631)
        (xy -13.336 -0.636)
        (xy -13.336 -0.637)
      )

      (stroke (width 0.001) (type solid)) (fill solid) (layer "B.Paste"))
    (fp_poly
      (pts
        (xy -13.336 0.633)
        (xy -13.78 0.632)
        (xy -13.779 0.611)
        (xy -13.779 0.587)
        (xy -13.776 0.564)
        (xy -13.77 0.542)
        (xy -13.766 0.52)
        (xy -13.758 0.497)
        (xy -13.751 0.475)
        (xy -13.743 0.454)
        (xy -13.732 0.432)
        (xy -13.721 0.412)
        (xy -13.708 0.393)
        (xy -13.695 0.373)
        (xy -13.681 0.354)
        (xy -13.667 0.338)
        (xy -13.651 0.32)
        (xy -13.633 0.304)
        (xy -13.616 0.289)
        (xy -13.597 0.276)
        (xy -13.578 0.263)
        (xy -13.558 0.249)
        (xy -13.538 0.238)
        (xy -13.517 0.229)
        (xy -13.495 0.219)
        (xy -13.474 0.212)
        (xy -13.452 0.205)
        (xy -13.429 0.201)
        (xy -13.407 0.196)
        (xy -13.383 0.192)
        (xy -13.359 0.191)
        (xy -13.336 0.19)
        (xy -13.312 0.191)
        (xy -13.288 0.192)
        (xy -13.266 0.196)
        (xy -13.243 0.201)
        (xy -13.221 0.205)
        (xy -13.197 0.212)
        (xy -13.176 0.22)
        (xy -13.154 0.229)
        (xy -13.133 0.239)
        (xy -13.113 0.25)
        (xy -13.093 0.263)
        (xy -13.074 0.276)
        (xy -13.055 0.289)
        (xy -13.038 0.304)
        (xy -13.02 0.32)
        (xy -13.004 0.338)
        (xy -12.99 0.355)
        (xy -12.975 0.373)
        (xy -12.962 0.394)
        (xy -12.95 0.413)
        (xy -12.939 0.433)
        (xy -12.929 0.455)
        (xy -12.92 0.476)
        (xy -12.913 0.497)
        (xy -12.905 0.521)
        (xy -12.901 0.543)
        (xy -12.895 0.565)
        (xy -12.892 0.588)
        (xy -12.891 0.612)
        (xy -12.891 0.635)
        (xy -12.891 0.659)
        (xy -12.892 0.683)
        (xy -12.895 0.705)
        (xy -12.901 0.728)
        (xy -12.905 0.75)
        (xy -12.913 0.774)
        (xy -12.92 0.795)
        (xy -12.929 0.816)
        (xy -12.939 0.837)
        (xy -12.95 0.857)
        (xy -12.962 0.877)
        (xy -12.975 0.898)
        (xy -12.99 0.916)
        (xy -13.004 0.934)
        (xy -13.02 0.95)
        (xy -13.038 0.966)
        (xy -13.055 0.981)
        (xy -13.074 0.995)
        (xy -13.093 1.008)
        (xy -13.113 1.02)
        (xy -13.133 1.031)
        (xy -13.154 1.043)
        (xy -13.176 1.051)
        (xy -13.197 1.059)
        (xy -13.221 1.065)
        (xy -13.243 1.071)
        (xy -13.266 1.075)
        (xy -13.288 1.079)
        (xy -13.312 1.079)
        (xy -13.336 1.081)
        (xy -13.359 1.079)
        (xy -13.383 1.079)
        (xy -13.407 1.075)
        (xy -13.429 1.071)
        (xy -13.452 1.065)
        (xy -13.474 1.059)
        (xy -13.495 1.051)
        (xy -13.517 1.043)
        (xy -13.538 1.033)
        (xy -13.558 1.021)
        (xy -13.578 1.008)
        (xy -13.597 0.995)
        (xy -13.616 0.981)
        (xy -13.633 0.966)
        (xy -13.651 0.95)
        (xy -13.667 0.934)
        (xy -13.681 0.917)
        (xy -13.695 0.898)
        (xy -13.708 0.878)
        (xy -13.721 0.858)
        (xy -13.732 0.838)
        (xy -13.743 0.817)
        (xy -13.751 0.796)
        (xy -13.758 0.774)
        (xy -13.766 0.751)
        (xy -13.77 0.729)
        (xy -13.776 0.706)
        (xy -13.779 0.684)
        (xy -13.779 0.66)
        (xy -13.78 0.637)
        (xy -13.336 0.637)
        (xy -13.336 0.632)
        (xy -13.336 0.633)
      )

      (stroke (width 0.001) (type solid)) (fill solid) (layer "B.Paste"))
    (fp_poly
      (pts
        (xy -12.065 -4.447)
        (xy -12.51 -4.446)
        (xy -12.51 -4.469)
        (xy -12.508 -4.493)
        (xy -12.506 -4.515)
        (xy -12.5 -4.538)
        (xy -12.495 -4.56)
        (xy -12.488 -4.583)
        (xy -12.481 -4.605)
        (xy -12.472 -4.626)
        (xy -12.462 -4.647)
        (xy -12.452 -4.668)
        (xy -12.439 -4.687)
        (xy -12.426 -4.706)
        (xy -12.411 -4.725)
        (xy -12.397 -4.743)
        (xy -12.381 -4.759)
        (xy -12.363 -4.775)
        (xy -12.346 -4.791)
        (xy -12.327 -4.804)
        (xy -12.308 -4.817)
        (xy -12.288 -4.831)
        (xy -12.269 -4.841)
        (xy -12.247 -4.852)
        (xy -12.225 -4.86)
        (xy -12.203 -4.868)
        (xy -12.181 -4.874)
        (xy -12.16 -4.879)
        (xy -12.136 -4.884)
        (xy -12.113 -4.887)
        (xy -12.09 -4.889)
        (xy -12.065 -4.889)
        (xy -12.042 -4.889)
        (xy -12.019 -4.887)
        (xy -11.995 -4.884)
        (xy -11.972 -4.879)
        (xy -11.95 -4.874)
        (xy -11.927 -4.868)
        (xy -11.907 -4.86)
        (xy -11.885 -4.852)
        (xy -11.863 -4.841)
        (xy -11.843 -4.829)
        (xy -11.824 -4.817)
        (xy -11.804 -4.804)
        (xy -11.785 -4.791)
        (xy -11.767 -4.775)
        (xy -11.75 -4.759)
        (xy -11.734 -4.743)
        (xy -11.719 -4.724)
        (xy -11.705 -4.706)
        (xy -11.692 -4.687)
        (xy -11.68 -4.668)
        (xy -11.67 -4.647)
        (xy -11.658 -4.626)
        (xy -11.651 -4.603)
        (xy -11.642 -4.583)
        (xy -11.635 -4.559)
        (xy -11.631 -4.538)
        (xy -11.625 -4.514)
        (xy -11.622 -4.491)
        (xy -11.622 -4.467)
        (xy -11.62 -4.445)
        (xy -11.622 -4.421)
        (xy -11.622 -4.397)
        (xy -11.625 -4.374)
        (xy -11.631 -4.352)
        (xy -11.635 -4.329)
        (xy -11.642 -4.307)
        (xy -11.651 -4.285)
        (xy -11.658 -4.264)
        (xy -11.67 -4.243)
        (xy -11.68 -4.222)
        (xy -11.692 -4.203)
        (xy -11.705 -4.182)
        (xy -11.719 -4.164)
        (xy -11.734 -4.147)
        (xy -11.75 -4.129)
        (xy -11.767 -4.113)
        (xy -11.785 -4.099)
        (xy -11.804 -4.084)
        (xy -11.824 -4.071)
        (xy -11.843 -4.059)
        (xy -11.863 -4.049)
        (xy -11.885 -4.038)
        (xy -11.907 -4.03)
        (xy -11.927 -4.022)
        (xy -11.95 -4.014)
        (xy -11.972 -4.009)
        (xy -11.995 -4.004)
        (xy -12.019 -4.001)
        (xy -12.042 -4.001)
        (xy -12.065 -3.999)
        (xy -12.09 -4.001)
        (xy -12.113 -4.001)
        (xy -12.136 -4.004)
        (xy -12.16 -4.009)
        (xy -12.181 -4.014)
        (xy -12.203 -4.022)
        (xy -12.225 -4.028)
        (xy -12.247 -4.038)
        (xy -12.269 -4.047)
        (xy -12.288 -4.059)
        (xy -12.308 -4.071)
        (xy -12.327 -4.084)
        (xy -12.346 -4.099)
        (xy -12.363 -4.113)
        (xy -12.381 -4.129)
        (xy -12.397 -4.147)
        (xy -12.411 -4.163)
        (xy -12.426 -4.182)
        (xy -12.439 -4.201)
        (xy -12.452 -4.222)
        (xy -12.462 -4.241)
        (xy -12.472 -4.262)
        (xy -12.481 -4.285)
        (xy -12.488 -4.307)
        (xy -12.495 -4.328)
        (xy -12.5 -4.35)
        (xy -12.506 -4.373)
        (xy -12.508 -4.397)
        (xy -12.51 -4.421)
        (xy -12.51 -4.442)
        (xy -12.065 -4.442)
        (xy -12.065 -4.446)
        (xy -12.065 -4.447)
      )

      (stroke (width 0.001) (type solid)) (fill solid) (layer "B.Paste"))
    (fp_poly
      (pts
        (xy -12.065 -1.907)
        (xy -12.51 -1.906)
        (xy -12.51 -1.929)
        (xy -12.508 -1.953)
        (xy -12.506 -1.975)
        (xy -12.5 -1.999)
        (xy -12.495 -2.02)
        (xy -12.488 -2.043)
        (xy -12.481 -2.064)
        (xy -12.472 -2.087)
        (xy -12.462 -2.108)
        (xy -12.452 -2.128)
        (xy -12.439 -2.148)
        (xy -12.426 -2.166)
        (xy -12.411 -2.185)
        (xy -12.397 -2.202)
        (xy -12.381 -2.22)
        (xy -12.363 -2.236)
        (xy -12.346 -2.25)
        (xy -12.327 -2.265)
        (xy -12.308 -2.277)
        (xy -12.288 -2.29)
        (xy -12.269 -2.301)
        (xy -12.247 -2.311)
        (xy -12.225 -2.321)
        (xy -12.203 -2.327)
        (xy -12.181 -2.334)
        (xy -12.16 -2.339)
        (xy -12.136 -2.345)
        (xy -12.113 -2.347)
        (xy -12.09 -2.349)
        (xy -12.065 -2.35)
        (xy -12.042 -2.349)
        (xy -12.019 -2.347)
        (xy -11.995 -2.345)
        (xy -11.972 -2.339)
        (xy -11.95 -2.334)
        (xy -11.927 -2.327)
        (xy -11.907 -2.319)
        (xy -11.885 -2.311)
        (xy -11.863 -2.301)
        (xy -11.843 -2.289)
        (xy -11.824 -2.277)
        (xy -11.804 -2.265)
        (xy -11.785 -2.25)
        (xy -11.767 -2.236)
        (xy -11.75 -2.22)
        (xy -11.734 -2.202)
        (xy -11.719 -2.185)
        (xy -11.705 -2.166)
        (xy -11.692 -2.146)
        (xy -11.68 -2.126)
        (xy -11.67 -2.107)
        (xy -11.658 -2.085)
        (xy -11.651 -2.064)
        (xy -11.642 -2.043)
        (xy -11.635 -2.019)
        (xy -11.631 -1.997)
        (xy -11.625 -1.975)
        (xy -11.622 -1.951)
        (xy -11.622 -1.927)
        (xy -11.62 -1.904)
        (xy -11.622 -1.881)
        (xy -11.622 -1.858)
        (xy -11.625 -1.834)
        (xy -11.631 -1.812)
        (xy -11.635 -1.789)
        (xy -11.642 -1.766)
        (xy -11.651 -1.745)
        (xy -11.658 -1.723)
        (xy -11.67 -1.703)
        (xy -11.68 -1.683)
        (xy -11.692 -1.662)
        (xy -11.705 -1.642)
        (xy -11.719 -1.624)
        (xy -11.734 -1.606)
        (xy -11.75 -1.59)
        (xy -11.767 -1.574)
        (xy -11.785 -1.558)
        (xy -11.804 -1.544)
        (xy -11.824 -1.531)
        (xy -11.843 -1.519)
        (xy -11.863 -1.508)
        (xy -11.885 -1.497)
        (xy -11.907 -1.489)
        (xy -11.927 -1.481)
        (xy -11.95 -1.475)
        (xy -11.972 -1.469)
        (xy -11.995 -1.465)
        (xy -12.019 -1.461)
        (xy -12.042 -1.461)
        (xy -12.065 -1.459)
        (xy -12.09 -1.461)
        (xy -12.113 -1.461)
        (xy -12.136 -1.465)
        (xy -12.16 -1.469)
        (xy -12.181 -1.475)
        (xy -12.203 -1.481)
        (xy -12.225 -1.489)
        (xy -12.247 -1.497)
        (xy -12.269 -1.507)
        (xy -12.288 -1.518)
        (xy -12.308 -1.531)
        (xy -12.327 -1.544)
        (xy -12.346 -1.558)
        (xy -12.363 -1.574)
        (xy -12.381 -1.59)
        (xy -12.397 -1.606)
        (xy -12.411 -1.624)
        (xy -12.426 -1.642)
        (xy -12.439 -1.661)
        (xy -12.452 -1.681)
        (xy -12.462 -1.701)
        (xy -12.472 -1.723)
        (xy -12.481 -1.745)
        (xy -12.488 -1.766)
        (xy -12.495 -1.788)
        (xy -12.5 -1.81)
        (xy -12.506 -1.834)
        (xy -12.508 -1.856)
        (xy -12.51 -1.88)
        (xy -12.51 -1.902)
        (xy -12.065 -1.902)
        (xy -12.065 -1.906)
        (xy -12.065 -1.907)
      )

      (stroke (width 0.001) (type solid)) (fill solid) (layer "B.Paste"))
    (fp_poly
      (pts
        (xy -12.065 -0.637)
        (xy -12.51 -0.636)
        (xy -12.51 -0.659)
        (xy -12.508 -0.683)
        (xy -12.506 -0.705)
        (xy -12.5 -0.728)
        (xy -12.495 -0.75)
        (xy -12.488 -0.773)
        (xy -12.481 -0.795)
        (xy -12.472 -0.816)
        (xy -12.462 -0.837)
        (xy -12.452 -0.857)
        (xy -12.439 -0.877)
        (xy -12.426 -0.897)
        (xy -12.411 -0.916)
        (xy -12.397 -0.933)
        (xy -12.381 -0.949)
        (xy -12.363 -0.965)
        (xy -12.346 -0.98)
        (xy -12.327 -0.994)
        (xy -12.308 -1.007)
        (xy -12.288 -1.02)
        (xy -12.269 -1.032)
        (xy -12.247 -1.042)
        (xy -12.225 -1.05)
        (xy -12.203 -1.058)
        (xy -12.181 -1.064)
        (xy -12.16 -1.07)
        (xy -12.136 -1.074)
        (xy -12.113 -1.078)
        (xy -12.09 -1.078)
        (xy -12.065 -1.08)
        (xy -12.042 -1.078)
        (xy -12.019 -1.078)
        (xy -11.995 -1.074)
        (xy -11.972 -1.07)
        (xy -11.95 -1.064)
        (xy -11.927 -1.058)
        (xy -11.907 -1.05)
        (xy -11.885 -1.042)
        (xy -11.863 -1.03)
        (xy -11.843 -1.019)
        (xy -11.824 -1.007)
        (xy -11.804 -0.994)
        (xy -11.785 -0.98)
        (xy -11.767 -0.965)
        (xy -11.75 -0.949)
        (xy -11.734 -0.933)
        (xy -11.719 -0.915)
        (xy -11.705 -0.897)
        (xy -11.692 -0.876)
        (xy -11.68 -0.856)
        (xy -11.67 -0.836)
        (xy -11.658 -0.815)
        (xy -11.651 -0.794)
        (xy -11.642 -0.773)
        (xy -11.635 -0.749)
        (xy -11.631 -0.727)
        (xy -11.625 -0.704)
        (xy -11.622 -0.682)
        (xy -11.622 -0.658)
        (xy -11.62 -0.634)
        (xy -11.622 -0.611)
        (xy -11.622 -0.587)
        (xy -11.625 -0.564)
        (xy -11.631 -0.542)
        (xy -11.635 -0.52)
        (xy -11.642 -0.496)
        (xy -11.651 -0.475)
        (xy -11.658 -0.454)
        (xy -11.67 -0.432)
        (xy -11.68 -0.412)
        (xy -11.692 -0.393)
        (xy -11.705 -0.372)
        (xy -11.719 -0.354)
        (xy -11.734 -0.337)
        (xy -11.75 -0.32)
        (xy -11.767 -0.303)
        (xy -11.785 -0.288)
        (xy -11.804 -0.275)
        (xy -11.824 -0.262)
        (xy -11.843 -0.249)
        (xy -11.863 -0.238)
        (xy -11.885 -0.228)
        (xy -11.907 -0.219)
        (xy -11.927 -0.211)
        (xy -11.95 -0.204)
        (xy -11.972 -0.2)
        (xy -11.995 -0.195)
        (xy -12.019 -0.192)
        (xy -12.042 -0.19)
        (xy -12.065 -0.189)
        (xy -12.09 -0.19)
        (xy -12.113 -0.192)
        (xy -12.136 -0.195)
        (xy -12.16 -0.2)
        (xy -12.181 -0.204)
        (xy -12.203 -0.211)
        (xy -12.225 -0.218)
        (xy -12.247 -0.228)
        (xy -12.269 -0.237)
        (xy -12.288 -0.248)
        (xy -12.308 -0.262)
        (xy -12.327 -0.275)
        (xy -12.346 -0.288)
        (xy -12.363 -0.303)
        (xy -12.381 -0.32)
        (xy -12.397 -0.337)
        (xy -12.411 -0.353)
        (xy -12.426 -0.372)
        (xy -12.439 -0.392)
        (xy -12.452 -0.411)
        (xy -12.462 -0.431)
        (xy -12.472 -0.453)
        (xy -12.481 -0.474)
        (xy -12.488 -0.496)
        (xy -12.495 -0.519)
        (xy -12.5 -0.541)
        (xy -12.506 -0.563)
        (xy -12.508 -0.586)
        (xy -12.51 -0.61)
        (xy -12.51 -0.631)
        (xy -12.065 -0.631)
        (xy -12.065 -0.636)
        (xy -12.065 -0.637)
      )

      (stroke (width 0.001) (type solid)) (fill solid) (layer "B.Paste"))
    (fp_poly
      (pts
        (xy -12.065 0.633)
        (xy -12.51 0.632)
        (xy -12.51 0.611)
        (xy -12.508 0.587)
        (xy -12.506 0.564)
        (xy -12.5 0.542)
        (xy -12.495 0.52)
        (xy -12.488 0.497)
        (xy -12.481 0.475)
        (xy -12.472 0.454)
        (xy -12.462 0.432)
        (xy -12.452 0.412)
        (xy -12.439 0.393)
        (xy -12.426 0.373)
        (xy -12.411 0.354)
        (xy -12.397 0.338)
        (xy -12.381 0.32)
        (xy -12.363 0.304)
        (xy -12.346 0.289)
        (xy -12.327 0.276)
        (xy -12.308 0.263)
        (xy -12.288 0.249)
        (xy -12.269 0.238)
        (xy -12.247 0.229)
        (xy -12.225 0.219)
        (xy -12.203 0.212)
        (xy -12.181 0.205)
        (xy -12.16 0.201)
        (xy -12.136 0.196)
        (xy -12.113 0.192)
        (xy -12.09 0.191)
        (xy -12.065 0.19)
        (xy -12.042 0.191)
        (xy -12.019 0.192)
        (xy -11.995 0.196)
        (xy -11.972 0.201)
        (xy -11.95 0.205)
        (xy -11.927 0.212)
        (xy -11.907 0.22)
        (xy -11.885 0.229)
        (xy -11.863 0.239)
        (xy -11.843 0.25)
        (xy -11.824 0.263)
        (xy -11.804 0.276)
        (xy -11.785 0.289)
        (xy -11.767 0.304)
        (xy -11.75 0.32)
        (xy -11.734 0.338)
        (xy -11.719 0.355)
        (xy -11.705 0.373)
        (xy -11.692 0.394)
        (xy -11.68 0.413)
        (xy -11.67 0.433)
        (xy -11.658 0.455)
        (xy -11.651 0.476)
        (xy -11.642 0.497)
        (xy -11.635 0.521)
        (xy -11.631 0.543)
        (xy -11.625 0.565)
        (xy -11.622 0.588)
        (xy -11.622 0.612)
        (xy -11.62 0.635)
        (xy -11.622 0.659)
        (xy -11.622 0.683)
        (xy -11.625 0.705)
        (xy -11.631 0.728)
        (xy -11.635 0.75)
        (xy -11.642 0.774)
        (xy -11.651 0.795)
        (xy -11.658 0.816)
        (xy -11.67 0.837)
        (xy -11.68 0.857)
        (xy -11.692 0.877)
        (xy -11.705 0.898)
        (xy -11.719 0.916)
        (xy -11.734 0.934)
        (xy -11.75 0.95)
        (xy -11.767 0.966)
        (xy -11.785 0.981)
        (xy -11.804 0.995)
        (xy -11.824 1.008)
        (xy -11.843 1.02)
        (xy -11.863 1.031)
        (xy -11.885 1.043)
        (xy -11.907 1.051)
        (xy -11.927 1.059)
        (xy -11.95 1.065)
        (xy -11.972 1.071)
        (xy -11.995 1.075)
        (xy -12.019 1.079)
        (xy -12.042 1.079)
        (xy -12.065 1.081)
        (xy -12.09 1.079)
        (xy -12.113 1.079)
        (xy -12.136 1.075)
        (xy -12.16 1.071)
        (xy -12.181 1.065)
        (xy -12.203 1.059)
        (xy -12.225 1.051)
        (xy -12.247 1.043)
        (xy -12.269 1.033)
        (xy -12.288 1.021)
        (xy -12.308 1.008)
        (xy -12.327 0.995)
        (xy -12.346 0.981)
        (xy -12.363 0.966)
        (xy -12.381 0.95)
        (xy -12.397 0.934)
        (xy -12.411 0.917)
        (xy -12.426 0.898)
        (xy -12.439 0.878)
        (xy -12.452 0.858)
        (xy -12.462 0.838)
        (xy -12.472 0.817)
        (xy -12.481 0.796)
        (xy -12.488 0.774)
        (xy -12.495 0.751)
        (xy -12.5 0.729)
        (xy -12.506 0.706)
        (xy -12.508 0.684)
        (xy -12.51 0.66)
        (xy -12.51 0.637)
        (xy -12.065 0.637)
        (xy -12.065 0.632)
        (xy -12.065 0.633)
      )

      (stroke (width 0.001) (type solid)) (fill solid) (layer "B.Paste"))
    (fp_poly
      (pts
        (xy -10.795 -4.447)
        (xy -11.24 -4.446)
        (xy -11.24 -4.469)
        (xy -11.238 -4.493)
        (xy -11.235 -4.515)
        (xy -11.231 -4.538)
        (xy -11.225 -4.56)
        (xy -11.218 -4.583)
        (xy -11.212 -4.605)
        (xy -11.202 -4.626)
        (xy -11.192 -4.647)
        (xy -11.181 -4.668)
        (xy -11.168 -4.687)
        (xy -11.155 -4.706)
        (xy -11.141 -4.725)
        (xy -11.126 -4.743)
        (xy -11.11 -4.759)
        (xy -11.093 -4.775)
        (xy -11.077 -4.791)
        (xy -11.058 -4.804)
        (xy -11.039 -4.817)
        (xy -11.019 -4.831)
        (xy -10.998 -4.841)
        (xy -10.978 -4.852)
        (xy -10.955 -4.86)
        (xy -10.933 -4.868)
        (xy -10.911 -4.874)
        (xy -10.889 -4.879)
        (xy -10.866 -4.884)
        (xy -10.843 -4.887)
        (xy -10.82 -4.889)
        (xy -10.795 -4.889)
        (xy -10.773 -4.889)
        (xy -10.748 -4.887)
        (xy -10.725 -4.884)
        (xy -10.702 -4.879)
        (xy -10.68 -4.874)
        (xy -10.657 -4.868)
        (xy -10.636 -4.86)
        (xy -10.615 -4.852)
        (xy -10.593 -4.841)
        (xy -10.572 -4.829)
        (xy -10.554 -4.817)
        (xy -10.533 -4.804)
        (xy -10.516 -4.791)
        (xy -10.497 -4.775)
        (xy -10.481 -4.759)
        (xy -10.465 -4.743)
        (xy -10.449 -4.724)
        (xy -10.436 -4.706)
        (xy -10.423 -4.687)
        (xy -10.41 -4.668)
        (xy -10.399 -4.647)
        (xy -10.388 -4.626)
        (xy -10.381 -4.603)
        (xy -10.372 -4.583)
        (xy -10.365 -4.559)
        (xy -10.36 -4.538)
        (xy -10.356 -4.514)
        (xy -10.353 -4.491)
        (xy -10.352 -4.467)
        (xy -10.35 -4.445)
        (xy -10.352 -4.421)
        (xy -10.353 -4.397)
        (xy -10.356 -4.374)
        (xy -10.36 -4.352)
        (xy -10.365 -4.329)
        (xy -10.372 -4.307)
        (xy -10.381 -4.285)
        (xy -10.388 -4.264)
        (xy -10.399 -4.243)
        (xy -10.41 -4.222)
        (xy -10.423 -4.203)
        (xy -10.436 -4.182)
        (xy -10.449 -4.164)
        (xy -10.465 -4.147)
        (xy -10.481 -4.129)
        (xy -10.497 -4.113)
        (xy -10.516 -4.099)
        (xy -10.533 -4.084)
        (xy -10.554 -4.071)
        (xy -10.572 -4.059)
        (xy -10.593 -4.049)
        (xy -10.615 -4.038)
        (xy -10.636 -4.03)
        (xy -10.657 -4.022)
        (xy -10.68 -4.014)
        (xy -10.702 -4.009)
        (xy -10.725 -4.004)
        (xy -10.748 -4.001)
        (xy -10.773 -4.001)
        (xy -10.795 -3.999)
        (xy -10.82 -4.001)
        (xy -10.843 -4.001)
        (xy -10.866 -4.004)
        (xy -10.889 -4.009)
        (xy -10.911 -4.014)
        (xy -10.933 -4.022)
        (xy -10.955 -4.028)
        (xy -10.978 -4.038)
        (xy -10.998 -4.047)
        (xy -11.019 -4.059)
        (xy -11.039 -4.071)
        (xy -11.058 -4.084)
        (xy -11.077 -4.099)
        (xy -11.093 -4.113)
        (xy -11.11 -4.129)
        (xy -11.126 -4.147)
        (xy -11.141 -4.163)
        (xy -11.155 -4.182)
        (xy -11.168 -4.201)
        (xy -11.181 -4.222)
        (xy -11.192 -4.241)
        (xy -11.202 -4.262)
        (xy -11.212 -4.285)
        (xy -11.218 -4.307)
        (xy -11.225 -4.328)
        (xy -11.231 -4.35)
        (xy -11.235 -4.373)
        (xy -11.238 -4.397)
        (xy -11.24 -4.421)
        (xy -11.24 -4.442)
        (xy -10.795 -4.442)
        (xy -10.795 -4.446)
        (xy -10.795 -4.447)
      )

      (stroke (width 0.001) (type solid)) (fill solid) (layer "B.Paste"))
    (fp_poly
      (pts
        (xy -10.795 -1.907)
        (xy -11.24 -1.906)
        (xy -11.24 -1.929)
        (xy -11.238 -1.953)
        (xy -11.235 -1.975)
        (xy -11.231 -1.999)
        (xy -11.225 -2.02)
        (xy -11.218 -2.043)
        (xy -11.212 -2.064)
        (xy -11.202 -2.087)
        (xy -11.192 -2.108)
        (xy -11.181 -2.128)
        (xy -11.168 -2.148)
        (xy -11.155 -2.166)
        (xy -11.141 -2.185)
        (xy -11.126 -2.202)
        (xy -11.11 -2.22)
        (xy -11.093 -2.236)
        (xy -11.077 -2.25)
        (xy -11.058 -2.265)
        (xy -11.039 -2.277)
        (xy -11.019 -2.29)
        (xy -10.998 -2.301)
        (xy -10.978 -2.311)
        (xy -10.955 -2.321)
        (xy -10.933 -2.327)
        (xy -10.911 -2.334)
        (xy -10.889 -2.339)
        (xy -10.866 -2.345)
        (xy -10.843 -2.347)
        (xy -10.82 -2.349)
        (xy -10.795 -2.35)
        (xy -10.773 -2.349)
        (xy -10.748 -2.347)
        (xy -10.725 -2.345)
        (xy -10.702 -2.339)
        (xy -10.68 -2.334)
        (xy -10.657 -2.327)
        (xy -10.636 -2.319)
        (xy -10.615 -2.311)
        (xy -10.593 -2.301)
        (xy -10.572 -2.289)
        (xy -10.554 -2.277)
        (xy -10.533 -2.265)
        (xy -10.516 -2.25)
        (xy -10.497 -2.236)
        (xy -10.481 -2.22)
        (xy -10.465 -2.202)
        (xy -10.449 -2.185)
        (xy -10.436 -2.166)
        (xy -10.423 -2.146)
        (xy -10.41 -2.126)
        (xy -10.399 -2.107)
        (xy -10.388 -2.085)
        (xy -10.381 -2.064)
        (xy -10.372 -2.043)
        (xy -10.365 -2.019)
        (xy -10.36 -1.997)
        (xy -10.356 -1.975)
        (xy -10.353 -1.951)
        (xy -10.352 -1.927)
        (xy -10.35 -1.904)
        (xy -10.352 -1.881)
        (xy -10.353 -1.858)
        (xy -10.356 -1.834)
        (xy -10.36 -1.812)
        (xy -10.365 -1.789)
        (xy -10.372 -1.766)
        (xy -10.381 -1.745)
        (xy -10.388 -1.723)
        (xy -10.399 -1.703)
        (xy -10.41 -1.683)
        (xy -10.423 -1.662)
        (xy -10.436 -1.642)
        (xy -10.449 -1.624)
        (xy -10.465 -1.606)
        (xy -10.481 -1.59)
        (xy -10.497 -1.574)
        (xy -10.516 -1.558)
        (xy -10.533 -1.544)
        (xy -10.554 -1.531)
        (xy -10.572 -1.519)
        (xy -10.593 -1.508)
        (xy -10.615 -1.497)
        (xy -10.636 -1.489)
        (xy -10.657 -1.481)
        (xy -10.68 -1.475)
        (xy -10.702 -1.469)
        (xy -10.725 -1.465)
        (xy -10.748 -1.461)
        (xy -10.773 -1.461)
        (xy -10.795 -1.459)
        (xy -10.82 -1.461)
        (xy -10.843 -1.461)
        (xy -10.866 -1.465)
        (xy -10.889 -1.469)
        (xy -10.911 -1.475)
        (xy -10.933 -1.481)
        (xy -10.955 -1.489)
        (xy -10.978 -1.497)
        (xy -10.998 -1.507)
        (xy -11.019 -1.518)
        (xy -11.039 -1.531)
        (xy -11.058 -1.544)
        (xy -11.077 -1.558)
        (xy -11.093 -1.574)
        (xy -11.11 -1.59)
        (xy -11.126 -1.606)
        (xy -11.141 -1.624)
        (xy -11.155 -1.642)
        (xy -11.168 -1.661)
        (xy -11.181 -1.681)
        (xy -11.192 -1.701)
        (xy -11.202 -1.723)
        (xy -11.212 -1.745)
        (xy -11.218 -1.766)
        (xy -11.225 -1.788)
        (xy -11.231 -1.81)
        (xy -11.235 -1.834)
        (xy -11.238 -1.856)
        (xy -11.24 -1.88)
        (xy -11.24 -1.902)
        (xy -10.795 -1.902)
        (xy -10.795 -1.906)
        (xy -10.795 -1.907)
      )

      (stroke (width 0.001) (type solid)) (fill solid) (layer "B.Paste"))
    (fp_poly
      (pts
        (xy -10.795 -0.637)
        (xy -11.24 -0.636)
        (xy -11.24 -0.659)
        (xy -11.238 -0.683)
        (xy -11.235 -0.705)
        (xy -11.231 -0.728)
        (xy -11.225 -0.75)
        (xy -11.218 -0.773)
        (xy -11.212 -0.795)
        (xy -11.202 -0.816)
        (xy -11.192 -0.837)
        (xy -11.181 -0.857)
        (xy -11.168 -0.877)
        (xy -11.155 -0.897)
        (xy -11.141 -0.916)
        (xy -11.126 -0.933)
        (xy -11.11 -0.949)
        (xy -11.093 -0.965)
        (xy -11.077 -0.98)
        (xy -11.058 -0.994)
        (xy -11.039 -1.007)
        (xy -11.019 -1.02)
        (xy -10.998 -1.032)
        (xy -10.978 -1.042)
        (xy -10.955 -1.05)
        (xy -10.933 -1.058)
        (xy -10.911 -1.064)
        (xy -10.889 -1.07)
        (xy -10.866 -1.074)
        (xy -10.843 -1.078)
        (xy -10.82 -1.078)
        (xy -10.795 -1.08)
        (xy -10.773 -1.078)
        (xy -10.748 -1.078)
        (xy -10.725 -1.074)
        (xy -10.702 -1.07)
        (xy -10.68 -1.064)
        (xy -10.657 -1.058)
        (xy -10.636 -1.05)
        (xy -10.615 -1.042)
        (xy -10.593 -1.03)
        (xy -10.572 -1.019)
        (xy -10.554 -1.007)
        (xy -10.533 -0.994)
        (xy -10.516 -0.98)
        (xy -10.497 -0.965)
        (xy -10.481 -0.949)
        (xy -10.465 -0.933)
        (xy -10.449 -0.915)
        (xy -10.436 -0.897)
        (xy -10.423 -0.876)
        (xy -10.41 -0.856)
        (xy -10.399 -0.836)
        (xy -10.388 -0.815)
        (xy -10.381 -0.794)
        (xy -10.372 -0.773)
        (xy -10.365 -0.749)
        (xy -10.36 -0.727)
        (xy -10.356 -0.704)
        (xy -10.353 -0.682)
        (xy -10.352 -0.658)
        (xy -10.35 -0.634)
        (xy -10.352 -0.611)
        (xy -10.353 -0.587)
        (xy -10.356 -0.564)
        (xy -10.36 -0.542)
        (xy -10.365 -0.52)
        (xy -10.372 -0.496)
        (xy -10.381 -0.475)
        (xy -10.388 -0.454)
        (xy -10.399 -0.432)
        (xy -10.41 -0.412)
        (xy -10.423 -0.393)
        (xy -10.436 -0.372)
        (xy -10.449 -0.354)
        (xy -10.465 -0.337)
        (xy -10.481 -0.32)
        (xy -10.497 -0.303)
        (xy -10.516 -0.288)
        (xy -10.533 -0.275)
        (xy -10.554 -0.262)
        (xy -10.572 -0.249)
        (xy -10.593 -0.238)
        (xy -10.615 -0.228)
        (xy -10.636 -0.219)
        (xy -10.657 -0.211)
        (xy -10.68 -0.204)
        (xy -10.702 -0.2)
        (xy -10.725 -0.195)
        (xy -10.748 -0.192)
        (xy -10.773 -0.19)
        (xy -10.795 -0.189)
        (xy -10.82 -0.19)
        (xy -10.843 -0.192)
        (xy -10.866 -0.195)
        (xy -10.889 -0.2)
        (xy -10.911 -0.204)
        (xy -10.933 -0.211)
        (xy -10.955 -0.218)
        (xy -10.978 -0.228)
        (xy -10.998 -0.237)
        (xy -11.019 -0.248)
        (xy -11.039 -0.262)
        (xy -11.058 -0.275)
        (xy -11.077 -0.288)
        (xy -11.093 -0.303)
        (xy -11.11 -0.32)
        (xy -11.126 -0.337)
        (xy -11.141 -0.353)
        (xy -11.155 -0.372)
        (xy -11.168 -0.392)
        (xy -11.181 -0.411)
        (xy -11.192 -0.431)
        (xy -11.202 -0.453)
        (xy -11.212 -0.474)
        (xy -11.218 -0.496)
        (xy -11.225 -0.519)
        (xy -11.231 -0.541)
        (xy -11.235 -0.563)
        (xy -11.238 -0.586)
        (xy -11.24 -0.61)
        (xy -11.24 -0.631)
        (xy -10.795 -0.631)
        (xy -10.795 -0.636)
        (xy -10.795 -0.637)
      )

      (stroke (width 0.001) (type solid)) (fill solid) (layer "B.Paste"))
    (fp_poly
      (pts
        (xy -10.795 0.633)
        (xy -11.24 0.632)
        (xy -11.24 0.611)
        (xy -11.238 0.587)
        (xy -11.235 0.564)
        (xy -11.231 0.542)
        (xy -11.225 0.52)
        (xy -11.218 0.497)
        (xy -11.212 0.475)
        (xy -11.202 0.454)
        (xy -11.192 0.432)
        (xy -11.181 0.412)
        (xy -11.168 0.393)
        (xy -11.155 0.373)
        (xy -11.141 0.354)
        (xy -11.126 0.338)
        (xy -11.11 0.32)
        (xy -11.093 0.304)
        (xy -11.077 0.289)
        (xy -11.058 0.276)
        (xy -11.039 0.263)
        (xy -11.019 0.249)
        (xy -10.998 0.238)
        (xy -10.978 0.229)
        (xy -10.955 0.219)
        (xy -10.933 0.212)
        (xy -10.911 0.205)
        (xy -10.889 0.201)
        (xy -10.866 0.196)
        (xy -10.843 0.192)
        (xy -10.82 0.191)
        (xy -10.795 0.19)
        (xy -10.773 0.191)
        (xy -10.748 0.192)
        (xy -10.725 0.196)
        (xy -10.702 0.201)
        (xy -10.68 0.205)
        (xy -10.657 0.212)
        (xy -10.636 0.22)
        (xy -10.615 0.229)
        (xy -10.593 0.239)
        (xy -10.572 0.25)
        (xy -10.554 0.263)
        (xy -10.533 0.276)
        (xy -10.516 0.289)
        (xy -10.497 0.304)
        (xy -10.481 0.32)
        (xy -10.465 0.338)
        (xy -10.449 0.355)
        (xy -10.436 0.373)
        (xy -10.423 0.394)
        (xy -10.41 0.413)
        (xy -10.399 0.433)
        (xy -10.388 0.455)
        (xy -10.381 0.476)
        (xy -10.372 0.497)
        (xy -10.365 0.521)
        (xy -10.36 0.543)
        (xy -10.356 0.565)
        (xy -10.353 0.588)
        (xy -10.352 0.612)
        (xy -10.35 0.635)
        (xy -10.352 0.659)
        (xy -10.353 0.683)
        (xy -10.356 0.705)
        (xy -10.36 0.728)
        (xy -10.365 0.75)
        (xy -10.372 0.774)
        (xy -10.381 0.795)
        (xy -10.388 0.816)
        (xy -10.399 0.837)
        (xy -10.41 0.857)
        (xy -10.423 0.877)
        (xy -10.436 0.898)
        (xy -10.449 0.916)
        (xy -10.465 0.934)
        (xy -10.481 0.95)
        (xy -10.497 0.966)
        (xy -10.516 0.981)
        (xy -10.533 0.995)
        (xy -10.554 1.008)
        (xy -10.572 1.02)
        (xy -10.593 1.031)
        (xy -10.615 1.043)
        (xy -10.636 1.051)
        (xy -10.657 1.059)
        (xy -10.68 1.065)
        (xy -10.702 1.071)
        (xy -10.725 1.075)
        (xy -10.748 1.079)
        (xy -10.773 1.079)
        (xy -10.795 1.081)
        (xy -10.82 1.079)
        (xy -10.843 1.079)
        (xy -10.866 1.075)
        (xy -10.889 1.071)
        (xy -10.911 1.065)
        (xy -10.933 1.059)
        (xy -10.955 1.051)
        (xy -10.978 1.043)
        (xy -10.998 1.033)
        (xy -11.019 1.021)
        (xy -11.039 1.008)
        (xy -11.058 0.995)
        (xy -11.077 0.981)
        (xy -11.093 0.966)
        (xy -11.11 0.95)
        (xy -11.126 0.934)
        (xy -11.141 0.917)
        (xy -11.155 0.898)
        (xy -11.168 0.878)
        (xy -11.181 0.858)
        (xy -11.192 0.838)
        (xy -11.202 0.817)
        (xy -11.212 0.796)
        (xy -11.218 0.774)
        (xy -11.225 0.751)
        (xy -11.231 0.729)
        (xy -11.235 0.706)
        (xy -11.238 0.684)
        (xy -11.24 0.66)
        (xy -11.24 0.637)
        (xy -10.795 0.637)
        (xy -10.795 0.632)
        (xy -10.795 0.633)
      )

      (stroke (width 0.001) (type solid)) (fill solid) (layer "B.Paste"))
    (fp_poly
      (pts
        (xy -9.526 -4.447)
        (xy -9.971 -4.446)
        (xy -9.969 -4.469)
        (xy -9.968 -4.493)
        (xy -9.965 -4.515)
        (xy -9.961 -4.538)
        (xy -9.955 -4.56)
        (xy -9.949 -4.583)
        (xy -9.942 -4.605)
        (xy -9.933 -4.626)
        (xy -9.923 -4.647)
        (xy -9.911 -4.668)
        (xy -9.898 -4.687)
        (xy -9.885 -4.706)
        (xy -9.872 -4.725)
        (xy -9.856 -4.743)
        (xy -9.84 -4.759)
        (xy -9.824 -4.775)
        (xy -9.806 -4.791)
        (xy -9.788 -4.804)
        (xy -9.769 -4.817)
        (xy -9.748 -4.831)
        (xy -9.728 -4.841)
        (xy -9.708 -4.852)
        (xy -9.686 -4.86)
        (xy -9.664 -4.868)
        (xy -9.641 -4.874)
        (xy -9.619 -4.879)
        (xy -9.596 -4.884)
        (xy -9.574 -4.887)
        (xy -9.549 -4.889)
        (xy -9.526 -4.889)
        (xy -9.503 -4.889)
        (xy -9.478 -4.887)
        (xy -9.455 -4.884)
        (xy -9.433 -4.879)
        (xy -9.41 -4.874)
        (xy -9.388 -4.868)
        (xy -9.366 -4.86)
        (xy -9.344 -4.852)
        (xy -9.324 -4.841)
        (xy -9.304 -4.829)
        (xy -9.283 -4.817)
        (xy -9.263 -4.804)
        (xy -9.245 -4.791)
        (xy -9.228 -4.775)
        (xy -9.211 -4.759)
        (xy -9.195 -4.743)
        (xy -9.18 -4.724)
        (xy -9.165 -4.706)
        (xy -9.152 -4.687)
        (xy -9.141 -4.668)
        (xy -9.129 -4.647)
        (xy -9.119 -4.626)
        (xy -9.11 -4.603)
        (xy -9.103 -4.583)
        (xy -9.096 -4.559)
        (xy -9.09 -4.538)
        (xy -9.086 -4.514)
        (xy -9.083 -4.491)
        (xy -9.081 -4.467)
        (xy -9.08 -4.445)
        (xy -9.081 -4.421)
        (xy -9.083 -4.397)
        (xy -9.086 -4.374)
        (xy -9.09 -4.352)
        (xy -9.096 -4.329)
        (xy -9.103 -4.307)
        (xy -9.11 -4.285)
        (xy -9.119 -4.264)
        (xy -9.129 -4.243)
        (xy -9.141 -4.222)
        (xy -9.152 -4.203)
        (xy -9.165 -4.182)
        (xy -9.18 -4.164)
        (xy -9.195 -4.147)
        (xy -9.211 -4.129)
        (xy -9.228 -4.113)
        (xy -9.245 -4.099)
        (xy -9.263 -4.084)
        (xy -9.283 -4.071)
        (xy -9.304 -4.059)
        (xy -9.324 -4.049)
        (xy -9.344 -4.038)
        (xy -9.366 -4.03)
        (xy -9.388 -4.022)
        (xy -9.41 -4.014)
        (xy -9.433 -4.009)
        (xy -9.455 -4.004)
        (xy -9.478 -4.001)
        (xy -9.503 -4.001)
        (xy -9.526 -3.999)
        (xy -9.549 -4.001)
        (xy -9.574 -4.001)
        (xy -9.596 -4.004)
        (xy -9.619 -4.009)
        (xy -9.641 -4.014)
        (xy -9.664 -4.022)
        (xy -9.686 -4.028)
        (xy -9.708 -4.038)
        (xy -9.728 -4.047)
        (xy -9.748 -4.059)
        (xy -9.769 -4.071)
        (xy -9.788 -4.084)
        (xy -9.806 -4.099)
        (xy -9.824 -4.113)
        (xy -9.84 -4.129)
        (xy -9.856 -4.147)
        (xy -9.872 -4.163)
        (xy -9.885 -4.182)
        (xy -9.898 -4.201)
        (xy -9.911 -4.222)
        (xy -9.923 -4.241)
        (xy -9.933 -4.262)
        (xy -9.942 -4.285)
        (xy -9.949 -4.307)
        (xy -9.955 -4.328)
        (xy -9.961 -4.35)
        (xy -9.965 -4.373)
        (xy -9.968 -4.397)
        (xy -9.969 -4.421)
        (xy -9.971 -4.442)
        (xy -9.526 -4.442)
        (xy -9.526 -4.446)
        (xy -9.526 -4.447)
      )

      (stroke (width 0.001) (type solid)) (fill solid) (layer "B.Paste"))
    (fp_poly
      (pts
        (xy -9.526 -1.907)
        (xy -9.971 -1.906)
        (xy -9.969 -1.929)
        (xy -9.968 -1.953)
        (xy -9.965 -1.975)
        (xy -9.961 -1.999)
        (xy -9.955 -2.02)
        (xy -9.949 -2.043)
        (xy -9.942 -2.064)
        (xy -9.933 -2.087)
        (xy -9.923 -2.108)
        (xy -9.911 -2.128)
        (xy -9.898 -2.148)
        (xy -9.885 -2.166)
        (xy -9.872 -2.185)
        (xy -9.856 -2.202)
        (xy -9.84 -2.22)
        (xy -9.824 -2.236)
        (xy -9.806 -2.25)
        (xy -9.788 -2.265)
        (xy -9.769 -2.277)
        (xy -9.748 -2.29)
        (xy -9.728 -2.301)
        (xy -9.708 -2.311)
        (xy -9.686 -2.321)
        (xy -9.664 -2.327)
        (xy -9.641 -2.334)
        (xy -9.619 -2.339)
        (xy -9.596 -2.345)
        (xy -9.574 -2.347)
        (xy -9.549 -2.349)
        (xy -9.526 -2.35)
        (xy -9.503 -2.349)
        (xy -9.478 -2.347)
        (xy -9.455 -2.345)
        (xy -9.433 -2.339)
        (xy -9.41 -2.334)
        (xy -9.388 -2.327)
        (xy -9.366 -2.319)
        (xy -9.344 -2.311)
        (xy -9.324 -2.301)
        (xy -9.304 -2.289)
        (xy -9.283 -2.277)
        (xy -9.263 -2.265)
        (xy -9.245 -2.25)
        (xy -9.228 -2.236)
        (xy -9.211 -2.22)
        (xy -9.195 -2.202)
        (xy -9.18 -2.185)
        (xy -9.165 -2.166)
        (xy -9.152 -2.146)
        (xy -9.141 -2.126)
        (xy -9.129 -2.107)
        (xy -9.119 -2.085)
        (xy -9.11 -2.064)
        (xy -9.103 -2.043)
        (xy -9.096 -2.019)
        (xy -9.09 -1.997)
        (xy -9.086 -1.975)
        (xy -9.083 -1.951)
        (xy -9.081 -1.927)
        (xy -9.08 -1.904)
        (xy -9.081 -1.881)
        (xy -9.083 -1.858)
        (xy -9.086 -1.834)
        (xy -9.09 -1.812)
        (xy -9.096 -1.789)
        (xy -9.103 -1.766)
        (xy -9.11 -1.745)
        (xy -9.119 -1.723)
        (xy -9.129 -1.703)
        (xy -9.141 -1.683)
        (xy -9.152 -1.662)
        (xy -9.165 -1.642)
        (xy -9.18 -1.624)
        (xy -9.195 -1.606)
        (xy -9.211 -1.59)
        (xy -9.228 -1.574)
        (xy -9.245 -1.558)
        (xy -9.263 -1.544)
        (xy -9.283 -1.531)
        (xy -9.304 -1.519)
        (xy -9.324 -1.508)
        (xy -9.344 -1.497)
        (xy -9.366 -1.489)
        (xy -9.388 -1.481)
        (xy -9.41 -1.475)
        (xy -9.433 -1.469)
        (xy -9.455 -1.465)
        (xy -9.478 -1.461)
        (xy -9.503 -1.461)
        (xy -9.526 -1.459)
        (xy -9.549 -1.461)
        (xy -9.574 -1.461)
        (xy -9.596 -1.465)
        (xy -9.619 -1.469)
        (xy -9.641 -1.475)
        (xy -9.664 -1.481)
        (xy -9.686 -1.489)
        (xy -9.708 -1.497)
        (xy -9.728 -1.507)
        (xy -9.748 -1.518)
        (xy -9.769 -1.531)
        (xy -9.788 -1.544)
        (xy -9.806 -1.558)
        (xy -9.824 -1.574)
        (xy -9.84 -1.59)
        (xy -9.856 -1.606)
        (xy -9.872 -1.624)
        (xy -9.885 -1.642)
        (xy -9.898 -1.661)
        (xy -9.911 -1.681)
        (xy -9.923 -1.701)
        (xy -9.933 -1.723)
        (xy -9.942 -1.745)
        (xy -9.949 -1.766)
        (xy -9.955 -1.788)
        (xy -9.961 -1.81)
        (xy -9.965 -1.834)
        (xy -9.968 -1.856)
        (xy -9.969 -1.88)
        (xy -9.971 -1.902)
        (xy -9.526 -1.902)
        (xy -9.526 -1.906)
        (xy -9.526 -1.907)
      )

      (stroke (width 0.001) (type solid)) (fill solid) (layer "B.Paste"))
    (fp_poly
      (pts
        (xy -9.526 -0.637)
        (xy -9.971 -0.636)
        (xy -9.969 -0.659)
        (xy -9.968 -0.683)
        (xy -9.965 -0.705)
        (xy -9.961 -0.728)
        (xy -9.955 -0.75)
        (xy -9.949 -0.773)
        (xy -9.942 -0.795)
        (xy -9.933 -0.816)
        (xy -9.923 -0.837)
        (xy -9.911 -0.857)
        (xy -9.898 -0.877)
        (xy -9.885 -0.897)
        (xy -9.872 -0.916)
        (xy -9.856 -0.933)
        (xy -9.84 -0.949)
        (xy -9.824 -0.965)
        (xy -9.806 -0.98)
        (xy -9.788 -0.994)
        (xy -9.769 -1.007)
        (xy -9.748 -1.02)
        (xy -9.728 -1.032)
        (xy -9.708 -1.042)
        (xy -9.686 -1.05)
        (xy -9.664 -1.058)
        (xy -9.641 -1.064)
        (xy -9.619 -1.07)
        (xy -9.596 -1.074)
        (xy -9.574 -1.078)
        (xy -9.549 -1.078)
        (xy -9.526 -1.08)
        (xy -9.503 -1.078)
        (xy -9.478 -1.078)
        (xy -9.455 -1.074)
        (xy -9.433 -1.07)
        (xy -9.41 -1.064)
        (xy -9.388 -1.058)
        (xy -9.366 -1.05)
        (xy -9.344 -1.042)
        (xy -9.324 -1.03)
        (xy -9.304 -1.019)
        (xy -9.283 -1.007)
        (xy -9.263 -0.994)
        (xy -9.245 -0.98)
        (xy -9.228 -0.965)
        (xy -9.211 -0.949)
        (xy -9.195 -0.933)
        (xy -9.18 -0.915)
        (xy -9.165 -0.897)
        (xy -9.152 -0.876)
        (xy -9.141 -0.856)
        (xy -9.129 -0.836)
        (xy -9.119 -0.815)
        (xy -9.11 -0.794)
        (xy -9.103 -0.773)
        (xy -9.096 -0.749)
        (xy -9.09 -0.727)
        (xy -9.086 -0.704)
        (xy -9.083 -0.682)
        (xy -9.081 -0.658)
        (xy -9.08 -0.634)
        (xy -9.081 -0.611)
        (xy -9.083 -0.587)
        (xy -9.086 -0.564)
        (xy -9.09 -0.542)
        (xy -9.096 -0.52)
        (xy -9.103 -0.496)
        (xy -9.11 -0.475)
        (xy -9.119 -0.454)
        (xy -9.129 -0.432)
        (xy -9.141 -0.412)
        (xy -9.152 -0.393)
        (xy -9.165 -0.372)
        (xy -9.18 -0.354)
        (xy -9.195 -0.337)
        (xy -9.211 -0.32)
        (xy -9.228 -0.303)
        (xy -9.245 -0.288)
        (xy -9.263 -0.275)
        (xy -9.283 -0.262)
        (xy -9.304 -0.249)
        (xy -9.324 -0.238)
        (xy -9.344 -0.228)
        (xy -9.366 -0.219)
        (xy -9.388 -0.211)
        (xy -9.41 -0.204)
        (xy -9.433 -0.2)
        (xy -9.455 -0.195)
        (xy -9.478 -0.192)
        (xy -9.503 -0.19)
        (xy -9.526 -0.189)
        (xy -9.549 -0.19)
        (xy -9.574 -0.192)
        (xy -9.596 -0.195)
        (xy -9.619 -0.2)
        (xy -9.641 -0.204)
        (xy -9.664 -0.211)
        (xy -9.686 -0.218)
        (xy -9.708 -0.228)
        (xy -9.728 -0.237)
        (xy -9.748 -0.248)
        (xy -9.769 -0.262)
        (xy -9.788 -0.275)
        (xy -9.806 -0.288)
        (xy -9.824 -0.303)
        (xy -9.84 -0.32)
        (xy -9.856 -0.337)
        (xy -9.872 -0.353)
        (xy -9.885 -0.372)
        (xy -9.898 -0.392)
        (xy -9.911 -0.411)
        (xy -9.923 -0.431)
        (xy -9.933 -0.453)
        (xy -9.942 -0.474)
        (xy -9.949 -0.496)
        (xy -9.955 -0.519)
        (xy -9.961 -0.541)
        (xy -9.965 -0.563)
        (xy -9.968 -0.586)
        (xy -9.969 -0.61)
        (xy -9.971 -0.631)
        (xy -9.526 -0.631)
        (xy -9.526 -0.636)
        (xy -9.526 -0.637)
      )

      (stroke (width 0.001) (type solid)) (fill solid) (layer "B.Paste"))
    (fp_poly
      (pts
        (xy -9.526 0.633)
        (xy -9.971 0.632)
        (xy -9.969 0.611)
        (xy -9.968 0.587)
        (xy -9.965 0.564)
        (xy -9.961 0.542)
        (xy -9.955 0.52)
        (xy -9.949 0.497)
        (xy -9.942 0.475)
        (xy -9.933 0.454)
        (xy -9.923 0.432)
        (xy -9.911 0.412)
        (xy -9.898 0.393)
        (xy -9.885 0.373)
        (xy -9.872 0.354)
        (xy -9.856 0.338)
        (xy -9.84 0.32)
        (xy -9.824 0.304)
        (xy -9.806 0.289)
        (xy -9.788 0.276)
        (xy -9.769 0.263)
        (xy -9.748 0.249)
        (xy -9.728 0.238)
        (xy -9.708 0.229)
        (xy -9.686 0.219)
        (xy -9.664 0.212)
        (xy -9.641 0.205)
        (xy -9.619 0.201)
        (xy -9.596 0.196)
        (xy -9.574 0.192)
        (xy -9.549 0.191)
        (xy -9.526 0.19)
        (xy -9.503 0.191)
        (xy -9.478 0.192)
        (xy -9.455 0.196)
        (xy -9.433 0.201)
        (xy -9.41 0.205)
        (xy -9.388 0.212)
        (xy -9.366 0.22)
        (xy -9.344 0.229)
        (xy -9.324 0.239)
        (xy -9.304 0.25)
        (xy -9.283 0.263)
        (xy -9.263 0.276)
        (xy -9.245 0.289)
        (xy -9.228 0.304)
        (xy -9.211 0.32)
        (xy -9.195 0.338)
        (xy -9.18 0.355)
        (xy -9.165 0.373)
        (xy -9.152 0.394)
        (xy -9.141 0.413)
        (xy -9.129 0.433)
        (xy -9.119 0.455)
        (xy -9.11 0.476)
        (xy -9.103 0.497)
        (xy -9.096 0.521)
        (xy -9.09 0.543)
        (xy -9.086 0.565)
        (xy -9.083 0.588)
        (xy -9.081 0.612)
        (xy -9.08 0.635)
        (xy -9.081 0.659)
        (xy -9.083 0.683)
        (xy -9.086 0.705)
        (xy -9.09 0.728)
        (xy -9.096 0.75)
        (xy -9.103 0.774)
        (xy -9.11 0.795)
        (xy -9.119 0.816)
        (xy -9.129 0.837)
        (xy -9.141 0.857)
        (xy -9.152 0.877)
        (xy -9.165 0.898)
        (xy -9.18 0.916)
        (xy -9.195 0.934)
        (xy -9.211 0.95)
        (xy -9.228 0.966)
        (xy -9.245 0.981)
        (xy -9.263 0.995)
        (xy -9.283 1.008)
        (xy -9.304 1.02)
        (xy -9.324 1.031)
        (xy -9.344 1.043)
        (xy -9.366 1.051)
        (xy -9.388 1.059)
        (xy -9.41 1.065)
        (xy -9.433 1.071)
        (xy -9.455 1.075)
        (xy -9.478 1.079)
        (xy -9.503 1.079)
        (xy -9.526 1.081)
        (xy -9.549 1.079)
        (xy -9.574 1.079)
        (xy -9.596 1.075)
        (xy -9.619 1.071)
        (xy -9.641 1.065)
        (xy -9.664 1.059)
        (xy -9.686 1.051)
        (xy -9.708 1.043)
        (xy -9.728 1.033)
        (xy -9.748 1.021)
        (xy -9.769 1.008)
        (xy -9.788 0.995)
        (xy -9.806 0.981)
        (xy -9.824 0.966)
        (xy -9.84 0.95)
        (xy -9.856 0.934)
        (xy -9.872 0.917)
        (xy -9.885 0.898)
        (xy -9.898 0.878)
        (xy -9.911 0.858)
        (xy -9.923 0.838)
        (xy -9.933 0.817)
        (xy -9.942 0.796)
        (xy -9.949 0.774)
        (xy -9.955 0.751)
        (xy -9.961 0.729)
        (xy -9.965 0.706)
        (xy -9.968 0.684)
        (xy -9.969 0.66)
        (xy -9.971 0.637)
        (xy -9.526 0.637)
        (xy -9.526 0.632)
        (xy -9.526 0.633)
      )

      (stroke (width 0.001) (type solid)) (fill solid) (layer "B.Paste"))
    (fp_poly
      (pts
        (xy -8.256 -4.447)
        (xy -8.7 -4.446)
        (xy -8.699 -4.469)
        (xy -8.699 -4.493)
        (xy -8.696 -4.515)
        (xy -8.69 -4.538)
        (xy -8.686 -4.56)
        (xy -8.679 -4.583)
        (xy -8.671 -4.605)
        (xy -8.663 -4.626)
        (xy -8.652 -4.647)
        (xy -8.641 -4.668)
        (xy -8.628 -4.687)
        (xy -8.616 -4.706)
        (xy -8.602 -4.725)
        (xy -8.587 -4.743)
        (xy -8.571 -4.759)
        (xy -8.554 -4.775)
        (xy -8.536 -4.791)
        (xy -8.517 -4.804)
        (xy -8.498 -4.817)
        (xy -8.478 -4.831)
        (xy -8.459 -4.841)
        (xy -8.437 -4.852)
        (xy -8.415 -4.86)
        (xy -8.394 -4.868)
        (xy -8.372 -4.874)
        (xy -8.35 -4.879)
        (xy -8.327 -4.884)
        (xy -8.304 -4.887)
        (xy -8.279 -4.889)
        (xy -8.256 -4.889)
        (xy -8.232 -4.889)
        (xy -8.209 -4.887)
        (xy -8.186 -4.884)
        (xy -8.163 -4.879)
        (xy -8.141 -4.874)
        (xy -8.118 -4.868)
        (xy -8.096 -4.86)
        (xy -8.074 -4.852)
        (xy -8.054 -4.841)
        (xy -8.033 -4.829)
        (xy -8.013 -4.817)
        (xy -7.994 -4.804)
        (xy -7.975 -4.791)
        (xy -7.957 -4.775)
        (xy -7.941 -4.759)
        (xy -7.925 -4.743)
        (xy -7.909 -4.724)
        (xy -7.895 -4.706)
        (xy -7.882 -4.687)
        (xy -7.87 -4.666)
        (xy -7.859 -4.647)
        (xy -7.848 -4.626)
        (xy -7.84 -4.603)
        (xy -7.832 -4.583)
        (xy -7.826 -4.559)
        (xy -7.821 -4.538)
        (xy -7.816 -4.514)
        (xy -7.813 -4.491)
        (xy -7.811 -4.467)
        (xy -7.81 -4.445)
        (xy -7.811 -4.421)
        (xy -7.813 -4.397)
        (xy -7.816 -4.374)
        (xy -7.821 -4.352)
        (xy -7.826 -4.329)
        (xy -7.832 -4.307)
        (xy -7.84 -4.285)
        (xy -7.848 -4.264)
        (xy -7.859 -4.243)
        (xy -7.87 -4.222)
        (xy -7.882 -4.203)
        (xy -7.895 -4.182)
        (xy -7.909 -4.164)
        (xy -7.925 -4.147)
        (xy -7.941 -4.129)
        (xy -7.957 -4.113)
        (xy -7.975 -4.099)
        (xy -7.994 -4.084)
        (xy -8.013 -4.071)
        (xy -8.033 -4.059)
        (xy -8.054 -4.049)
        (xy -8.074 -4.038)
        (xy -8.096 -4.03)
        (xy -8.118 -4.022)
        (xy -8.141 -4.014)
        (xy -8.163 -4.009)
        (xy -8.186 -4.004)
        (xy -8.209 -4.001)
        (xy -8.232 -4.001)
        (xy -8.256 -3.999)
        (xy -8.279 -4.001)
        (xy -8.304 -4.001)
        (xy -8.327 -4.004)
        (xy -8.35 -4.009)
        (xy -8.372 -4.014)
        (xy -8.394 -4.022)
        (xy -8.415 -4.028)
        (xy -8.437 -4.038)
        (xy -8.459 -4.047)
        (xy -8.478 -4.059)
        (xy -8.498 -4.071)
        (xy -8.517 -4.084)
        (xy -8.536 -4.099)
        (xy -8.554 -4.113)
        (xy -8.571 -4.129)
        (xy -8.587 -4.147)
        (xy -8.602 -4.163)
        (xy -8.616 -4.182)
        (xy -8.628 -4.201)
        (xy -8.641 -4.222)
        (xy -8.652 -4.241)
        (xy -8.663 -4.262)
        (xy -8.671 -4.285)
        (xy -8.679 -4.307)
        (xy -8.686 -4.328)
        (xy -8.69 -4.35)
        (xy -8.696 -4.373)
        (xy -8.699 -4.397)
        (xy -8.699 -4.421)
        (xy -8.7 -4.442)
        (xy -8.256 -4.442)
        (xy -8.256 -4.446)
        (xy -8.256 -4.447)
      )

      (stroke (width 0.001) (type solid)) (fill solid) (layer "B.Paste"))
    (fp_poly
      (pts
        (xy -8.256 -1.907)
        (xy -8.7 -1.906)
        (xy -8.699 -1.929)
        (xy -8.699 -1.953)
        (xy -8.696 -1.975)
        (xy -8.69 -1.999)
        (xy -8.686 -2.02)
        (xy -8.679 -2.043)
        (xy -8.671 -2.064)
        (xy -8.663 -2.087)
        (xy -8.652 -2.108)
        (xy -8.641 -2.128)
        (xy -8.628 -2.148)
        (xy -8.616 -2.166)
        (xy -8.602 -2.185)
        (xy -8.587 -2.202)
        (xy -8.571 -2.22)
        (xy -8.554 -2.236)
        (xy -8.536 -2.25)
        (xy -8.517 -2.265)
        (xy -8.498 -2.277)
        (xy -8.478 -2.29)
        (xy -8.459 -2.301)
        (xy -8.437 -2.311)
        (xy -8.415 -2.321)
        (xy -8.394 -2.327)
        (xy -8.372 -2.334)
        (xy -8.35 -2.339)
        (xy -8.327 -2.345)
        (xy -8.304 -2.347)
        (xy -8.279 -2.349)
        (xy -8.256 -2.35)
        (xy -8.232 -2.349)
        (xy -8.209 -2.347)
        (xy -8.186 -2.345)
        (xy -8.163 -2.339)
        (xy -8.141 -2.334)
        (xy -8.118 -2.327)
        (xy -8.096 -2.319)
        (xy -8.074 -2.311)
        (xy -8.054 -2.301)
        (xy -8.033 -2.289)
        (xy -8.013 -2.277)
        (xy -7.994 -2.265)
        (xy -7.975 -2.25)
        (xy -7.957 -2.236)
        (xy -7.941 -2.22)
        (xy -7.925 -2.202)
        (xy -7.909 -2.185)
        (xy -7.895 -2.166)
        (xy -7.882 -2.146)
        (xy -7.87 -2.126)
        (xy -7.859 -2.107)
        (xy -7.848 -2.085)
        (xy -7.84 -2.064)
        (xy -7.832 -2.043)
        (xy -7.826 -2.019)
        (xy -7.821 -1.997)
        (xy -7.816 -1.975)
        (xy -7.813 -1.951)
        (xy -7.811 -1.927)
        (xy -7.81 -1.904)
        (xy -7.811 -1.881)
        (xy -7.813 -1.858)
        (xy -7.816 -1.834)
        (xy -7.821 -1.812)
        (xy -7.826 -1.789)
        (xy -7.832 -1.766)
        (xy -7.84 -1.745)
        (xy -7.848 -1.723)
        (xy -7.859 -1.703)
        (xy -7.87 -1.683)
        (xy -7.882 -1.662)
        (xy -7.895 -1.642)
        (xy -7.909 -1.624)
        (xy -7.925 -1.606)
        (xy -7.941 -1.59)
        (xy -7.957 -1.574)
        (xy -7.975 -1.558)
        (xy -7.994 -1.544)
        (xy -8.013 -1.531)
        (xy -8.033 -1.519)
        (xy -8.054 -1.508)
        (xy -8.074 -1.497)
        (xy -8.096 -1.489)
        (xy -8.118 -1.481)
        (xy -8.141 -1.475)
        (xy -8.163 -1.469)
        (xy -8.186 -1.465)
        (xy -8.209 -1.461)
        (xy -8.232 -1.461)
        (xy -8.256 -1.459)
        (xy -8.279 -1.461)
        (xy -8.304 -1.461)
        (xy -8.327 -1.465)
        (xy -8.35 -1.469)
        (xy -8.372 -1.475)
        (xy -8.394 -1.481)
        (xy -8.415 -1.489)
        (xy -8.437 -1.497)
        (xy -8.459 -1.507)
        (xy -8.478 -1.518)
        (xy -8.498 -1.531)
        (xy -8.517 -1.544)
        (xy -8.536 -1.558)
        (xy -8.554 -1.574)
        (xy -8.571 -1.59)
        (xy -8.587 -1.606)
        (xy -8.602 -1.624)
        (xy -8.616 -1.642)
        (xy -8.628 -1.661)
        (xy -8.641 -1.681)
        (xy -8.652 -1.701)
        (xy -8.663 -1.723)
        (xy -8.671 -1.745)
        (xy -8.679 -1.766)
        (xy -8.686 -1.788)
        (xy -8.69 -1.81)
        (xy -8.696 -1.834)
        (xy -8.699 -1.856)
        (xy -8.699 -1.88)
        (xy -8.7 -1.902)
        (xy -8.256 -1.902)
        (xy -8.256 -1.906)
        (xy -8.256 -1.907)
      )

      (stroke (width 0.001) (type solid)) (fill solid) (layer "B.Paste"))
    (fp_poly
      (pts
        (xy -8.256 -0.637)
        (xy -8.7 -0.636)
        (xy -8.699 -0.659)
        (xy -8.699 -0.683)
        (xy -8.696 -0.705)
        (xy -8.69 -0.728)
        (xy -8.686 -0.75)
        (xy -8.679 -0.773)
        (xy -8.671 -0.795)
        (xy -8.663 -0.816)
        (xy -8.652 -0.837)
        (xy -8.641 -0.857)
        (xy -8.628 -0.877)
        (xy -8.616 -0.897)
        (xy -8.602 -0.916)
        (xy -8.587 -0.933)
        (xy -8.571 -0.949)
        (xy -8.554 -0.965)
        (xy -8.536 -0.98)
        (xy -8.517 -0.994)
        (xy -8.498 -1.007)
        (xy -8.478 -1.02)
        (xy -8.459 -1.032)
        (xy -8.437 -1.042)
        (xy -8.415 -1.05)
        (xy -8.394 -1.058)
        (xy -8.372 -1.064)
        (xy -8.35 -1.07)
        (xy -8.327 -1.074)
        (xy -8.304 -1.078)
        (xy -8.279 -1.078)
        (xy -8.256 -1.08)
        (xy -8.232 -1.078)
        (xy -8.209 -1.078)
        (xy -8.186 -1.074)
        (xy -8.163 -1.07)
        (xy -8.141 -1.064)
        (xy -8.118 -1.058)
        (xy -8.096 -1.05)
        (xy -8.074 -1.042)
        (xy -8.054 -1.03)
        (xy -8.033 -1.019)
        (xy -8.013 -1.007)
        (xy -7.994 -0.994)
        (xy -7.975 -0.98)
        (xy -7.957 -0.965)
        (xy -7.941 -0.949)
        (xy -7.925 -0.933)
        (xy -7.909 -0.915)
        (xy -7.895 -0.897)
        (xy -7.882 -0.876)
        (xy -7.87 -0.856)
        (xy -7.859 -0.836)
        (xy -7.848 -0.815)
        (xy -7.84 -0.794)
        (xy -7.832 -0.773)
        (xy -7.826 -0.749)
        (xy -7.821 -0.727)
        (xy -7.816 -0.704)
        (xy -7.813 -0.682)
        (xy -7.811 -0.658)
        (xy -7.81 -0.634)
        (xy -7.811 -0.611)
        (xy -7.813 -0.587)
        (xy -7.816 -0.564)
        (xy -7.821 -0.542)
        (xy -7.826 -0.52)
        (xy -7.832 -0.496)
        (xy -7.84 -0.475)
        (xy -7.848 -0.454)
        (xy -7.859 -0.432)
        (xy -7.87 -0.412)
        (xy -7.882 -0.393)
        (xy -7.895 -0.372)
        (xy -7.909 -0.354)
        (xy -7.925 -0.337)
        (xy -7.941 -0.32)
        (xy -7.957 -0.303)
        (xy -7.975 -0.288)
        (xy -7.994 -0.275)
        (xy -8.013 -0.262)
        (xy -8.033 -0.249)
        (xy -8.054 -0.238)
        (xy -8.074 -0.228)
        (xy -8.096 -0.219)
        (xy -8.118 -0.211)
        (xy -8.141 -0.204)
        (xy -8.163 -0.2)
        (xy -8.186 -0.195)
        (xy -8.209 -0.192)
        (xy -8.232 -0.19)
        (xy -8.256 -0.189)
        (xy -8.279 -0.19)
        (xy -8.304 -0.192)
        (xy -8.327 -0.195)
        (xy -8.35 -0.2)
        (xy -8.372 -0.204)
        (xy -8.394 -0.211)
        (xy -8.415 -0.218)
        (xy -8.437 -0.228)
        (xy -8.459 -0.237)
        (xy -8.478 -0.248)
        (xy -8.498 -0.262)
        (xy -8.517 -0.275)
        (xy -8.536 -0.288)
        (xy -8.554 -0.303)
        (xy -8.571 -0.32)
        (xy -8.587 -0.337)
        (xy -8.602 -0.353)
        (xy -8.616 -0.372)
        (xy -8.628 -0.392)
        (xy -8.641 -0.411)
        (xy -8.652 -0.431)
        (xy -8.663 -0.453)
        (xy -8.671 -0.474)
        (xy -8.679 -0.496)
        (xy -8.686 -0.519)
        (xy -8.69 -0.541)
        (xy -8.696 -0.563)
        (xy -8.699 -0.586)
        (xy -8.699 -0.61)
        (xy -8.7 -0.631)
        (xy -8.256 -0.631)
        (xy -8.256 -0.636)
        (xy -8.256 -0.637)
      )

      (stroke (width 0.001) (type solid)) (fill solid) (layer "B.Paste"))
    (fp_poly
      (pts
        (xy -8.256 0.633)
        (xy -8.7 0.632)
        (xy -8.699 0.611)
        (xy -8.699 0.587)
        (xy -8.696 0.564)
        (xy -8.69 0.542)
        (xy -8.686 0.52)
        (xy -8.679 0.497)
        (xy -8.671 0.475)
        (xy -8.663 0.454)
        (xy -8.652 0.432)
        (xy -8.641 0.412)
        (xy -8.628 0.393)
        (xy -8.616 0.373)
        (xy -8.602 0.354)
        (xy -8.587 0.338)
        (xy -8.571 0.32)
        (xy -8.554 0.304)
        (xy -8.536 0.289)
        (xy -8.517 0.276)
        (xy -8.498 0.263)
        (xy -8.478 0.249)
        (xy -8.459 0.238)
        (xy -8.437 0.229)
        (xy -8.415 0.219)
        (xy -8.394 0.212)
        (xy -8.372 0.205)
        (xy -8.35 0.201)
        (xy -8.327 0.196)
        (xy -8.304 0.192)
        (xy -8.279 0.191)
        (xy -8.256 0.19)
        (xy -8.232 0.191)
        (xy -8.209 0.192)
        (xy -8.186 0.196)
        (xy -8.163 0.201)
        (xy -8.141 0.205)
        (xy -8.118 0.212)
        (xy -8.096 0.22)
        (xy -8.074 0.229)
        (xy -8.054 0.239)
        (xy -8.033 0.25)
        (xy -8.013 0.263)
        (xy -7.994 0.276)
        (xy -7.975 0.289)
        (xy -7.957 0.304)
        (xy -7.941 0.32)
        (xy -7.925 0.338)
        (xy -7.909 0.355)
        (xy -7.895 0.373)
        (xy -7.882 0.394)
        (xy -7.87 0.413)
        (xy -7.859 0.433)
        (xy -7.848 0.455)
        (xy -7.84 0.476)
        (xy -7.832 0.497)
        (xy -7.826 0.521)
        (xy -7.821 0.543)
        (xy -7.816 0.565)
        (xy -7.813 0.588)
        (xy -7.811 0.612)
        (xy -7.81 0.635)
        (xy -7.811 0.659)
        (xy -7.813 0.683)
        (xy -7.816 0.705)
        (xy -7.821 0.728)
        (xy -7.826 0.75)
        (xy -7.832 0.774)
        (xy -7.84 0.795)
        (xy -7.848 0.816)
        (xy -7.859 0.837)
        (xy -7.87 0.857)
        (xy -7.882 0.877)
        (xy -7.895 0.898)
        (xy -7.909 0.916)
        (xy -7.925 0.934)
        (xy -7.941 0.95)
        (xy -7.957 0.966)
        (xy -7.975 0.981)
        (xy -7.994 0.995)
        (xy -8.013 1.008)
        (xy -8.033 1.02)
        (xy -8.054 1.031)
        (xy -8.074 1.043)
        (xy -8.096 1.051)
        (xy -8.118 1.059)
        (xy -8.141 1.065)
        (xy -8.163 1.071)
        (xy -8.186 1.075)
        (xy -8.209 1.079)
        (xy -8.232 1.079)
        (xy -8.256 1.081)
        (xy -8.279 1.079)
        (xy -8.304 1.079)
        (xy -8.327 1.075)
        (xy -8.35 1.071)
        (xy -8.372 1.065)
        (xy -8.394 1.059)
        (xy -8.415 1.051)
        (xy -8.437 1.043)
        (xy -8.459 1.033)
        (xy -8.478 1.021)
        (xy -8.498 1.008)
        (xy -8.517 0.995)
        (xy -8.536 0.981)
        (xy -8.554 0.966)
        (xy -8.571 0.95)
        (xy -8.587 0.934)
        (xy -8.602 0.917)
        (xy -8.616 0.898)
        (xy -8.628 0.878)
        (xy -8.641 0.858)
        (xy -8.652 0.838)
        (xy -8.663 0.817)
        (xy -8.671 0.796)
        (xy -8.679 0.774)
        (xy -8.686 0.751)
        (xy -8.69 0.729)
        (xy -8.696 0.706)
        (xy -8.699 0.684)
        (xy -8.699 0.66)
        (xy -8.7 0.637)
        (xy -8.256 0.637)
        (xy -8.256 0.632)
        (xy -8.256 0.633)
      )

      (stroke (width 0.001) (type solid)) (fill solid) (layer "B.Paste"))
    (fp_poly
      (pts
        (xy -6.986 -4.447)
        (xy -7.43 -4.446)
        (xy -7.43 -4.469)
        (xy -7.428 -4.493)
        (xy -7.425 -4.515)
        (xy -7.42 -4.538)
        (xy -7.415 -4.56)
        (xy -7.409 -4.583)
        (xy -7.401 -4.605)
        (xy -7.393 -4.626)
        (xy -7.382 -4.647)
        (xy -7.372 -4.668)
        (xy -7.358 -4.687)
        (xy -7.345 -4.706)
        (xy -7.332 -4.725)
        (xy -7.316 -4.743)
        (xy -7.3 -4.759)
        (xy -7.284 -4.775)
        (xy -7.266 -4.791)
        (xy -7.247 -4.804)
        (xy -7.228 -4.817)
        (xy -7.209 -4.831)
        (xy -7.188 -4.841)
        (xy -7.167 -4.852)
        (xy -7.145 -4.86)
        (xy -7.124 -4.868)
        (xy -7.101 -4.874)
        (xy -7.079 -4.879)
        (xy -7.056 -4.884)
        (xy -7.034 -4.887)
        (xy -7.01 -4.889)
        (xy -6.986 -4.889)
        (xy -6.962 -4.889)
        (xy -6.938 -4.887)
        (xy -6.915 -4.884)
        (xy -6.893 -4.879)
        (xy -6.87 -4.874)
        (xy -6.848 -4.868)
        (xy -6.826 -4.86)
        (xy -6.805 -4.852)
        (xy -6.784 -4.841)
        (xy -6.763 -4.829)
        (xy -6.744 -4.817)
        (xy -6.723 -4.804)
        (xy -6.705 -4.791)
        (xy -6.688 -4.775)
        (xy -6.67 -4.759)
        (xy -6.654 -4.743)
        (xy -6.64 -4.724)
        (xy -6.625 -4.706)
        (xy -6.612 -4.687)
        (xy -6.6 -4.668)
        (xy -6.59 -4.647)
        (xy -6.579 -4.626)
        (xy -6.571 -4.603)
        (xy -6.563 -4.583)
        (xy -6.555 -4.559)
        (xy -6.55 -4.538)
        (xy -6.545 -4.514)
        (xy -6.542 -4.491)
        (xy -6.542 -4.467)
        (xy -6.54 -4.445)
        (xy -6.542 -4.421)
        (xy -6.542 -4.397)
        (xy -6.545 -4.374)
        (xy -6.55 -4.352)
        (xy -6.555 -4.329)
        (xy -6.563 -4.307)
        (xy -6.571 -4.285)
        (xy -6.579 -4.264)
        (xy -6.59 -4.243)
        (xy -6.6 -4.222)
        (xy -6.612 -4.203)
        (xy -6.625 -4.182)
        (xy -6.64 -4.164)
        (xy -6.654 -4.147)
        (xy -6.67 -4.129)
        (xy -6.688 -4.113)
        (xy -6.705 -4.099)
        (xy -6.723 -4.084)
        (xy -6.744 -4.071)
        (xy -6.763 -4.059)
        (xy -6.784 -4.049)
        (xy -6.805 -4.038)
        (xy -6.826 -4.03)
        (xy -6.848 -4.022)
        (xy -6.87 -4.014)
        (xy -6.893 -4.009)
        (xy -6.915 -4.004)
        (xy -6.938 -4.001)
        (xy -6.962 -4.001)
        (xy -6.986 -3.999)
        (xy -7.01 -4.001)
        (xy -7.034 -4.001)
        (xy -7.056 -4.004)
        (xy -7.079 -4.009)
        (xy -7.101 -4.014)
        (xy -7.124 -4.022)
        (xy -7.145 -4.028)
        (xy -7.167 -4.038)
        (xy -7.188 -4.047)
        (xy -7.209 -4.059)
        (xy -7.228 -4.071)
        (xy -7.247 -4.084)
        (xy -7.266 -4.099)
        (xy -7.284 -4.113)
        (xy -7.3 -4.129)
        (xy -7.316 -4.147)
        (xy -7.332 -4.163)
        (xy -7.345 -4.182)
        (xy -7.358 -4.201)
        (xy -7.372 -4.222)
        (xy -7.382 -4.241)
        (xy -7.393 -4.262)
        (xy -7.401 -4.285)
        (xy -7.409 -4.307)
        (xy -7.415 -4.328)
        (xy -7.42 -4.35)
        (xy -7.425 -4.373)
        (xy -7.428 -4.397)
        (xy -7.43 -4.421)
        (xy -7.43 -4.442)
        (xy -6.986 -4.442)
        (xy -6.986 -4.446)
        (xy -6.986 -4.447)
      )

      (stroke (width 0.001) (type solid)) (fill solid) (layer "B.Paste"))
    (fp_poly
      (pts
        (xy -6.986 -1.907)
        (xy -7.43 -1.906)
        (xy -7.43 -1.929)
        (xy -7.428 -1.953)
        (xy -7.425 -1.975)
        (xy -7.42 -1.999)
        (xy -7.415 -2.02)
        (xy -7.409 -2.043)
        (xy -7.401 -2.064)
        (xy -7.393 -2.087)
        (xy -7.382 -2.108)
        (xy -7.372 -2.128)
        (xy -7.358 -2.148)
        (xy -7.345 -2.166)
        (xy -7.332 -2.185)
        (xy -7.316 -2.202)
        (xy -7.3 -2.22)
        (xy -7.284 -2.236)
        (xy -7.266 -2.25)
        (xy -7.247 -2.265)
        (xy -7.228 -2.277)
        (xy -7.209 -2.29)
        (xy -7.188 -2.301)
        (xy -7.167 -2.311)
        (xy -7.145 -2.321)
        (xy -7.124 -2.327)
        (xy -7.101 -2.334)
        (xy -7.079 -2.339)
        (xy -7.056 -2.345)
        (xy -7.034 -2.347)
        (xy -7.01 -2.349)
        (xy -6.986 -2.35)
        (xy -6.962 -2.349)
        (xy -6.938 -2.347)
        (xy -6.915 -2.345)
        (xy -6.893 -2.339)
        (xy -6.87 -2.334)
        (xy -6.848 -2.327)
        (xy -6.826 -2.319)
        (xy -6.805 -2.311)
        (xy -6.784 -2.301)
        (xy -6.763 -2.289)
        (xy -6.744 -2.277)
        (xy -6.723 -2.265)
        (xy -6.705 -2.25)
        (xy -6.688 -2.236)
        (xy -6.67 -2.22)
        (xy -6.654 -2.202)
        (xy -6.64 -2.185)
        (xy -6.625 -2.166)
        (xy -6.612 -2.146)
        (xy -6.6 -2.126)
        (xy -6.59 -2.107)
        (xy -6.579 -2.085)
        (xy -6.571 -2.064)
        (xy -6.563 -2.043)
        (xy -6.555 -2.019)
        (xy -6.55 -1.997)
        (xy -6.545 -1.975)
        (xy -6.542 -1.951)
        (xy -6.542 -1.927)
        (xy -6.54 -1.904)
        (xy -6.542 -1.881)
        (xy -6.542 -1.858)
        (xy -6.545 -1.834)
        (xy -6.55 -1.812)
        (xy -6.555 -1.789)
        (xy -6.563 -1.766)
        (xy -6.571 -1.745)
        (xy -6.579 -1.723)
        (xy -6.59 -1.703)
        (xy -6.6 -1.683)
        (xy -6.612 -1.662)
        (xy -6.625 -1.642)
        (xy -6.64 -1.624)
        (xy -6.654 -1.606)
        (xy -6.67 -1.59)
        (xy -6.688 -1.574)
        (xy -6.705 -1.558)
        (xy -6.723 -1.544)
        (xy -6.744 -1.531)
        (xy -6.763 -1.519)
        (xy -6.784 -1.508)
        (xy -6.805 -1.497)
        (xy -6.826 -1.489)
        (xy -6.848 -1.481)
        (xy -6.87 -1.475)
        (xy -6.893 -1.469)
        (xy -6.915 -1.465)
        (xy -6.938 -1.461)
        (xy -6.962 -1.461)
        (xy -6.986 -1.459)
        (xy -7.01 -1.461)
        (xy -7.034 -1.461)
        (xy -7.056 -1.465)
        (xy -7.079 -1.469)
        (xy -7.101 -1.475)
        (xy -7.124 -1.481)
        (xy -7.145 -1.489)
        (xy -7.167 -1.497)
        (xy -7.188 -1.507)
        (xy -7.209 -1.518)
        (xy -7.228 -1.531)
        (xy -7.247 -1.544)
        (xy -7.266 -1.558)
        (xy -7.284 -1.574)
        (xy -7.3 -1.59)
        (xy -7.316 -1.606)
        (xy -7.332 -1.624)
        (xy -7.345 -1.642)
        (xy -7.358 -1.661)
        (xy -7.372 -1.681)
        (xy -7.382 -1.701)
        (xy -7.393 -1.723)
        (xy -7.401 -1.745)
        (xy -7.409 -1.766)
        (xy -7.415 -1.788)
        (xy -7.42 -1.81)
        (xy -7.425 -1.834)
        (xy -7.428 -1.856)
        (xy -7.43 -1.88)
        (xy -7.43 -1.902)
        (xy -6.986 -1.902)
        (xy -6.986 -1.906)
        (xy -6.986 -1.907)
      )

      (stroke (width 0.001) (type solid)) (fill solid) (layer "B.Paste"))
    (fp_poly
      (pts
        (xy -6.986 -0.637)
        (xy -7.43 -0.636)
        (xy -7.43 -0.659)
        (xy -7.428 -0.683)
        (xy -7.425 -0.705)
        (xy -7.42 -0.728)
        (xy -7.415 -0.75)
        (xy -7.409 -0.773)
        (xy -7.401 -0.795)
        (xy -7.393 -0.816)
        (xy -7.382 -0.837)
        (xy -7.372 -0.857)
        (xy -7.358 -0.877)
        (xy -7.345 -0.897)
        (xy -7.332 -0.916)
        (xy -7.316 -0.933)
        (xy -7.3 -0.949)
        (xy -7.284 -0.965)
        (xy -7.266 -0.98)
        (xy -7.247 -0.994)
        (xy -7.228 -1.007)
        (xy -7.209 -1.02)
        (xy -7.188 -1.032)
        (xy -7.167 -1.042)
        (xy -7.145 -1.05)
        (xy -7.124 -1.058)
        (xy -7.101 -1.064)
        (xy -7.079 -1.07)
        (xy -7.056 -1.074)
        (xy -7.034 -1.078)
        (xy -7.01 -1.078)
        (xy -6.986 -1.08)
        (xy -6.962 -1.078)
        (xy -6.938 -1.078)
        (xy -6.915 -1.074)
        (xy -6.893 -1.07)
        (xy -6.87 -1.064)
        (xy -6.848 -1.058)
        (xy -6.826 -1.05)
        (xy -6.805 -1.042)
        (xy -6.784 -1.03)
        (xy -6.763 -1.019)
        (xy -6.744 -1.007)
        (xy -6.723 -0.994)
        (xy -6.705 -0.98)
        (xy -6.688 -0.965)
        (xy -6.67 -0.949)
        (xy -6.654 -0.933)
        (xy -6.64 -0.915)
        (xy -6.625 -0.897)
        (xy -6.612 -0.876)
        (xy -6.6 -0.856)
        (xy -6.59 -0.836)
        (xy -6.579 -0.815)
        (xy -6.571 -0.794)
        (xy -6.563 -0.773)
        (xy -6.555 -0.749)
        (xy -6.55 -0.727)
        (xy -6.545 -0.704)
        (xy -6.542 -0.682)
        (xy -6.542 -0.658)
        (xy -6.54 -0.634)
        (xy -6.542 -0.611)
        (xy -6.542 -0.587)
        (xy -6.545 -0.564)
        (xy -6.55 -0.542)
        (xy -6.555 -0.52)
        (xy -6.563 -0.496)
        (xy -6.571 -0.475)
        (xy -6.579 -0.454)
        (xy -6.59 -0.432)
        (xy -6.6 -0.412)
        (xy -6.612 -0.393)
        (xy -6.625 -0.372)
        (xy -6.64 -0.354)
        (xy -6.654 -0.337)
        (xy -6.67 -0.32)
        (xy -6.688 -0.303)
        (xy -6.705 -0.288)
        (xy -6.723 -0.275)
        (xy -6.744 -0.262)
        (xy -6.763 -0.249)
        (xy -6.784 -0.238)
        (xy -6.805 -0.228)
        (xy -6.826 -0.219)
        (xy -6.848 -0.211)
        (xy -6.87 -0.204)
        (xy -6.893 -0.2)
        (xy -6.915 -0.195)
        (xy -6.938 -0.192)
        (xy -6.962 -0.19)
        (xy -6.986 -0.189)
        (xy -7.01 -0.19)
        (xy -7.034 -0.192)
        (xy -7.056 -0.195)
        (xy -7.079 -0.2)
        (xy -7.101 -0.204)
        (xy -7.124 -0.211)
        (xy -7.145 -0.218)
        (xy -7.167 -0.228)
        (xy -7.188 -0.237)
        (xy -7.209 -0.248)
        (xy -7.228 -0.262)
        (xy -7.247 -0.275)
        (xy -7.266 -0.288)
        (xy -7.284 -0.303)
        (xy -7.3 -0.32)
        (xy -7.316 -0.337)
        (xy -7.332 -0.353)
        (xy -7.345 -0.372)
        (xy -7.358 -0.392)
        (xy -7.372 -0.411)
        (xy -7.382 -0.431)
        (xy -7.393 -0.453)
        (xy -7.401 -0.474)
        (xy -7.409 -0.496)
        (xy -7.415 -0.519)
        (xy -7.42 -0.541)
        (xy -7.425 -0.563)
        (xy -7.428 -0.586)
        (xy -7.43 -0.61)
        (xy -7.43 -0.631)
        (xy -6.986 -0.631)
        (xy -6.986 -0.636)
        (xy -6.986 -0.637)
      )

      (stroke (width 0.001) (type solid)) (fill solid) (layer "B.Paste"))
    (fp_poly
      (pts
        (xy -6.986 0.633)
        (xy -7.43 0.632)
        (xy -7.43 0.611)
        (xy -7.428 0.587)
        (xy -7.425 0.564)
        (xy -7.42 0.542)
        (xy -7.415 0.52)
        (xy -7.409 0.497)
        (xy -7.401 0.475)
        (xy -7.393 0.454)
        (xy -7.382 0.432)
        (xy -7.372 0.412)
        (xy -7.358 0.393)
        (xy -7.345 0.373)
        (xy -7.332 0.354)
        (xy -7.316 0.338)
        (xy -7.3 0.32)
        (xy -7.284 0.304)
        (xy -7.266 0.289)
        (xy -7.247 0.276)
        (xy -7.228 0.263)
        (xy -7.209 0.249)
        (xy -7.188 0.238)
        (xy -7.167 0.229)
        (xy -7.145 0.219)
        (xy -7.124 0.212)
        (xy -7.101 0.205)
        (xy -7.079 0.201)
        (xy -7.056 0.196)
        (xy -7.034 0.192)
        (xy -7.01 0.191)
        (xy -6.986 0.19)
        (xy -6.962 0.191)
        (xy -6.938 0.192)
        (xy -6.915 0.196)
        (xy -6.893 0.201)
        (xy -6.87 0.205)
        (xy -6.848 0.212)
        (xy -6.826 0.22)
        (xy -6.805 0.229)
        (xy -6.784 0.239)
        (xy -6.763 0.25)
        (xy -6.744 0.263)
        (xy -6.723 0.276)
        (xy -6.705 0.289)
        (xy -6.688 0.304)
        (xy -6.67 0.32)
        (xy -6.654 0.338)
        (xy -6.64 0.355)
        (xy -6.625 0.373)
        (xy -6.612 0.394)
        (xy -6.6 0.413)
        (xy -6.59 0.433)
        (xy -6.579 0.455)
        (xy -6.571 0.476)
        (xy -6.563 0.497)
        (xy -6.555 0.521)
        (xy -6.55 0.543)
        (xy -6.545 0.565)
        (xy -6.542 0.588)
        (xy -6.542 0.612)
        (xy -6.54 0.635)
        (xy -6.542 0.659)
        (xy -6.542 0.683)
        (xy -6.545 0.705)
        (xy -6.55 0.728)
        (xy -6.555 0.75)
        (xy -6.563 0.774)
        (xy -6.571 0.795)
        (xy -6.579 0.816)
        (xy -6.59 0.837)
        (xy -6.6 0.857)
        (xy -6.612 0.877)
        (xy -6.625 0.898)
        (xy -6.64 0.916)
        (xy -6.654 0.934)
        (xy -6.67 0.95)
        (xy -6.688 0.966)
        (xy -6.705 0.981)
        (xy -6.723 0.995)
        (xy -6.744 1.008)
        (xy -6.763 1.02)
        (xy -6.784 1.031)
        (xy -6.805 1.043)
        (xy -6.826 1.051)
        (xy -6.848 1.059)
        (xy -6.87 1.065)
        (xy -6.893 1.071)
        (xy -6.915 1.075)
        (xy -6.938 1.079)
        (xy -6.962 1.079)
        (xy -6.986 1.081)
        (xy -7.01 1.079)
        (xy -7.034 1.079)
        (xy -7.056 1.075)
        (xy -7.079 1.071)
        (xy -7.101 1.065)
        (xy -7.124 1.059)
        (xy -7.145 1.051)
        (xy -7.167 1.043)
        (xy -7.188 1.033)
        (xy -7.209 1.021)
        (xy -7.228 1.008)
        (xy -7.247 0.995)
        (xy -7.266 0.981)
        (xy -7.284 0.966)
        (xy -7.3 0.95)
        (xy -7.316 0.934)
        (xy -7.332 0.917)
        (xy -7.345 0.898)
        (xy -7.358 0.878)
        (xy -7.372 0.858)
        (xy -7.382 0.838)
        (xy -7.393 0.817)
        (xy -7.401 0.796)
        (xy -7.409 0.774)
        (xy -7.415 0.751)
        (xy -7.42 0.729)
        (xy -7.425 0.706)
        (xy -7.428 0.684)
        (xy -7.43 0.66)
        (xy -7.43 0.637)
        (xy -6.986 0.637)
        (xy -6.986 0.632)
        (xy -6.986 0.633)
      )

      (stroke (width 0.001) (type solid)) (fill solid) (layer "B.Paste"))
    (fp_poly
      (pts
        (xy -5.715 -4.447)
        (xy -6.161 -4.446)
        (xy -6.159 -4.469)
        (xy -6.159 -4.493)
        (xy -6.156 -4.515)
        (xy -6.151 -4.538)
        (xy -6.145 -4.56)
        (xy -6.138 -4.583)
        (xy -6.132 -4.605)
        (xy -6.122 -4.626)
        (xy -6.112 -4.647)
        (xy -6.101 -4.668)
        (xy -6.088 -4.687)
        (xy -6.076 -4.706)
        (xy -6.061 -4.725)
        (xy -6.047 -4.743)
        (xy -6.031 -4.759)
        (xy -6.013 -4.775)
        (xy -5.997 -4.791)
        (xy -5.978 -4.804)
        (xy -5.959 -4.817)
        (xy -5.938 -4.831)
        (xy -5.919 -4.841)
        (xy -5.898 -4.852)
        (xy -5.875 -4.86)
        (xy -5.853 -4.868)
        (xy -5.832 -4.874)
        (xy -5.81 -4.879)
        (xy -5.786 -4.884)
        (xy -5.763 -4.887)
        (xy -5.739 -4.889)
        (xy -5.715 -4.889)
        (xy -5.693 -4.889)
        (xy -5.669 -4.887)
        (xy -5.645 -4.884)
        (xy -5.622 -4.879)
        (xy -5.6 -4.874)
        (xy -5.577 -4.868)
        (xy -5.556 -4.86)
        (xy -5.534 -4.852)
        (xy -5.513 -4.841)
        (xy -5.492 -4.829)
        (xy -5.473 -4.817)
        (xy -5.454 -4.804)
        (xy -5.435 -4.791)
        (xy -5.417 -4.775)
        (xy -5.401 -4.759)
        (xy -5.385 -4.743)
        (xy -5.369 -4.724)
        (xy -5.356 -4.706)
        (xy -5.342 -4.687)
        (xy -5.33 -4.668)
        (xy -5.319 -4.647)
        (xy -5.308 -4.626)
        (xy -5.3 -4.603)
        (xy -5.292 -4.583)
        (xy -5.286 -4.559)
        (xy -5.281 -4.538)
        (xy -5.276 -4.514)
        (xy -5.273 -4.491)
        (xy -5.271 -4.467)
        (xy -5.27 -4.445)
        (xy -5.271 -4.421)
        (xy -5.273 -4.397)
        (xy -5.276 -4.374)
        (xy -5.281 -4.352)
        (xy -5.286 -4.329)
        (xy -5.292 -4.307)
        (xy -5.3 -4.285)
        (xy -5.308 -4.264)
        (xy -5.319 -4.243)
        (xy -5.33 -4.222)
        (xy -5.342 -4.203)
        (xy -5.356 -4.182)
        (xy -5.369 -4.164)
        (xy -5.385 -4.147)
        (xy -5.401 -4.129)
        (xy -5.417 -4.113)
        (xy -5.435 -4.099)
        (xy -5.454 -4.084)
        (xy -5.473 -4.071)
        (xy -5.492 -4.059)
        (xy -5.513 -4.049)
        (xy -5.534 -4.038)
        (xy -5.556 -4.03)
        (xy -5.577 -4.022)
        (xy -5.6 -4.014)
        (xy -5.622 -4.009)
        (xy -5.645 -4.004)
        (xy -5.669 -4.001)
        (xy -5.693 -4.001)
        (xy -5.715 -3.999)
        (xy -5.739 -4.001)
        (xy -5.763 -4.001)
        (xy -5.786 -4.004)
        (xy -5.81 -4.009)
        (xy -5.832 -4.014)
        (xy -5.853 -4.022)
        (xy -5.875 -4.028)
        (xy -5.898 -4.038)
        (xy -5.919 -4.047)
        (xy -5.938 -4.059)
        (xy -5.959 -4.071)
        (xy -5.978 -4.084)
        (xy -5.997 -4.099)
        (xy -6.013 -4.113)
        (xy -6.031 -4.129)
        (xy -6.047 -4.147)
        (xy -6.061 -4.163)
        (xy -6.076 -4.182)
        (xy -6.088 -4.201)
        (xy -6.101 -4.222)
        (xy -6.112 -4.241)
        (xy -6.122 -4.262)
        (xy -6.132 -4.285)
        (xy -6.138 -4.307)
        (xy -6.145 -4.328)
        (xy -6.151 -4.35)
        (xy -6.156 -4.373)
        (xy -6.159 -4.397)
        (xy -6.159 -4.421)
        (xy -6.161 -4.442)
        (xy -5.715 -4.442)
        (xy -5.715 -4.446)
        (xy -5.715 -4.447)
      )

      (stroke (width 0.001) (type solid)) (fill solid) (layer "B.Paste"))
    (fp_poly
      (pts
        (xy -5.715 -1.907)
        (xy -6.161 -1.906)
        (xy -6.159 -1.929)
        (xy -6.159 -1.953)
        (xy -6.156 -1.975)
        (xy -6.151 -1.999)
        (xy -6.145 -2.02)
        (xy -6.138 -2.043)
        (xy -6.132 -2.064)
        (xy -6.122 -2.087)
        (xy -6.112 -2.108)
        (xy -6.101 -2.128)
        (xy -6.088 -2.148)
        (xy -6.076 -2.166)
        (xy -6.061 -2.185)
        (xy -6.047 -2.202)
        (xy -6.031 -2.22)
        (xy -6.013 -2.236)
        (xy -5.997 -2.25)
        (xy -5.978 -2.265)
        (xy -5.959 -2.277)
        (xy -5.938 -2.29)
        (xy -5.919 -2.301)
        (xy -5.898 -2.311)
        (xy -5.875 -2.321)
        (xy -5.853 -2.327)
        (xy -5.832 -2.334)
        (xy -5.81 -2.339)
        (xy -5.786 -2.345)
        (xy -5.763 -2.347)
        (xy -5.739 -2.349)
        (xy -5.715 -2.35)
        (xy -5.693 -2.349)
        (xy -5.669 -2.347)
        (xy -5.645 -2.345)
        (xy -5.622 -2.339)
        (xy -5.6 -2.334)
        (xy -5.577 -2.327)
        (xy -5.556 -2.319)
        (xy -5.534 -2.311)
        (xy -5.513 -2.301)
        (xy -5.492 -2.289)
        (xy -5.473 -2.277)
        (xy -5.454 -2.265)
        (xy -5.435 -2.25)
        (xy -5.417 -2.236)
        (xy -5.401 -2.22)
        (xy -5.385 -2.202)
        (xy -5.369 -2.185)
        (xy -5.356 -2.166)
        (xy -5.342 -2.146)
        (xy -5.33 -2.126)
        (xy -5.319 -2.107)
        (xy -5.308 -2.085)
        (xy -5.3 -2.064)
        (xy -5.292 -2.043)
        (xy -5.286 -2.019)
        (xy -5.281 -1.997)
        (xy -5.276 -1.975)
        (xy -5.273 -1.951)
        (xy -5.271 -1.927)
        (xy -5.27 -1.904)
        (xy -5.271 -1.881)
        (xy -5.273 -1.858)
        (xy -5.276 -1.834)
        (xy -5.281 -1.812)
        (xy -5.286 -1.789)
        (xy -5.292 -1.766)
        (xy -5.3 -1.745)
        (xy -5.308 -1.723)
        (xy -5.319 -1.703)
        (xy -5.33 -1.683)
        (xy -5.342 -1.662)
        (xy -5.356 -1.642)
        (xy -5.369 -1.624)
        (xy -5.385 -1.606)
        (xy -5.401 -1.59)
        (xy -5.417 -1.574)
        (xy -5.435 -1.558)
        (xy -5.454 -1.544)
        (xy -5.473 -1.531)
        (xy -5.492 -1.519)
        (xy -5.513 -1.508)
        (xy -5.534 -1.497)
        (xy -5.556 -1.489)
        (xy -5.577 -1.481)
        (xy -5.6 -1.475)
        (xy -5.622 -1.469)
        (xy -5.645 -1.465)
        (xy -5.669 -1.461)
        (xy -5.693 -1.461)
        (xy -5.715 -1.459)
        (xy -5.739 -1.461)
        (xy -5.763 -1.461)
        (xy -5.786 -1.465)
        (xy -5.81 -1.469)
        (xy -5.832 -1.475)
        (xy -5.853 -1.481)
        (xy -5.875 -1.489)
        (xy -5.898 -1.497)
        (xy -5.919 -1.507)
        (xy -5.938 -1.518)
        (xy -5.959 -1.531)
        (xy -5.978 -1.544)
        (xy -5.997 -1.558)
        (xy -6.013 -1.574)
        (xy -6.031 -1.59)
        (xy -6.047 -1.606)
        (xy -6.061 -1.624)
        (xy -6.076 -1.642)
        (xy -6.088 -1.661)
        (xy -6.101 -1.681)
        (xy -6.112 -1.701)
        (xy -6.122 -1.723)
        (xy -6.132 -1.745)
        (xy -6.138 -1.766)
        (xy -6.145 -1.788)
        (xy -6.151 -1.81)
        (xy -6.156 -1.834)
        (xy -6.159 -1.856)
        (xy -6.159 -1.88)
        (xy -6.161 -1.902)
        (xy -5.715 -1.902)
        (xy -5.715 -1.906)
        (xy -5.715 -1.907)
      )

      (stroke (width 0.001) (type solid)) (fill solid) (layer "B.Paste"))
    (fp_poly
      (pts
        (xy -5.715 -0.637)
        (xy -6.161 -0.636)
        (xy -6.159 -0.659)
        (xy -6.159 -0.683)
        (xy -6.156 -0.705)
        (xy -6.151 -0.728)
        (xy -6.145 -0.75)
        (xy -6.138 -0.773)
        (xy -6.132 -0.795)
        (xy -6.122 -0.816)
        (xy -6.112 -0.837)
        (xy -6.101 -0.857)
        (xy -6.088 -0.877)
        (xy -6.076 -0.897)
        (xy -6.061 -0.916)
        (xy -6.047 -0.933)
        (xy -6.031 -0.949)
        (xy -6.013 -0.965)
        (xy -5.997 -0.98)
        (xy -5.978 -0.994)
        (xy -5.959 -1.007)
        (xy -5.938 -1.02)
        (xy -5.919 -1.032)
        (xy -5.898 -1.042)
        (xy -5.875 -1.05)
        (xy -5.853 -1.058)
        (xy -5.832 -1.064)
        (xy -5.81 -1.07)
        (xy -5.786 -1.074)
        (xy -5.763 -1.078)
        (xy -5.739 -1.078)
        (xy -5.715 -1.08)
        (xy -5.693 -1.078)
        (xy -5.669 -1.078)
        (xy -5.645 -1.074)
        (xy -5.622 -1.07)
        (xy -5.6 -1.064)
        (xy -5.577 -1.058)
        (xy -5.556 -1.05)
        (xy -5.534 -1.042)
        (xy -5.513 -1.03)
        (xy -5.492 -1.019)
        (xy -5.473 -1.007)
        (xy -5.454 -0.994)
        (xy -5.435 -0.98)
        (xy -5.417 -0.965)
        (xy -5.401 -0.949)
        (xy -5.385 -0.933)
        (xy -5.369 -0.915)
        (xy -5.356 -0.897)
        (xy -5.342 -0.876)
        (xy -5.33 -0.856)
        (xy -5.319 -0.836)
        (xy -5.308 -0.815)
        (xy -5.3 -0.794)
        (xy -5.292 -0.773)
        (xy -5.286 -0.749)
        (xy -5.281 -0.727)
        (xy -5.276 -0.704)
        (xy -5.273 -0.682)
        (xy -5.271 -0.658)
        (xy -5.27 -0.634)
        (xy -5.271 -0.611)
        (xy -5.273 -0.587)
        (xy -5.276 -0.564)
        (xy -5.281 -0.542)
        (xy -5.286 -0.52)
        (xy -5.292 -0.496)
        (xy -5.3 -0.475)
        (xy -5.308 -0.454)
        (xy -5.319 -0.432)
        (xy -5.33 -0.412)
        (xy -5.342 -0.393)
        (xy -5.356 -0.372)
        (xy -5.369 -0.354)
        (xy -5.385 -0.337)
        (xy -5.401 -0.32)
        (xy -5.417 -0.303)
        (xy -5.435 -0.288)
        (xy -5.454 -0.275)
        (xy -5.473 -0.262)
        (xy -5.492 -0.249)
        (xy -5.513 -0.238)
        (xy -5.534 -0.228)
        (xy -5.556 -0.219)
        (xy -5.577 -0.211)
        (xy -5.6 -0.204)
        (xy -5.622 -0.2)
        (xy -5.645 -0.195)
        (xy -5.669 -0.192)
        (xy -5.693 -0.19)
        (xy -5.715 -0.189)
        (xy -5.739 -0.19)
        (xy -5.763 -0.192)
        (xy -5.786 -0.195)
        (xy -5.81 -0.2)
        (xy -5.832 -0.204)
        (xy -5.853 -0.211)
        (xy -5.875 -0.218)
        (xy -5.898 -0.228)
        (xy -5.919 -0.237)
        (xy -5.938 -0.248)
        (xy -5.959 -0.262)
        (xy -5.978 -0.275)
        (xy -5.997 -0.288)
        (xy -6.013 -0.303)
        (xy -6.031 -0.32)
        (xy -6.047 -0.337)
        (xy -6.061 -0.353)
        (xy -6.076 -0.372)
        (xy -6.088 -0.392)
        (xy -6.101 -0.411)
        (xy -6.112 -0.431)
        (xy -6.122 -0.453)
        (xy -6.132 -0.474)
        (xy -6.138 -0.496)
        (xy -6.145 -0.519)
        (xy -6.151 -0.541)
        (xy -6.156 -0.563)
        (xy -6.159 -0.586)
        (xy -6.159 -0.61)
        (xy -6.161 -0.631)
        (xy -5.715 -0.631)
        (xy -5.715 -0.636)
        (xy -5.715 -0.637)
      )

      (stroke (width 0.001) (type solid)) (fill solid) (layer "B.Paste"))
    (fp_poly
      (pts
        (xy -5.715 0.633)
        (xy -6.161 0.632)
        (xy -6.159 0.611)
        (xy -6.159 0.587)
        (xy -6.156 0.564)
        (xy -6.151 0.542)
        (xy -6.145 0.52)
        (xy -6.138 0.497)
        (xy -6.132 0.475)
        (xy -6.122 0.454)
        (xy -6.112 0.432)
        (xy -6.101 0.412)
        (xy -6.088 0.393)
        (xy -6.076 0.373)
        (xy -6.061 0.354)
        (xy -6.047 0.338)
        (xy -6.031 0.32)
        (xy -6.013 0.304)
        (xy -5.997 0.289)
        (xy -5.978 0.276)
        (xy -5.959 0.263)
        (xy -5.938 0.249)
        (xy -5.919 0.238)
        (xy -5.898 0.229)
        (xy -5.875 0.219)
        (xy -5.853 0.212)
        (xy -5.832 0.205)
        (xy -5.81 0.201)
        (xy -5.786 0.196)
        (xy -5.763 0.192)
        (xy -5.739 0.191)
        (xy -5.715 0.19)
        (xy -5.693 0.191)
        (xy -5.669 0.192)
        (xy -5.645 0.196)
        (xy -5.622 0.201)
        (xy -5.6 0.205)
        (xy -5.577 0.212)
        (xy -5.556 0.22)
        (xy -5.534 0.229)
        (xy -5.513 0.239)
        (xy -5.492 0.25)
        (xy -5.473 0.263)
        (xy -5.454 0.276)
        (xy -5.435 0.289)
        (xy -5.417 0.304)
        (xy -5.401 0.32)
        (xy -5.385 0.338)
        (xy -5.369 0.355)
        (xy -5.356 0.373)
        (xy -5.342 0.394)
        (xy -5.33 0.413)
        (xy -5.319 0.433)
        (xy -5.308 0.455)
        (xy -5.3 0.476)
        (xy -5.292 0.497)
        (xy -5.286 0.521)
        (xy -5.281 0.543)
        (xy -5.276 0.565)
        (xy -5.273 0.588)
        (xy -5.271 0.612)
        (xy -5.27 0.635)
        (xy -5.271 0.659)
        (xy -5.273 0.683)
        (xy -5.276 0.705)
        (xy -5.281 0.728)
        (xy -5.286 0.75)
        (xy -5.292 0.774)
        (xy -5.3 0.795)
        (xy -5.308 0.816)
        (xy -5.319 0.837)
        (xy -5.33 0.857)
        (xy -5.342 0.877)
        (xy -5.356 0.898)
        (xy -5.369 0.916)
        (xy -5.385 0.934)
        (xy -5.401 0.95)
        (xy -5.417 0.966)
        (xy -5.435 0.981)
        (xy -5.454 0.995)
        (xy -5.473 1.008)
        (xy -5.492 1.02)
        (xy -5.513 1.031)
        (xy -5.534 1.043)
        (xy -5.556 1.051)
        (xy -5.577 1.059)
        (xy -5.6 1.065)
        (xy -5.622 1.071)
        (xy -5.645 1.075)
        (xy -5.669 1.079)
        (xy -5.693 1.079)
        (xy -5.715 1.081)
        (xy -5.739 1.079)
        (xy -5.763 1.079)
        (xy -5.786 1.075)
        (xy -5.81 1.071)
        (xy -5.832 1.065)
        (xy -5.853 1.059)
        (xy -5.875 1.051)
        (xy -5.898 1.043)
        (xy -5.919 1.033)
        (xy -5.938 1.021)
        (xy -5.959 1.008)
        (xy -5.978 0.995)
        (xy -5.997 0.981)
        (xy -6.013 0.966)
        (xy -6.031 0.95)
        (xy -6.047 0.934)
        (xy -6.061 0.917)
        (xy -6.076 0.898)
        (xy -6.088 0.878)
        (xy -6.101 0.858)
        (xy -6.112 0.838)
        (xy -6.122 0.817)
        (xy -6.132 0.796)
        (xy -6.138 0.774)
        (xy -6.145 0.751)
        (xy -6.151 0.729)
        (xy -6.156 0.706)
        (xy -6.159 0.684)
        (xy -6.159 0.66)
        (xy -6.161 0.637)
        (xy -5.715 0.637)
        (xy -5.715 0.632)
        (xy -5.715 0.633)
      )

      (stroke (width 0.001) (type solid)) (fill solid) (layer "B.Paste"))
    (fp_poly
      (pts
        (xy -4.446 -4.447)
        (xy -4.89 -4.446)
        (xy -4.89 -4.469)
        (xy -4.888 -4.493)
        (xy -4.885 -4.515)
        (xy -4.88 -4.538)
        (xy -4.875 -4.56)
        (xy -4.869 -4.583)
        (xy -4.861 -4.605)
        (xy -4.853 -4.626)
        (xy -4.842 -4.647)
        (xy -4.832 -4.668)
        (xy -4.818 -4.687)
        (xy -4.805 -4.706)
        (xy -4.792 -4.725)
        (xy -4.776 -4.743)
        (xy -4.76 -4.759)
        (xy -4.744 -4.775)
        (xy -4.726 -4.791)
        (xy -4.707 -4.804)
        (xy -4.688 -4.817)
        (xy -4.669 -4.831)
        (xy -4.648 -4.841)
        (xy -4.627 -4.852)
        (xy -4.606 -4.86)
        (xy -4.584 -4.868)
        (xy -4.561 -4.874)
        (xy -4.539 -4.879)
        (xy -4.516 -4.884)
        (xy -4.494 -4.887)
        (xy -4.47 -4.889)
        (xy -4.446 -4.889)
        (xy -4.422 -4.889)
        (xy -4.398 -4.887)
        (xy -4.375 -4.884)
        (xy -4.353 -4.879)
        (xy -4.33 -4.874)
        (xy -4.308 -4.868)
        (xy -4.286 -4.86)
        (xy -4.265 -4.852)
        (xy -4.244 -4.841)
        (xy -4.223 -4.829)
        (xy -4.204 -4.817)
        (xy -4.183 -4.804)
        (xy -4.165 -4.791)
        (xy -4.148 -4.775)
        (xy -4.13 -4.759)
        (xy -4.114 -4.743)
        (xy -4.1 -4.724)
        (xy -4.085 -4.706)
        (xy -4.072 -4.687)
        (xy -4.06 -4.668)
        (xy -4.05 -4.647)
        (xy -4.039 -4.626)
        (xy -4.031 -4.603)
        (xy -4.023 -4.583)
        (xy -4.015 -4.559)
        (xy -4.01 -4.538)
        (xy -4.005 -4.514)
        (xy -4.002 -4.491)
        (xy -4.002 -4.467)
        (xy -4 -4.445)
        (xy -4.002 -4.421)
        (xy -4.002 -4.397)
        (xy -4.005 -4.374)
        (xy -4.01 -4.352)
        (xy -4.015 -4.329)
        (xy -4.023 -4.307)
        (xy -4.031 -4.285)
        (xy -4.039 -4.264)
        (xy -4.05 -4.243)
        (xy -4.06 -4.222)
        (xy -4.072 -4.203)
        (xy -4.085 -4.182)
        (xy -4.1 -4.164)
        (xy -4.114 -4.147)
        (xy -4.13 -4.129)
        (xy -4.148 -4.113)
        (xy -4.165 -4.099)
        (xy -4.183 -4.084)
        (xy -4.204 -4.071)
        (xy -4.223 -4.059)
        (xy -4.244 -4.049)
        (xy -4.265 -4.038)
        (xy -4.286 -4.03)
        (xy -4.308 -4.022)
        (xy -4.33 -4.014)
        (xy -4.353 -4.009)
        (xy -4.375 -4.004)
        (xy -4.398 -4.001)
        (xy -4.422 -4.001)
        (xy -4.446 -3.999)
        (xy -4.47 -4.001)
        (xy -4.494 -4.001)
        (xy -4.516 -4.004)
        (xy -4.539 -4.009)
        (xy -4.561 -4.014)
        (xy -4.584 -4.022)
        (xy -4.606 -4.028)
        (xy -4.627 -4.038)
        (xy -4.648 -4.047)
        (xy -4.669 -4.059)
        (xy -4.688 -4.071)
        (xy -4.707 -4.084)
        (xy -4.726 -4.099)
        (xy -4.744 -4.113)
        (xy -4.76 -4.129)
        (xy -4.776 -4.147)
        (xy -4.792 -4.163)
        (xy -4.805 -4.182)
        (xy -4.818 -4.201)
        (xy -4.832 -4.222)
        (xy -4.842 -4.241)
        (xy -4.853 -4.262)
        (xy -4.861 -4.285)
        (xy -4.869 -4.307)
        (xy -4.875 -4.328)
        (xy -4.88 -4.35)
        (xy -4.885 -4.373)
        (xy -4.888 -4.397)
        (xy -4.89 -4.421)
        (xy -4.89 -4.442)
        (xy -4.446 -4.442)
        (xy -4.446 -4.446)
        (xy -4.446 -4.447)
      )

      (stroke (width 0.001) (type solid)) (fill solid) (layer "B.Paste"))
    (fp_poly
      (pts
        (xy -4.446 -1.907)
        (xy -4.89 -1.906)
        (xy -4.89 -1.929)
        (xy -4.888 -1.953)
        (xy -4.885 -1.975)
        (xy -4.88 -1.999)
        (xy -4.875 -2.02)
        (xy -4.869 -2.043)
        (xy -4.861 -2.064)
        (xy -4.853 -2.087)
        (xy -4.842 -2.108)
        (xy -4.832 -2.128)
        (xy -4.818 -2.148)
        (xy -4.805 -2.166)
        (xy -4.792 -2.185)
        (xy -4.776 -2.202)
        (xy -4.76 -2.22)
        (xy -4.744 -2.236)
        (xy -4.726 -2.25)
        (xy -4.707 -2.265)
        (xy -4.688 -2.277)
        (xy -4.669 -2.29)
        (xy -4.648 -2.301)
        (xy -4.627 -2.311)
        (xy -4.606 -2.321)
        (xy -4.584 -2.327)
        (xy -4.561 -2.334)
        (xy -4.539 -2.339)
        (xy -4.516 -2.345)
        (xy -4.494 -2.347)
        (xy -4.47 -2.349)
        (xy -4.446 -2.35)
        (xy -4.422 -2.349)
        (xy -4.398 -2.347)
        (xy -4.375 -2.345)
        (xy -4.353 -2.339)
        (xy -4.33 -2.334)
        (xy -4.308 -2.327)
        (xy -4.286 -2.319)
        (xy -4.265 -2.311)
        (xy -4.244 -2.301)
        (xy -4.223 -2.289)
        (xy -4.204 -2.277)
        (xy -4.183 -2.265)
        (xy -4.165 -2.25)
        (xy -4.148 -2.236)
        (xy -4.13 -2.22)
        (xy -4.114 -2.202)
        (xy -4.1 -2.185)
        (xy -4.085 -2.166)
        (xy -4.072 -2.146)
        (xy -4.06 -2.126)
        (xy -4.05 -2.107)
        (xy -4.039 -2.085)
        (xy -4.031 -2.064)
        (xy -4.023 -2.043)
        (xy -4.015 -2.019)
        (xy -4.01 -1.997)
        (xy -4.005 -1.975)
        (xy -4.002 -1.951)
        (xy -4.002 -1.927)
        (xy -4 -1.904)
        (xy -4.002 -1.881)
        (xy -4.002 -1.858)
        (xy -4.005 -1.834)
        (xy -4.01 -1.812)
        (xy -4.015 -1.789)
        (xy -4.023 -1.766)
        (xy -4.031 -1.745)
        (xy -4.039 -1.723)
        (xy -4.05 -1.703)
        (xy -4.06 -1.683)
        (xy -4.072 -1.662)
        (xy -4.085 -1.642)
        (xy -4.1 -1.624)
        (xy -4.114 -1.606)
        (xy -4.13 -1.59)
        (xy -4.148 -1.574)
        (xy -4.165 -1.558)
        (xy -4.183 -1.544)
        (xy -4.204 -1.531)
        (xy -4.223 -1.519)
        (xy -4.244 -1.508)
        (xy -4.265 -1.497)
        (xy -4.286 -1.489)
        (xy -4.308 -1.481)
        (xy -4.33 -1.475)
        (xy -4.353 -1.469)
        (xy -4.375 -1.465)
        (xy -4.398 -1.461)
        (xy -4.422 -1.461)
        (xy -4.446 -1.459)
        (xy -4.47 -1.461)
        (xy -4.494 -1.461)
        (xy -4.516 -1.465)
        (xy -4.539 -1.469)
        (xy -4.561 -1.475)
        (xy -4.584 -1.481)
        (xy -4.606 -1.489)
        (xy -4.627 -1.497)
        (xy -4.648 -1.507)
        (xy -4.669 -1.518)
        (xy -4.688 -1.531)
        (xy -4.707 -1.544)
        (xy -4.726 -1.558)
        (xy -4.744 -1.574)
        (xy -4.76 -1.59)
        (xy -4.776 -1.606)
        (xy -4.792 -1.624)
        (xy -4.805 -1.642)
        (xy -4.818 -1.661)
        (xy -4.832 -1.681)
        (xy -4.842 -1.701)
        (xy -4.853 -1.723)
        (xy -4.861 -1.745)
        (xy -4.869 -1.766)
        (xy -4.875 -1.788)
        (xy -4.88 -1.81)
        (xy -4.885 -1.834)
        (xy -4.888 -1.856)
        (xy -4.89 -1.88)
        (xy -4.89 -1.902)
        (xy -4.446 -1.902)
        (xy -4.446 -1.906)
        (xy -4.446 -1.907)
      )

      (stroke (width 0.001) (type solid)) (fill solid) (layer "B.Paste"))
    (fp_poly
      (pts
        (xy -4.446 -0.637)
        (xy -4.89 -0.636)
        (xy -4.89 -0.659)
        (xy -4.888 -0.683)
        (xy -4.885 -0.705)
        (xy -4.88 -0.728)
        (xy -4.875 -0.75)
        (xy -4.869 -0.773)
        (xy -4.861 -0.795)
        (xy -4.853 -0.816)
        (xy -4.842 -0.837)
        (xy -4.832 -0.857)
        (xy -4.818 -0.877)
        (xy -4.805 -0.897)
        (xy -4.792 -0.916)
        (xy -4.776 -0.933)
        (xy -4.76 -0.949)
        (xy -4.744 -0.965)
        (xy -4.726 -0.98)
        (xy -4.707 -0.994)
        (xy -4.688 -1.007)
        (xy -4.669 -1.02)
        (xy -4.648 -1.032)
        (xy -4.627 -1.042)
        (xy -4.606 -1.05)
        (xy -4.584 -1.058)
        (xy -4.561 -1.064)
        (xy -4.539 -1.07)
        (xy -4.516 -1.074)
        (xy -4.494 -1.078)
        (xy -4.47 -1.078)
        (xy -4.446 -1.08)
        (xy -4.422 -1.078)
        (xy -4.398 -1.078)
        (xy -4.375 -1.074)
        (xy -4.353 -1.07)
        (xy -4.33 -1.064)
        (xy -4.308 -1.058)
        (xy -4.286 -1.05)
        (xy -4.265 -1.042)
        (xy -4.244 -1.03)
        (xy -4.223 -1.019)
        (xy -4.204 -1.007)
        (xy -4.183 -0.994)
        (xy -4.165 -0.98)
        (xy -4.148 -0.965)
        (xy -4.13 -0.949)
        (xy -4.114 -0.933)
        (xy -4.1 -0.915)
        (xy -4.085 -0.897)
        (xy -4.072 -0.876)
        (xy -4.06 -0.856)
        (xy -4.05 -0.836)
        (xy -4.039 -0.815)
        (xy -4.031 -0.794)
        (xy -4.023 -0.773)
        (xy -4.015 -0.749)
        (xy -4.01 -0.727)
        (xy -4.005 -0.704)
        (xy -4.002 -0.682)
        (xy -4.002 -0.658)
        (xy -4 -0.634)
        (xy -4.002 -0.611)
        (xy -4.002 -0.587)
        (xy -4.005 -0.564)
        (xy -4.01 -0.542)
        (xy -4.015 -0.52)
        (xy -4.023 -0.496)
        (xy -4.031 -0.475)
        (xy -4.039 -0.454)
        (xy -4.05 -0.432)
        (xy -4.06 -0.412)
        (xy -4.072 -0.393)
        (xy -4.085 -0.372)
        (xy -4.1 -0.354)
        (xy -4.114 -0.337)
        (xy -4.13 -0.32)
        (xy -4.148 -0.303)
        (xy -4.165 -0.288)
        (xy -4.183 -0.275)
        (xy -4.204 -0.262)
        (xy -4.223 -0.249)
        (xy -4.244 -0.238)
        (xy -4.265 -0.228)
        (xy -4.286 -0.219)
        (xy -4.308 -0.211)
        (xy -4.33 -0.204)
        (xy -4.353 -0.2)
        (xy -4.375 -0.195)
        (xy -4.398 -0.192)
        (xy -4.422 -0.19)
        (xy -4.446 -0.189)
        (xy -4.47 -0.19)
        (xy -4.494 -0.192)
        (xy -4.516 -0.195)
        (xy -4.539 -0.2)
        (xy -4.561 -0.204)
        (xy -4.584 -0.211)
        (xy -4.606 -0.218)
        (xy -4.627 -0.228)
        (xy -4.648 -0.237)
        (xy -4.669 -0.248)
        (xy -4.688 -0.262)
        (xy -4.707 -0.275)
        (xy -4.726 -0.288)
        (xy -4.744 -0.303)
        (xy -4.76 -0.32)
        (xy -4.776 -0.337)
        (xy -4.792 -0.353)
        (xy -4.805 -0.372)
        (xy -4.818 -0.392)
        (xy -4.832 -0.411)
        (xy -4.842 -0.431)
        (xy -4.853 -0.453)
        (xy -4.861 -0.474)
        (xy -4.869 -0.496)
        (xy -4.875 -0.519)
        (xy -4.88 -0.541)
        (xy -4.885 -0.563)
        (xy -4.888 -0.586)
        (xy -4.89 -0.61)
        (xy -4.89 -0.631)
        (xy -4.446 -0.631)
        (xy -4.446 -0.636)
        (xy -4.446 -0.637)
      )

      (stroke (width 0.001) (type solid)) (fill solid) (layer "B.Paste"))
    (fp_poly
      (pts
        (xy -4.446 0.633)
        (xy -4.89 0.632)
        (xy -4.89 0.611)
        (xy -4.888 0.587)
        (xy -4.885 0.564)
        (xy -4.88 0.542)
        (xy -4.875 0.52)
        (xy -4.869 0.497)
        (xy -4.861 0.475)
        (xy -4.853 0.454)
        (xy -4.842 0.432)
        (xy -4.832 0.412)
        (xy -4.818 0.393)
        (xy -4.805 0.373)
        (xy -4.792 0.354)
        (xy -4.776 0.338)
        (xy -4.76 0.32)
        (xy -4.744 0.304)
        (xy -4.726 0.289)
        (xy -4.707 0.276)
        (xy -4.688 0.263)
        (xy -4.669 0.249)
        (xy -4.648 0.238)
        (xy -4.627 0.229)
        (xy -4.606 0.219)
        (xy -4.584 0.212)
        (xy -4.561 0.205)
        (xy -4.539 0.201)
        (xy -4.516 0.196)
        (xy -4.494 0.192)
        (xy -4.47 0.191)
        (xy -4.446 0.19)
        (xy -4.422 0.191)
        (xy -4.398 0.192)
        (xy -4.375 0.196)
        (xy -4.353 0.201)
        (xy -4.33 0.205)
        (xy -4.308 0.212)
        (xy -4.286 0.22)
        (xy -4.265 0.229)
        (xy -4.244 0.239)
        (xy -4.223 0.25)
        (xy -4.204 0.263)
        (xy -4.183 0.276)
        (xy -4.165 0.289)
        (xy -4.148 0.304)
        (xy -4.13 0.32)
        (xy -4.114 0.338)
        (xy -4.1 0.355)
        (xy -4.085 0.373)
        (xy -4.072 0.394)
        (xy -4.06 0.413)
        (xy -4.05 0.433)
        (xy -4.039 0.455)
        (xy -4.031 0.476)
        (xy -4.023 0.497)
        (xy -4.015 0.521)
        (xy -4.01 0.543)
        (xy -4.005 0.565)
        (xy -4.002 0.588)
        (xy -4.002 0.612)
        (xy -4 0.635)
        (xy -4.002 0.659)
        (xy -4.002 0.683)
        (xy -4.005 0.705)
        (xy -4.01 0.728)
        (xy -4.015 0.75)
        (xy -4.023 0.774)
        (xy -4.031 0.795)
        (xy -4.039 0.816)
        (xy -4.05 0.837)
        (xy -4.06 0.857)
        (xy -4.072 0.877)
        (xy -4.085 0.898)
        (xy -4.1 0.916)
        (xy -4.114 0.934)
        (xy -4.13 0.95)
        (xy -4.148 0.966)
        (xy -4.165 0.981)
        (xy -4.183 0.995)
        (xy -4.204 1.008)
        (xy -4.223 1.02)
        (xy -4.244 1.031)
        (xy -4.265 1.043)
        (xy -4.286 1.051)
        (xy -4.308 1.059)
        (xy -4.33 1.065)
        (xy -4.353 1.071)
        (xy -4.375 1.075)
        (xy -4.398 1.079)
        (xy -4.422 1.079)
        (xy -4.446 1.081)
        (xy -4.47 1.079)
        (xy -4.494 1.079)
        (xy -4.516 1.075)
        (xy -4.539 1.071)
        (xy -4.561 1.065)
        (xy -4.584 1.059)
        (xy -4.606 1.051)
        (xy -4.627 1.043)
        (xy -4.648 1.033)
        (xy -4.669 1.021)
        (xy -4.688 1.008)
        (xy -4.707 0.995)
        (xy -4.726 0.981)
        (xy -4.744 0.966)
        (xy -4.76 0.95)
        (xy -4.776 0.934)
        (xy -4.792 0.917)
        (xy -4.805 0.898)
        (xy -4.818 0.878)
        (xy -4.832 0.858)
        (xy -4.842 0.838)
        (xy -4.853 0.817)
        (xy -4.861 0.796)
        (xy -4.869 0.774)
        (xy -4.875 0.751)
        (xy -4.88 0.729)
        (xy -4.885 0.706)
        (xy -4.888 0.684)
        (xy -4.89 0.66)
        (xy -4.89 0.637)
        (xy -4.446 0.637)
        (xy -4.446 0.632)
        (xy -4.446 0.633)
      )

      (stroke (width 0.001) (type solid)) (fill solid) (layer "B.Paste"))
    (fp_poly
      (pts
        (xy -3.175 -4.447)
        (xy -3.621 -4.446)
        (xy -3.62 -4.469)
        (xy -3.618 -4.493)
        (xy -3.616 -4.515)
        (xy -3.61 -4.538)
        (xy -3.605 -4.56)
        (xy -3.598 -4.583)
        (xy -3.592 -4.605)
        (xy -3.582 -4.626)
        (xy -3.572 -4.647)
        (xy -3.561 -4.668)
        (xy -3.548 -4.687)
        (xy -3.536 -4.706)
        (xy -3.521 -4.725)
        (xy -3.506 -4.743)
        (xy -3.491 -4.759)
        (xy -3.473 -4.775)
        (xy -3.456 -4.791)
        (xy -3.437 -4.804)
        (xy -3.419 -4.817)
        (xy -3.399 -4.831)
        (xy -3.379 -4.841)
        (xy -3.358 -4.852)
        (xy -3.335 -4.86)
        (xy -3.314 -4.868)
        (xy -3.291 -4.874)
        (xy -3.27 -4.879)
        (xy -3.246 -4.884)
        (xy -3.223 -4.887)
        (xy -3.199 -4.889)
        (xy -3.175 -4.889)
        (xy -3.153 -4.889)
        (xy -3.129 -4.887)
        (xy -3.105 -4.884)
        (xy -3.082 -4.879)
        (xy -3.06 -4.874)
        (xy -3.037 -4.868)
        (xy -3.016 -4.86)
        (xy -2.995 -4.852)
        (xy -2.973 -4.841)
        (xy -2.952 -4.829)
        (xy -2.933 -4.817)
        (xy -2.913 -4.804)
        (xy -2.895 -4.791)
        (xy -2.877 -4.775)
        (xy -2.86 -4.759)
        (xy -2.844 -4.743)
        (xy -2.83 -4.724)
        (xy -2.815 -4.706)
        (xy -2.802 -4.687)
        (xy -2.79 -4.668)
        (xy -2.779 -4.647)
        (xy -2.768 -4.626)
        (xy -2.76 -4.603)
        (xy -2.752 -4.583)
        (xy -2.746 -4.559)
        (xy -2.741 -4.538)
        (xy -2.735 -4.514)
        (xy -2.733 -4.491)
        (xy -2.731 -4.467)
        (xy -2.73 -4.445)
        (xy -2.731 -4.421)
        (xy -2.733 -4.397)
        (xy -2.735 -4.374)
        (xy -2.741 -4.352)
        (xy -2.746 -4.329)
        (xy -2.752 -4.307)
        (xy -2.76 -4.285)
        (xy -2.768 -4.264)
        (xy -2.779 -4.243)
        (xy -2.79 -4.222)
        (xy -2.802 -4.203)
        (xy -2.815 -4.182)
        (xy -2.83 -4.164)
        (xy -2.844 -4.147)
        (xy -2.86 -4.129)
        (xy -2.877 -4.113)
        (xy -2.895 -4.099)
        (xy -2.913 -4.084)
        (xy -2.933 -4.071)
        (xy -2.952 -4.059)
        (xy -2.973 -4.049)
        (xy -2.995 -4.038)
        (xy -3.016 -4.03)
        (xy -3.037 -4.022)
        (xy -3.06 -4.014)
        (xy -3.082 -4.009)
        (xy -3.105 -4.004)
        (xy -3.129 -4.001)
        (xy -3.153 -4.001)
        (xy -3.175 -3.999)
        (xy -3.199 -4.001)
        (xy -3.223 -4.001)
        (xy -3.246 -4.004)
        (xy -3.27 -4.009)
        (xy -3.291 -4.014)
        (xy -3.314 -4.022)
        (xy -3.335 -4.028)
        (xy -3.358 -4.038)
        (xy -3.379 -4.047)
        (xy -3.399 -4.059)
        (xy -3.419 -4.071)
        (xy -3.437 -4.084)
        (xy -3.456 -4.099)
        (xy -3.473 -4.113)
        (xy -3.491 -4.129)
        (xy -3.506 -4.147)
        (xy -3.521 -4.163)
        (xy -3.536 -4.182)
        (xy -3.548 -4.201)
        (xy -3.561 -4.222)
        (xy -3.572 -4.241)
        (xy -3.582 -4.262)
        (xy -3.592 -4.285)
        (xy -3.598 -4.307)
        (xy -3.605 -4.328)
        (xy -3.61 -4.35)
        (xy -3.616 -4.373)
        (xy -3.618 -4.397)
        (xy -3.62 -4.421)
        (xy -3.621 -4.442)
        (xy -3.175 -4.442)
        (xy -3.175 -4.446)
        (xy -3.175 -4.447)
      )

      (stroke (width 0.001) (type solid)) (fill solid) (layer "B.Paste"))
    (fp_poly
      (pts
        (xy -3.175 -1.907)
        (xy -3.621 -1.906)
        (xy -3.62 -1.929)
        (xy -3.618 -1.953)
        (xy -3.616 -1.975)
        (xy -3.61 -1.999)
        (xy -3.605 -2.02)
        (xy -3.598 -2.043)
        (xy -3.592 -2.064)
        (xy -3.582 -2.087)
        (xy -3.572 -2.108)
        (xy -3.561 -2.128)
        (xy -3.548 -2.148)
        (xy -3.536 -2.166)
        (xy -3.521 -2.185)
        (xy -3.506 -2.202)
        (xy -3.491 -2.22)
        (xy -3.473 -2.236)
        (xy -3.456 -2.25)
        (xy -3.437 -2.265)
        (xy -3.419 -2.277)
        (xy -3.399 -2.29)
        (xy -3.379 -2.301)
        (xy -3.358 -2.311)
        (xy -3.335 -2.321)
        (xy -3.314 -2.327)
        (xy -3.291 -2.334)
        (xy -3.27 -2.339)
        (xy -3.246 -2.345)
        (xy -3.223 -2.347)
        (xy -3.199 -2.349)
        (xy -3.175 -2.35)
        (xy -3.153 -2.349)
        (xy -3.129 -2.347)
        (xy -3.105 -2.345)
        (xy -3.082 -2.339)
        (xy -3.06 -2.334)
        (xy -3.037 -2.327)
        (xy -3.016 -2.319)
        (xy -2.995 -2.311)
        (xy -2.973 -2.301)
        (xy -2.952 -2.289)
        (xy -2.933 -2.277)
        (xy -2.913 -2.265)
        (xy -2.895 -2.25)
        (xy -2.877 -2.236)
        (xy -2.86 -2.22)
        (xy -2.844 -2.202)
        (xy -2.83 -2.185)
        (xy -2.815 -2.166)
        (xy -2.802 -2.146)
        (xy -2.79 -2.126)
        (xy -2.779 -2.107)
        (xy -2.768 -2.085)
        (xy -2.76 -2.064)
        (xy -2.752 -2.043)
        (xy -2.746 -2.019)
        (xy -2.741 -1.997)
        (xy -2.735 -1.975)
        (xy -2.733 -1.951)
        (xy -2.731 -1.927)
        (xy -2.73 -1.904)
        (xy -2.731 -1.881)
        (xy -2.733 -1.858)
        (xy -2.735 -1.834)
        (xy -2.741 -1.812)
        (xy -2.746 -1.789)
        (xy -2.752 -1.766)
        (xy -2.76 -1.745)
        (xy -2.768 -1.723)
        (xy -2.779 -1.703)
        (xy -2.79 -1.683)
        (xy -2.802 -1.662)
        (xy -2.815 -1.642)
        (xy -2.83 -1.624)
        (xy -2.844 -1.606)
        (xy -2.86 -1.59)
        (xy -2.877 -1.574)
        (xy -2.895 -1.558)
        (xy -2.913 -1.544)
        (xy -2.933 -1.531)
        (xy -2.952 -1.519)
        (xy -2.973 -1.508)
        (xy -2.995 -1.497)
        (xy -3.016 -1.489)
        (xy -3.037 -1.481)
        (xy -3.06 -1.475)
        (xy -3.082 -1.469)
        (xy -3.105 -1.465)
        (xy -3.129 -1.461)
        (xy -3.153 -1.461)
        (xy -3.175 -1.459)
        (xy -3.199 -1.461)
        (xy -3.223 -1.461)
        (xy -3.246 -1.465)
        (xy -3.27 -1.469)
        (xy -3.291 -1.475)
        (xy -3.314 -1.481)
        (xy -3.335 -1.489)
        (xy -3.358 -1.497)
        (xy -3.379 -1.507)
        (xy -3.399 -1.518)
        (xy -3.419 -1.531)
        (xy -3.437 -1.544)
        (xy -3.456 -1.558)
        (xy -3.473 -1.574)
        (xy -3.491 -1.59)
        (xy -3.506 -1.606)
        (xy -3.521 -1.624)
        (xy -3.536 -1.642)
        (xy -3.548 -1.661)
        (xy -3.561 -1.681)
        (xy -3.572 -1.701)
        (xy -3.582 -1.723)
        (xy -3.592 -1.745)
        (xy -3.598 -1.766)
        (xy -3.605 -1.788)
        (xy -3.61 -1.81)
        (xy -3.616 -1.834)
        (xy -3.618 -1.856)
        (xy -3.62 -1.88)
        (xy -3.621 -1.902)
        (xy -3.175 -1.902)
        (xy -3.175 -1.906)
        (xy -3.175 -1.907)
      )

      (stroke (width 0.001) (type solid)) (fill solid) (layer "B.Paste"))
    (fp_poly
      (pts
        (xy -3.175 -0.637)
        (xy -3.621 -0.636)
        (xy -3.62 -0.659)
        (xy -3.618 -0.683)
        (xy -3.616 -0.705)
        (xy -3.61 -0.728)
        (xy -3.605 -0.75)
        (xy -3.598 -0.773)
        (xy -3.592 -0.795)
        (xy -3.582 -0.816)
        (xy -3.572 -0.837)
        (xy -3.561 -0.857)
        (xy -3.548 -0.877)
        (xy -3.536 -0.897)
        (xy -3.521 -0.916)
        (xy -3.506 -0.933)
        (xy -3.491 -0.949)
        (xy -3.473 -0.965)
        (xy -3.456 -0.98)
        (xy -3.437 -0.994)
        (xy -3.419 -1.007)
        (xy -3.399 -1.02)
        (xy -3.379 -1.032)
        (xy -3.358 -1.042)
        (xy -3.335 -1.05)
        (xy -3.314 -1.058)
        (xy -3.291 -1.064)
        (xy -3.27 -1.07)
        (xy -3.246 -1.074)
        (xy -3.223 -1.078)
        (xy -3.199 -1.078)
        (xy -3.175 -1.08)
        (xy -3.153 -1.078)
        (xy -3.129 -1.078)
        (xy -3.105 -1.074)
        (xy -3.082 -1.07)
        (xy -3.06 -1.064)
        (xy -3.037 -1.058)
        (xy -3.016 -1.05)
        (xy -2.995 -1.042)
        (xy -2.973 -1.03)
        (xy -2.952 -1.019)
        (xy -2.933 -1.007)
        (xy -2.913 -0.994)
        (xy -2.895 -0.98)
        (xy -2.877 -0.965)
        (xy -2.86 -0.949)
        (xy -2.844 -0.933)
        (xy -2.83 -0.915)
        (xy -2.815 -0.897)
        (xy -2.802 -0.876)
        (xy -2.79 -0.857)
        (xy -2.779 -0.836)
        (xy -2.768 -0.815)
        (xy -2.76 -0.794)
        (xy -2.752 -0.773)
        (xy -2.746 -0.749)
        (xy -2.741 -0.727)
        (xy -2.735 -0.704)
        (xy -2.733 -0.682)
        (xy -2.731 -0.658)
        (xy -2.73 -0.634)
        (xy -2.731 -0.611)
        (xy -2.733 -0.587)
        (xy -2.735 -0.564)
        (xy -2.741 -0.542)
        (xy -2.746 -0.52)
        (xy -2.752 -0.496)
        (xy -2.76 -0.475)
        (xy -2.768 -0.454)
        (xy -2.779 -0.432)
        (xy -2.79 -0.411)
        (xy -2.802 -0.393)
        (xy -2.815 -0.372)
        (xy -2.83 -0.354)
        (xy -2.844 -0.337)
        (xy -2.86 -0.32)
        (xy -2.877 -0.303)
        (xy -2.895 -0.288)
        (xy -2.913 -0.275)
        (xy -2.933 -0.262)
        (xy -2.952 -0.249)
        (xy -2.973 -0.238)
        (xy -2.995 -0.228)
        (xy -3.016 -0.219)
        (xy -3.037 -0.211)
        (xy -3.06 -0.204)
        (xy -3.082 -0.2)
        (xy -3.105 -0.195)
        (xy -3.129 -0.192)
        (xy -3.153 -0.19)
        (xy -3.175 -0.189)
        (xy -3.199 -0.19)
        (xy -3.223 -0.192)
        (xy -3.246 -0.195)
        (xy -3.27 -0.2)
        (xy -3.291 -0.204)
        (xy -3.314 -0.211)
        (xy -3.335 -0.218)
        (xy -3.358 -0.228)
        (xy -3.379 -0.237)
        (xy -3.399 -0.248)
        (xy -3.419 -0.262)
        (xy -3.437 -0.275)
        (xy -3.456 -0.288)
        (xy -3.473 -0.303)
        (xy -3.491 -0.32)
        (xy -3.506 -0.337)
        (xy -3.521 -0.353)
        (xy -3.536 -0.372)
        (xy -3.548 -0.392)
        (xy -3.561 -0.411)
        (xy -3.572 -0.431)
        (xy -3.582 -0.453)
        (xy -3.592 -0.474)
        (xy -3.598 -0.496)
        (xy -3.605 -0.519)
        (xy -3.61 -0.541)
        (xy -3.616 -0.563)
        (xy -3.618 -0.586)
        (xy -3.62 -0.61)
        (xy -3.621 -0.631)
        (xy -3.175 -0.631)
        (xy -3.175 -0.636)
        (xy -3.175 -0.637)
      )

      (stroke (width 0.001) (type solid)) (fill solid) (layer "B.Paste"))
    (fp_poly
      (pts
        (xy -3.175 0.633)
        (xy -3.621 0.632)
        (xy -3.62 0.611)
        (xy -3.618 0.587)
        (xy -3.616 0.564)
        (xy -3.61 0.542)
        (xy -3.605 0.52)
        (xy -3.598 0.497)
        (xy -3.592 0.475)
        (xy -3.582 0.454)
        (xy -3.572 0.432)
        (xy -3.561 0.412)
        (xy -3.548 0.393)
        (xy -3.536 0.373)
        (xy -3.521 0.354)
        (xy -3.506 0.338)
        (xy -3.491 0.32)
        (xy -3.473 0.304)
        (xy -3.456 0.289)
        (xy -3.437 0.276)
        (xy -3.419 0.263)
        (xy -3.399 0.249)
        (xy -3.379 0.238)
        (xy -3.358 0.229)
        (xy -3.335 0.219)
        (xy -3.314 0.212)
        (xy -3.291 0.205)
        (xy -3.27 0.201)
        (xy -3.246 0.196)
        (xy -3.223 0.192)
        (xy -3.199 0.191)
        (xy -3.175 0.19)
        (xy -3.153 0.191)
        (xy -3.129 0.192)
        (xy -3.105 0.196)
        (xy -3.082 0.201)
        (xy -3.06 0.205)
        (xy -3.037 0.212)
        (xy -3.016 0.22)
        (xy -2.995 0.229)
        (xy -2.973 0.239)
        (xy -2.952 0.25)
        (xy -2.933 0.263)
        (xy -2.913 0.276)
        (xy -2.895 0.289)
        (xy -2.877 0.304)
        (xy -2.86 0.32)
        (xy -2.844 0.338)
        (xy -2.83 0.355)
        (xy -2.815 0.373)
        (xy -2.802 0.394)
        (xy -2.79 0.412)
        (xy -2.779 0.433)
        (xy -2.768 0.455)
        (xy -2.76 0.476)
        (xy -2.752 0.497)
        (xy -2.746 0.521)
        (xy -2.741 0.543)
        (xy -2.735 0.565)
        (xy -2.733 0.588)
        (xy -2.731 0.612)
        (xy -2.73 0.635)
        (xy -2.731 0.659)
        (xy -2.733 0.683)
        (xy -2.735 0.705)
        (xy -2.741 0.728)
        (xy -2.746 0.75)
        (xy -2.752 0.774)
        (xy -2.76 0.795)
        (xy -2.768 0.816)
        (xy -2.779 0.837)
        (xy -2.79 0.858)
        (xy -2.802 0.877)
        (xy -2.815 0.898)
        (xy -2.83 0.916)
        (xy -2.844 0.934)
        (xy -2.86 0.95)
        (xy -2.877 0.966)
        (xy -2.895 0.981)
        (xy -2.913 0.995)
        (xy -2.933 1.008)
        (xy -2.952 1.02)
        (xy -2.973 1.031)
        (xy -2.995 1.043)
        (xy -3.016 1.051)
        (xy -3.037 1.059)
        (xy -3.06 1.065)
        (xy -3.082 1.071)
        (xy -3.105 1.075)
        (xy -3.129 1.079)
        (xy -3.153 1.079)
        (xy -3.175 1.081)
        (xy -3.199 1.079)
        (xy -3.223 1.079)
        (xy -3.246 1.075)
        (xy -3.27 1.071)
        (xy -3.291 1.065)
        (xy -3.314 1.059)
        (xy -3.335 1.051)
        (xy -3.358 1.043)
        (xy -3.379 1.033)
        (xy -3.399 1.021)
        (xy -3.419 1.008)
        (xy -3.437 0.995)
        (xy -3.456 0.981)
        (xy -3.473 0.966)
        (xy -3.491 0.95)
        (xy -3.506 0.934)
        (xy -3.521 0.917)
        (xy -3.536 0.898)
        (xy -3.548 0.878)
        (xy -3.561 0.858)
        (xy -3.572 0.838)
        (xy -3.582 0.817)
        (xy -3.592 0.796)
        (xy -3.598 0.774)
        (xy -3.605 0.751)
        (xy -3.61 0.729)
        (xy -3.616 0.706)
        (xy -3.618 0.684)
        (xy -3.62 0.66)
        (xy -3.621 0.637)
        (xy -3.175 0.637)
        (xy -3.175 0.632)
        (xy -3.175 0.633)
      )

      (stroke (width 0.001) (type solid)) (fill solid) (layer "B.Paste"))
    (fp_poly
      (pts
        (xy -1.905 -4.447)
        (xy -2.351 -4.446)
        (xy -2.35 -4.469)
        (xy -2.348 -4.493)
        (xy -2.346 -4.515)
        (xy -2.34 -4.538)
        (xy -2.335 -4.56)
        (xy -2.328 -4.583)
        (xy -2.322 -4.605)
        (xy -2.312 -4.626)
        (xy -2.302 -4.647)
        (xy -2.291 -4.668)
        (xy -2.278 -4.687)
        (xy -2.266 -4.706)
        (xy -2.251 -4.725)
        (xy -2.237 -4.743)
        (xy -2.221 -4.759)
        (xy -2.203 -4.775)
        (xy -2.186 -4.791)
        (xy -2.167 -4.804)
        (xy -2.149 -4.817)
        (xy -2.129 -4.831)
        (xy -2.109 -4.841)
        (xy -2.088 -4.852)
        (xy -2.065 -4.86)
        (xy -2.044 -4.868)
        (xy -2.021 -4.874)
        (xy -2 -4.879)
        (xy -1.976 -4.884)
        (xy -1.954 -4.887)
        (xy -1.93 -4.889)
        (xy -1.905 -4.889)
        (xy -1.882 -4.889)
        (xy -1.859 -4.887)
        (xy -1.835 -4.884)
        (xy -1.813 -4.879)
        (xy -1.79 -4.874)
        (xy -1.767 -4.868)
        (xy -1.746 -4.86)
        (xy -1.724 -4.852)
        (xy -1.704 -4.841)
        (xy -1.682 -4.829)
        (xy -1.663 -4.817)
        (xy -1.643 -4.804)
        (xy -1.625 -4.791)
        (xy -1.607 -4.775)
        (xy -1.591 -4.759)
        (xy -1.575 -4.743)
        (xy -1.559 -4.724)
        (xy -1.545 -4.706)
        (xy -1.532 -4.687)
        (xy -1.52 -4.668)
        (xy -1.509 -4.647)
        (xy -1.498 -4.626)
        (xy -1.49 -4.603)
        (xy -1.482 -4.583)
        (xy -1.476 -4.559)
        (xy -1.47 -4.538)
        (xy -1.466 -4.514)
        (xy -1.462 -4.491)
        (xy -1.462 -4.467)
        (xy -1.46 -4.445)
        (xy -1.462 -4.421)
        (xy -1.462 -4.397)
        (xy -1.466 -4.374)
        (xy -1.47 -4.352)
        (xy -1.476 -4.329)
        (xy -1.482 -4.307)
        (xy -1.49 -4.285)
        (xy -1.498 -4.264)
        (xy -1.509 -4.243)
        (xy -1.52 -4.222)
        (xy -1.532 -4.203)
        (xy -1.545 -4.182)
        (xy -1.559 -4.164)
        (xy -1.575 -4.147)
        (xy -1.591 -4.129)
        (xy -1.607 -4.113)
        (xy -1.625 -4.099)
        (xy -1.643 -4.084)
        (xy -1.663 -4.071)
        (xy -1.684 -4.059)
        (xy -1.704 -4.049)
        (xy -1.724 -4.038)
        (xy -1.746 -4.03)
        (xy -1.767 -4.022)
        (xy -1.79 -4.014)
        (xy -1.813 -4.009)
        (xy -1.835 -4.004)
        (xy -1.859 -4.001)
        (xy -1.882 -4.001)
        (xy -1.905 -3.999)
        (xy -1.93 -4.001)
        (xy -1.954 -4.001)
        (xy -1.976 -4.004)
        (xy -2 -4.009)
        (xy -2.021 -4.014)
        (xy -2.044 -4.022)
        (xy -2.065 -4.028)
        (xy -2.088 -4.038)
        (xy -2.109 -4.047)
        (xy -2.129 -4.059)
        (xy -2.149 -4.071)
        (xy -2.167 -4.084)
        (xy -2.186 -4.099)
        (xy -2.203 -4.113)
        (xy -2.221 -4.129)
        (xy -2.237 -4.147)
        (xy -2.251 -4.163)
        (xy -2.266 -4.182)
        (xy -2.278 -4.201)
        (xy -2.291 -4.222)
        (xy -2.302 -4.241)
        (xy -2.312 -4.262)
        (xy -2.322 -4.285)
        (xy -2.328 -4.307)
        (xy -2.335 -4.328)
        (xy -2.34 -4.35)
        (xy -2.346 -4.373)
        (xy -2.348 -4.397)
        (xy -2.35 -4.421)
        (xy -2.351 -4.442)
        (xy -1.905 -4.442)
        (xy -1.905 -4.446)
        (xy -1.905 -4.447)
      )

      (stroke (width 0.001) (type solid)) (fill solid) (layer "B.Paste"))
    (fp_poly
      (pts
        (xy -1.905 -1.907)
        (xy -2.351 -1.906)
        (xy -2.35 -1.929)
        (xy -2.348 -1.953)
        (xy -2.346 -1.975)
        (xy -2.34 -1.999)
        (xy -2.335 -2.02)
        (xy -2.328 -2.043)
        (xy -2.322 -2.064)
        (xy -2.312 -2.087)
        (xy -2.302 -2.108)
        (xy -2.291 -2.128)
        (xy -2.278 -2.148)
        (xy -2.266 -2.166)
        (xy -2.251 -2.185)
        (xy -2.237 -2.202)
        (xy -2.221 -2.22)
        (xy -2.203 -2.236)
        (xy -2.186 -2.25)
        (xy -2.167 -2.265)
        (xy -2.149 -2.277)
        (xy -2.129 -2.29)
        (xy -2.109 -2.301)
        (xy -2.088 -2.311)
        (xy -2.065 -2.321)
        (xy -2.044 -2.327)
        (xy -2.021 -2.334)
        (xy -2 -2.339)
        (xy -1.976 -2.345)
        (xy -1.954 -2.347)
        (xy -1.93 -2.349)
        (xy -1.905 -2.35)
        (xy -1.882 -2.349)
        (xy -1.859 -2.347)
        (xy -1.835 -2.345)
        (xy -1.813 -2.339)
        (xy -1.79 -2.334)
        (xy -1.767 -2.327)
        (xy -1.746 -2.319)
        (xy -1.724 -2.311)
        (xy -1.704 -2.301)
        (xy -1.684 -2.289)
        (xy -1.663 -2.277)
        (xy -1.643 -2.265)
        (xy -1.625 -2.25)
        (xy -1.607 -2.236)
        (xy -1.591 -2.22)
        (xy -1.575 -2.202)
        (xy -1.559 -2.185)
        (xy -1.545 -2.166)
        (xy -1.532 -2.146)
        (xy -1.52 -2.126)
        (xy -1.509 -2.107)
        (xy -1.498 -2.085)
        (xy -1.49 -2.064)
        (xy -1.482 -2.043)
        (xy -1.476 -2.019)
        (xy -1.47 -1.997)
        (xy -1.466 -1.975)
        (xy -1.462 -1.951)
        (xy -1.462 -1.927)
        (xy -1.46 -1.904)
        (xy -1.462 -1.881)
        (xy -1.462 -1.858)
        (xy -1.466 -1.834)
        (xy -1.47 -1.812)
        (xy -1.476 -1.789)
        (xy -1.482 -1.766)
        (xy -1.49 -1.745)
        (xy -1.498 -1.723)
        (xy -1.509 -1.703)
        (xy -1.52 -1.683)
        (xy -1.532 -1.662)
        (xy -1.545 -1.642)
        (xy -1.559 -1.624)
        (xy -1.575 -1.606)
        (xy -1.591 -1.59)
        (xy -1.607 -1.574)
        (xy -1.625 -1.558)
        (xy -1.643 -1.544)
        (xy -1.663 -1.531)
        (xy -1.684 -1.519)
        (xy -1.704 -1.508)
        (xy -1.724 -1.497)
        (xy -1.746 -1.489)
        (xy -1.767 -1.481)
        (xy -1.79 -1.475)
        (xy -1.813 -1.469)
        (xy -1.835 -1.465)
        (xy -1.859 -1.461)
        (xy -1.882 -1.461)
        (xy -1.905 -1.459)
        (xy -1.93 -1.461)
        (xy -1.954 -1.461)
        (xy -1.976 -1.465)
        (xy -2 -1.469)
        (xy -2.021 -1.475)
        (xy -2.044 -1.481)
        (xy -2.065 -1.489)
        (xy -2.088 -1.497)
        (xy -2.109 -1.507)
        (xy -2.129 -1.518)
        (xy -2.149 -1.531)
        (xy -2.167 -1.544)
        (xy -2.186 -1.558)
        (xy -2.203 -1.574)
        (xy -2.221 -1.59)
        (xy -2.237 -1.606)
        (xy -2.251 -1.624)
        (xy -2.266 -1.642)
        (xy -2.278 -1.661)
        (xy -2.291 -1.681)
        (xy -2.302 -1.701)
        (xy -2.312 -1.723)
        (xy -2.322 -1.745)
        (xy -2.328 -1.766)
        (xy -2.335 -1.788)
        (xy -2.34 -1.81)
        (xy -2.346 -1.834)
        (xy -2.348 -1.856)
        (xy -2.35 -1.88)
        (xy -2.351 -1.902)
        (xy -1.905 -1.902)
        (xy -1.905 -1.906)
        (xy -1.905 -1.907)
      )

      (stroke (width 0.001) (type solid)) (fill solid) (layer "B.Paste"))
    (fp_poly
      (pts
        (xy -1.905 -0.637)
        (xy -2.351 -0.636)
        (xy -2.35 -0.659)
        (xy -2.348 -0.683)
        (xy -2.346 -0.705)
        (xy -2.34 -0.728)
        (xy -2.335 -0.75)
        (xy -2.328 -0.773)
        (xy -2.322 -0.795)
        (xy -2.312 -0.816)
        (xy -2.302 -0.837)
        (xy -2.291 -0.857)
        (xy -2.278 -0.877)
        (xy -2.266 -0.897)
        (xy -2.251 -0.916)
        (xy -2.237 -0.933)
        (xy -2.221 -0.949)
        (xy -2.203 -0.965)
        (xy -2.186 -0.98)
        (xy -2.167 -0.994)
        (xy -2.149 -1.007)
        (xy -2.129 -1.02)
        (xy -2.109 -1.032)
        (xy -2.088 -1.042)
        (xy -2.065 -1.05)
        (xy -2.044 -1.058)
        (xy -2.021 -1.064)
        (xy -2 -1.07)
        (xy -1.976 -1.074)
        (xy -1.954 -1.078)
        (xy -1.93 -1.078)
        (xy -1.905 -1.08)
        (xy -1.882 -1.078)
        (xy -1.859 -1.078)
        (xy -1.835 -1.074)
        (xy -1.813 -1.07)
        (xy -1.79 -1.064)
        (xy -1.767 -1.058)
        (xy -1.746 -1.05)
        (xy -1.724 -1.042)
        (xy -1.704 -1.03)
        (xy -1.684 -1.019)
        (xy -1.663 -1.007)
        (xy -1.643 -0.994)
        (xy -1.625 -0.98)
        (xy -1.607 -0.965)
        (xy -1.591 -0.949)
        (xy -1.575 -0.933)
        (xy -1.559 -0.915)
        (xy -1.545 -0.897)
        (xy -1.532 -0.876)
        (xy -1.52 -0.857)
        (xy -1.509 -0.836)
        (xy -1.498 -0.815)
        (xy -1.49 -0.794)
        (xy -1.482 -0.773)
        (xy -1.476 -0.749)
        (xy -1.47 -0.727)
        (xy -1.466 -0.704)
        (xy -1.462 -0.682)
        (xy -1.462 -0.658)
        (xy -1.46 -0.634)
        (xy -1.462 -0.611)
        (xy -1.462 -0.587)
        (xy -1.466 -0.564)
        (xy -1.47 -0.542)
        (xy -1.476 -0.52)
        (xy -1.482 -0.496)
        (xy -1.49 -0.475)
        (xy -1.498 -0.454)
        (xy -1.509 -0.432)
        (xy -1.52 -0.411)
        (xy -1.532 -0.393)
        (xy -1.545 -0.372)
        (xy -1.559 -0.354)
        (xy -1.575 -0.337)
        (xy -1.591 -0.32)
        (xy -1.607 -0.303)
        (xy -1.625 -0.288)
        (xy -1.643 -0.275)
        (xy -1.663 -0.262)
        (xy -1.684 -0.249)
        (xy -1.704 -0.238)
        (xy -1.724 -0.228)
        (xy -1.746 -0.219)
        (xy -1.767 -0.211)
        (xy -1.79 -0.204)
        (xy -1.813 -0.2)
        (xy -1.835 -0.195)
        (xy -1.859 -0.192)
        (xy -1.882 -0.19)
        (xy -1.905 -0.189)
        (xy -1.93 -0.19)
        (xy -1.954 -0.192)
        (xy -1.976 -0.195)
        (xy -2 -0.2)
        (xy -2.021 -0.204)
        (xy -2.044 -0.211)
        (xy -2.065 -0.218)
        (xy -2.088 -0.228)
        (xy -2.109 -0.237)
        (xy -2.129 -0.248)
        (xy -2.149 -0.262)
        (xy -2.167 -0.275)
        (xy -2.186 -0.288)
        (xy -2.203 -0.303)
        (xy -2.221 -0.32)
        (xy -2.237 -0.337)
        (xy -2.251 -0.353)
        (xy -2.266 -0.372)
        (xy -2.278 -0.392)
        (xy -2.291 -0.411)
        (xy -2.302 -0.431)
        (xy -2.312 -0.453)
        (xy -2.322 -0.474)
        (xy -2.328 -0.496)
        (xy -2.335 -0.519)
        (xy -2.34 -0.541)
        (xy -2.346 -0.563)
        (xy -2.348 -0.586)
        (xy -2.35 -0.61)
        (xy -2.351 -0.631)
        (xy -1.905 -0.631)
        (xy -1.905 -0.636)
        (xy -1.905 -0.637)
      )

      (stroke (width 0.001) (type solid)) (fill solid) (layer "B.Paste"))
    (fp_poly
      (pts
        (xy -1.905 0.633)
        (xy -2.351 0.632)
        (xy -2.35 0.611)
        (xy -2.348 0.587)
        (xy -2.346 0.564)
        (xy -2.34 0.542)
        (xy -2.335 0.52)
        (xy -2.328 0.497)
        (xy -2.322 0.475)
        (xy -2.312 0.454)
        (xy -2.302 0.432)
        (xy -2.291 0.412)
        (xy -2.278 0.393)
        (xy -2.266 0.373)
        (xy -2.251 0.354)
        (xy -2.237 0.338)
        (xy -2.221 0.32)
        (xy -2.203 0.304)
        (xy -2.186 0.289)
        (xy -2.167 0.276)
        (xy -2.149 0.263)
        (xy -2.129 0.249)
        (xy -2.109 0.238)
        (xy -2.088 0.229)
        (xy -2.065 0.219)
        (xy -2.044 0.212)
        (xy -2.021 0.205)
        (xy -2 0.201)
        (xy -1.976 0.196)
        (xy -1.954 0.192)
        (xy -1.93 0.191)
        (xy -1.905 0.19)
        (xy -1.882 0.191)
        (xy -1.859 0.192)
        (xy -1.835 0.196)
        (xy -1.813 0.201)
        (xy -1.79 0.205)
        (xy -1.767 0.212)
        (xy -1.746 0.22)
        (xy -1.724 0.229)
        (xy -1.704 0.239)
        (xy -1.684 0.25)
        (xy -1.663 0.263)
        (xy -1.643 0.276)
        (xy -1.625 0.289)
        (xy -1.607 0.304)
        (xy -1.591 0.32)
        (xy -1.575 0.338)
        (xy -1.559 0.355)
        (xy -1.545 0.373)
        (xy -1.532 0.394)
        (xy -1.52 0.412)
        (xy -1.509 0.433)
        (xy -1.498 0.455)
        (xy -1.49 0.476)
        (xy -1.482 0.497)
        (xy -1.476 0.521)
        (xy -1.47 0.543)
        (xy -1.466 0.565)
        (xy -1.462 0.588)
        (xy -1.462 0.612)
        (xy -1.46 0.635)
        (xy -1.462 0.659)
        (xy -1.462 0.683)
        (xy -1.466 0.705)
        (xy -1.47 0.728)
        (xy -1.476 0.75)
        (xy -1.482 0.774)
        (xy -1.49 0.795)
        (xy -1.498 0.816)
        (xy -1.509 0.837)
        (xy -1.52 0.858)
        (xy -1.532 0.877)
        (xy -1.545 0.898)
        (xy -1.559 0.916)
        (xy -1.575 0.934)
        (xy -1.591 0.95)
        (xy -1.607 0.966)
        (xy -1.625 0.981)
        (xy -1.643 0.995)
        (xy -1.663 1.008)
        (xy -1.684 1.02)
        (xy -1.704 1.031)
        (xy -1.724 1.043)
        (xy -1.746 1.051)
        (xy -1.767 1.059)
        (xy -1.79 1.065)
        (xy -1.813 1.071)
        (xy -1.835 1.075)
        (xy -1.859 1.079)
        (xy -1.882 1.079)
        (xy -1.905 1.081)
        (xy -1.93 1.079)
        (xy -1.954 1.079)
        (xy -1.976 1.075)
        (xy -2 1.071)
        (xy -2.021 1.065)
        (xy -2.044 1.059)
        (xy -2.065 1.051)
        (xy -2.088 1.043)
        (xy -2.109 1.033)
        (xy -2.129 1.021)
        (xy -2.149 1.008)
        (xy -2.167 0.995)
        (xy -2.186 0.981)
        (xy -2.203 0.966)
        (xy -2.221 0.95)
        (xy -2.237 0.934)
        (xy -2.251 0.917)
        (xy -2.266 0.898)
        (xy -2.278 0.878)
        (xy -2.291 0.858)
        (xy -2.302 0.838)
        (xy -2.312 0.817)
        (xy -2.322 0.796)
        (xy -2.328 0.774)
        (xy -2.335 0.751)
        (xy -2.34 0.729)
        (xy -2.346 0.706)
        (xy -2.348 0.684)
        (xy -2.35 0.66)
        (xy -2.351 0.637)
        (xy -1.905 0.637)
        (xy -1.905 0.632)
        (xy -1.905 0.633)
      )

      (stroke (width 0.001) (type solid)) (fill solid) (layer "B.Paste"))
    (fp_poly
      (pts
        (xy -0.635 -4.447)
        (xy -1.081 -4.446)
        (xy -1.079 -4.469)
        (xy -1.079 -4.493)
        (xy -1.075 -4.515)
        (xy -1.071 -4.538)
        (xy -1.065 -4.56)
        (xy -1.059 -4.583)
        (xy -1.051 -4.605)
        (xy -1.043 -4.626)
        (xy -1.033 -4.647)
        (xy -1.021 -4.668)
        (xy -1.008 -4.687)
        (xy -0.995 -4.706)
        (xy -0.981 -4.725)
        (xy -0.966 -4.743)
        (xy -0.95 -4.759)
        (xy -0.934 -4.775)
        (xy -0.917 -4.791)
        (xy -0.898 -4.804)
        (xy -0.878 -4.817)
        (xy -0.858 -4.831)
        (xy -0.838 -4.841)
        (xy -0.817 -4.852)
        (xy -0.796 -4.86)
        (xy -0.774 -4.868)
        (xy -0.751 -4.874)
        (xy -0.729 -4.879)
        (xy -0.706 -4.884)
        (xy -0.684 -4.887)
        (xy -0.66 -4.889)
        (xy -0.635 -4.889)
        (xy -0.612 -4.889)
        (xy -0.588 -4.887)
        (xy -0.565 -4.884)
        (xy -0.543 -4.879)
        (xy -0.521 -4.874)
        (xy -0.497 -4.868)
        (xy -0.476 -4.86)
        (xy -0.455 -4.852)
        (xy -0.433 -4.841)
        (xy -0.412 -4.829)
        (xy -0.394 -4.817)
        (xy -0.373 -4.804)
        (xy -0.355 -4.791)
        (xy -0.338 -4.775)
        (xy -0.32 -4.759)
        (xy -0.304 -4.743)
        (xy -0.289 -4.724)
        (xy -0.276 -4.706)
        (xy -0.263 -4.687)
        (xy -0.25 -4.668)
        (xy -0.239 -4.647)
        (xy -0.229 -4.626)
        (xy -0.22 -4.603)
        (xy -0.212 -4.583)
        (xy -0.205 -4.559)
        (xy -0.201 -4.538)
        (xy -0.196 -4.514)
        (xy -0.192 -4.491)
        (xy -0.191 -4.467)
        (xy -0.19 -4.445)
        (xy -0.191 -4.421)
        (xy -0.192 -4.397)
        (xy -0.196 -4.374)
        (xy -0.201 -4.352)
        (xy -0.205 -4.329)
        (xy -0.212 -4.307)
        (xy -0.22 -4.285)
        (xy -0.229 -4.264)
        (xy -0.239 -4.243)
        (xy -0.25 -4.222)
        (xy -0.263 -4.203)
        (xy -0.276 -4.182)
        (xy -0.289 -4.164)
        (xy -0.304 -4.147)
        (xy -0.32 -4.129)
        (xy -0.338 -4.113)
        (xy -0.355 -4.099)
        (xy -0.373 -4.084)
        (xy -0.394 -4.071)
        (xy -0.413 -4.059)
        (xy -0.433 -4.049)
        (xy -0.455 -4.038)
        (xy -0.476 -4.03)
        (xy -0.497 -4.022)
        (xy -0.521 -4.014)
        (xy -0.543 -4.009)
        (xy -0.565 -4.004)
        (xy -0.588 -4.001)
        (xy -0.612 -4.001)
        (xy -0.635 -3.999)
        (xy -0.66 -4.001)
        (xy -0.684 -4.001)
        (xy -0.706 -4.004)
        (xy -0.729 -4.009)
        (xy -0.751 -4.014)
        (xy -0.774 -4.022)
        (xy -0.796 -4.028)
        (xy -0.817 -4.038)
        (xy -0.838 -4.047)
        (xy -0.858 -4.059)
        (xy -0.878 -4.071)
        (xy -0.898 -4.084)
        (xy -0.917 -4.099)
        (xy -0.934 -4.113)
        (xy -0.95 -4.129)
        (xy -0.966 -4.147)
        (xy -0.981 -4.163)
        (xy -0.995 -4.182)
        (xy -1.008 -4.201)
        (xy -1.021 -4.222)
        (xy -1.033 -4.241)
        (xy -1.043 -4.262)
        (xy -1.051 -4.285)
        (xy -1.059 -4.307)
        (xy -1.065 -4.328)
        (xy -1.071 -4.35)
        (xy -1.075 -4.373)
        (xy -1.079 -4.397)
        (xy -1.079 -4.421)
        (xy -1.081 -4.442)
        (xy -0.635 -4.442)
        (xy -0.635 -4.446)
        (xy -0.635 -4.447)
      )

      (stroke (width 0.001) (type solid)) (fill solid) (layer "B.Paste"))
    (fp_poly
      (pts
        (xy -0.635 -1.907)
        (xy -1.081 -1.906)
        (xy -1.079 -1.929)
        (xy -1.079 -1.953)
        (xy -1.075 -1.975)
        (xy -1.071 -1.999)
        (xy -1.065 -2.02)
        (xy -1.059 -2.043)
        (xy -1.051 -2.064)
        (xy -1.043 -2.087)
        (xy -1.033 -2.108)
        (xy -1.021 -2.128)
        (xy -1.008 -2.148)
        (xy -0.995 -2.166)
        (xy -0.981 -2.185)
        (xy -0.966 -2.202)
        (xy -0.95 -2.22)
        (xy -0.934 -2.236)
        (xy -0.917 -2.25)
        (xy -0.898 -2.265)
        (xy -0.878 -2.277)
        (xy -0.858 -2.29)
        (xy -0.838 -2.301)
        (xy -0.817 -2.311)
        (xy -0.796 -2.321)
        (xy -0.774 -2.327)
        (xy -0.751 -2.334)
        (xy -0.729 -2.339)
        (xy -0.706 -2.345)
        (xy -0.684 -2.347)
        (xy -0.66 -2.349)
        (xy -0.635 -2.35)
        (xy -0.612 -2.349)
        (xy -0.588 -2.347)
        (xy -0.565 -2.345)
        (xy -0.543 -2.339)
        (xy -0.521 -2.334)
        (xy -0.497 -2.327)
        (xy -0.476 -2.319)
        (xy -0.455 -2.311)
        (xy -0.433 -2.301)
        (xy -0.412 -2.289)
        (xy -0.394 -2.277)
        (xy -0.373 -2.265)
        (xy -0.355 -2.25)
        (xy -0.338 -2.236)
        (xy -0.32 -2.22)
        (xy -0.304 -2.202)
        (xy -0.289 -2.185)
        (xy -0.276 -2.166)
        (xy -0.263 -2.146)
        (xy -0.25 -2.126)
        (xy -0.239 -2.107)
        (xy -0.229 -2.085)
        (xy -0.22 -2.064)
        (xy -0.212 -2.043)
        (xy -0.205 -2.019)
        (xy -0.201 -1.997)
        (xy -0.196 -1.975)
        (xy -0.192 -1.951)
        (xy -0.191 -1.927)
        (xy -0.19 -1.904)
        (xy -0.191 -1.881)
        (xy -0.192 -1.858)
        (xy -0.196 -1.834)
        (xy -0.201 -1.812)
        (xy -0.205 -1.789)
        (xy -0.212 -1.766)
        (xy -0.22 -1.745)
        (xy -0.229 -1.723)
        (xy -0.239 -1.703)
        (xy -0.25 -1.683)
        (xy -0.263 -1.662)
        (xy -0.276 -1.642)
        (xy -0.289 -1.624)
        (xy -0.304 -1.606)
        (xy -0.32 -1.59)
        (xy -0.338 -1.574)
        (xy -0.355 -1.558)
        (xy -0.373 -1.544)
        (xy -0.394 -1.531)
        (xy -0.412 -1.519)
        (xy -0.433 -1.508)
        (xy -0.455 -1.497)
        (xy -0.476 -1.489)
        (xy -0.497 -1.481)
        (xy -0.521 -1.475)
        (xy -0.543 -1.469)
        (xy -0.565 -1.465)
        (xy -0.588 -1.461)
        (xy -0.612 -1.461)
        (xy -0.635 -1.459)
        (xy -0.66 -1.461)
        (xy -0.684 -1.461)
        (xy -0.706 -1.465)
        (xy -0.729 -1.469)
        (xy -0.751 -1.475)
        (xy -0.774 -1.481)
        (xy -0.796 -1.489)
        (xy -0.817 -1.497)
        (xy -0.838 -1.507)
        (xy -0.858 -1.518)
        (xy -0.878 -1.531)
        (xy -0.898 -1.544)
        (xy -0.917 -1.558)
        (xy -0.934 -1.574)
        (xy -0.95 -1.59)
        (xy -0.966 -1.606)
        (xy -0.981 -1.624)
        (xy -0.995 -1.642)
        (xy -1.008 -1.661)
        (xy -1.021 -1.681)
        (xy -1.033 -1.701)
        (xy -1.043 -1.723)
        (xy -1.051 -1.745)
        (xy -1.059 -1.766)
        (xy -1.065 -1.788)
        (xy -1.071 -1.81)
        (xy -1.075 -1.834)
        (xy -1.079 -1.856)
        (xy -1.079 -1.88)
        (xy -1.081 -1.902)
        (xy -0.635 -1.902)
        (xy -0.635 -1.906)
        (xy -0.635 -1.907)
      )

      (stroke (width 0.001) (type solid)) (fill solid) (layer "B.Paste"))
    (fp_poly
      (pts
        (xy -0.635 -0.637)
        (xy -1.081 -0.636)
        (xy -1.079 -0.659)
        (xy -1.079 -0.683)
        (xy -1.075 -0.705)
        (xy -1.071 -0.728)
        (xy -1.065 -0.75)
        (xy -1.059 -0.773)
        (xy -1.051 -0.795)
        (xy -1.043 -0.816)
        (xy -1.033 -0.837)
        (xy -1.021 -0.857)
        (xy -1.008 -0.877)
        (xy -0.995 -0.897)
        (xy -0.981 -0.916)
        (xy -0.966 -0.933)
        (xy -0.95 -0.949)
        (xy -0.934 -0.965)
        (xy -0.917 -0.98)
        (xy -0.898 -0.994)
        (xy -0.878 -1.007)
        (xy -0.858 -1.02)
        (xy -0.838 -1.032)
        (xy -0.817 -1.042)
        (xy -0.796 -1.05)
        (xy -0.774 -1.058)
        (xy -0.751 -1.064)
        (xy -0.729 -1.07)
        (xy -0.706 -1.074)
        (xy -0.684 -1.078)
        (xy -0.66 -1.078)
        (xy -0.635 -1.08)
        (xy -0.612 -1.078)
        (xy -0.588 -1.078)
        (xy -0.565 -1.074)
        (xy -0.543 -1.07)
        (xy -0.521 -1.064)
        (xy -0.497 -1.058)
        (xy -0.476 -1.05)
        (xy -0.455 -1.042)
        (xy -0.433 -1.03)
        (xy -0.412 -1.019)
        (xy -0.394 -1.007)
        (xy -0.373 -0.994)
        (xy -0.355 -0.98)
        (xy -0.338 -0.965)
        (xy -0.32 -0.949)
        (xy -0.304 -0.933)
        (xy -0.289 -0.915)
        (xy -0.276 -0.897)
        (xy -0.263 -0.876)
        (xy -0.25 -0.857)
        (xy -0.239 -0.836)
        (xy -0.229 -0.815)
        (xy -0.22 -0.794)
        (xy -0.212 -0.773)
        (xy -0.205 -0.749)
        (xy -0.201 -0.727)
        (xy -0.196 -0.704)
        (xy -0.192 -0.682)
        (xy -0.191 -0.658)
        (xy -0.19 -0.634)
        (xy -0.191 -0.611)
        (xy -0.192 -0.587)
        (xy -0.196 -0.564)
        (xy -0.201 -0.542)
        (xy -0.205 -0.52)
        (xy -0.212 -0.496)
        (xy -0.22 -0.475)
        (xy -0.229 -0.454)
        (xy -0.239 -0.432)
        (xy -0.25 -0.411)
        (xy -0.263 -0.393)
        (xy -0.276 -0.372)
        (xy -0.289 -0.354)
        (xy -0.304 -0.337)
        (xy -0.32 -0.32)
        (xy -0.338 -0.303)
        (xy -0.355 -0.288)
        (xy -0.373 -0.275)
        (xy -0.394 -0.262)
        (xy -0.412 -0.249)
        (xy -0.433 -0.238)
        (xy -0.455 -0.228)
        (xy -0.476 -0.219)
        (xy -0.497 -0.211)
        (xy -0.521 -0.204)
        (xy -0.543 -0.2)
        (xy -0.565 -0.195)
        (xy -0.588 -0.192)
        (xy -0.612 -0.19)
        (xy -0.635 -0.189)
        (xy -0.66 -0.19)
        (xy -0.684 -0.192)
        (xy -0.706 -0.195)
        (xy -0.729 -0.2)
        (xy -0.751 -0.204)
        (xy -0.774 -0.211)
        (xy -0.796 -0.218)
        (xy -0.817 -0.228)
        (xy -0.838 -0.237)
        (xy -0.858 -0.248)
        (xy -0.878 -0.262)
        (xy -0.898 -0.275)
        (xy -0.917 -0.288)
        (xy -0.934 -0.303)
        (xy -0.95 -0.32)
        (xy -0.966 -0.337)
        (xy -0.981 -0.353)
        (xy -0.995 -0.372)
        (xy -1.008 -0.392)
        (xy -1.021 -0.411)
        (xy -1.033 -0.431)
        (xy -1.043 -0.453)
        (xy -1.051 -0.474)
        (xy -1.059 -0.496)
        (xy -1.065 -0.519)
        (xy -1.071 -0.541)
        (xy -1.075 -0.563)
        (xy -1.079 -0.586)
        (xy -1.079 -0.61)
        (xy -1.081 -0.631)
        (xy -0.635 -0.631)
        (xy -0.635 -0.636)
        (xy -0.635 -0.637)
      )

      (stroke (width 0.001) (type solid)) (fill solid) (layer "B.Paste"))
    (fp_poly
      (pts
        (xy -0.635 0.633)
        (xy -1.081 0.632)
        (xy -1.079 0.611)
        (xy -1.079 0.587)
        (xy -1.075 0.564)
        (xy -1.071 0.542)
        (xy -1.065 0.52)
        (xy -1.059 0.497)
        (xy -1.051 0.475)
        (xy -1.043 0.454)
        (xy -1.033 0.432)
        (xy -1.021 0.412)
        (xy -1.008 0.393)
        (xy -0.995 0.373)
        (xy -0.981 0.354)
        (xy -0.966 0.338)
        (xy -0.95 0.32)
        (xy -0.934 0.304)
        (xy -0.917 0.289)
        (xy -0.898 0.276)
        (xy -0.878 0.263)
        (xy -0.858 0.249)
        (xy -0.838 0.238)
        (xy -0.817 0.229)
        (xy -0.796 0.219)
        (xy -0.774 0.212)
        (xy -0.751 0.205)
        (xy -0.729 0.201)
        (xy -0.706 0.196)
        (xy -0.684 0.192)
        (xy -0.66 0.191)
        (xy -0.635 0.19)
        (xy -0.612 0.191)
        (xy -0.588 0.192)
        (xy -0.565 0.196)
        (xy -0.543 0.201)
        (xy -0.521 0.205)
        (xy -0.497 0.212)
        (xy -0.476 0.22)
        (xy -0.455 0.229)
        (xy -0.433 0.239)
        (xy -0.412 0.25)
        (xy -0.394 0.263)
        (xy -0.373 0.276)
        (xy -0.355 0.289)
        (xy -0.338 0.304)
        (xy -0.32 0.32)
        (xy -0.304 0.338)
        (xy -0.289 0.355)
        (xy -0.276 0.373)
        (xy -0.263 0.394)
        (xy -0.25 0.412)
        (xy -0.239 0.433)
        (xy -0.229 0.455)
        (xy -0.22 0.476)
        (xy -0.212 0.497)
        (xy -0.205 0.521)
        (xy -0.201 0.543)
        (xy -0.196 0.565)
        (xy -0.192 0.588)
        (xy -0.191 0.612)
        (xy -0.19 0.635)
        (xy -0.191 0.659)
        (xy -0.192 0.683)
        (xy -0.196 0.705)
        (xy -0.201 0.728)
        (xy -0.205 0.75)
        (xy -0.212 0.774)
        (xy -0.22 0.795)
        (xy -0.229 0.816)
        (xy -0.239 0.837)
        (xy -0.25 0.858)
        (xy -0.263 0.877)
        (xy -0.276 0.898)
        (xy -0.289 0.916)
        (xy -0.304 0.934)
        (xy -0.32 0.95)
        (xy -0.338 0.966)
        (xy -0.355 0.981)
        (xy -0.373 0.995)
        (xy -0.394 1.008)
        (xy -0.412 1.02)
        (xy -0.433 1.031)
        (xy -0.455 1.043)
        (xy -0.476 1.051)
        (xy -0.497 1.059)
        (xy -0.521 1.065)
        (xy -0.543 1.071)
        (xy -0.565 1.075)
        (xy -0.588 1.079)
        (xy -0.612 1.079)
        (xy -0.635 1.081)
        (xy -0.66 1.079)
        (xy -0.684 1.079)
        (xy -0.706 1.075)
        (xy -0.729 1.071)
        (xy -0.751 1.065)
        (xy -0.774 1.059)
        (xy -0.796 1.051)
        (xy -0.817 1.043)
        (xy -0.838 1.033)
        (xy -0.858 1.021)
        (xy -0.878 1.008)
        (xy -0.898 0.995)
        (xy -0.917 0.981)
        (xy -0.934 0.966)
        (xy -0.95 0.95)
        (xy -0.966 0.934)
        (xy -0.981 0.917)
        (xy -0.995 0.898)
        (xy -1.008 0.878)
        (xy -1.021 0.858)
        (xy -1.033 0.838)
        (xy -1.043 0.817)
        (xy -1.051 0.796)
        (xy -1.059 0.774)
        (xy -1.065 0.751)
        (xy -1.071 0.729)
        (xy -1.075 0.706)
        (xy -1.079 0.684)
        (xy -1.079 0.66)
        (xy -1.081 0.637)
        (xy -0.635 0.637)
        (xy -0.635 0.632)
        (xy -0.635 0.633)
      )

      (stroke (width 0.001) (type solid)) (fill solid) (layer "B.Paste"))
    (fp_poly
      (pts
        (xy 0.634 -4.447)
        (xy 0.189 -4.446)
        (xy 0.19 -4.469)
        (xy 0.192 -4.493)
        (xy 0.195 -4.515)
        (xy 0.2 -4.538)
        (xy 0.204 -4.56)
        (xy 0.211 -4.583)
        (xy 0.218 -4.605)
        (xy 0.228 -4.626)
        (xy 0.237 -4.647)
        (xy 0.248 -4.668)
        (xy 0.262 -4.687)
        (xy 0.275 -4.706)
        (xy 0.288 -4.725)
        (xy 0.303 -4.743)
        (xy 0.32 -4.759)
        (xy 0.337 -4.775)
        (xy 0.353 -4.791)
        (xy 0.372 -4.804)
        (xy 0.392 -4.817)
        (xy 0.411 -4.831)
        (xy 0.431 -4.841)
        (xy 0.453 -4.852)
        (xy 0.474 -4.86)
        (xy 0.496 -4.868)
        (xy 0.519 -4.874)
        (xy 0.541 -4.879)
        (xy 0.563 -4.884)
        (xy 0.586 -4.887)
        (xy 0.61 -4.889)
        (xy 0.634 -4.889)
        (xy 0.658 -4.889)
        (xy 0.682 -4.887)
        (xy 0.704 -4.884)
        (xy 0.727 -4.879)
        (xy 0.749 -4.874)
        (xy 0.773 -4.868)
        (xy 0.794 -4.86)
        (xy 0.815 -4.852)
        (xy 0.836 -4.841)
        (xy 0.857 -4.829)
        (xy 0.876 -4.817)
        (xy 0.897 -4.804)
        (xy 0.915 -4.791)
        (xy 0.933 -4.775)
        (xy 0.949 -4.759)
        (xy 0.965 -4.743)
        (xy 0.98 -4.724)
        (xy 0.994 -4.706)
        (xy 1.007 -4.687)
        (xy 1.019 -4.668)
        (xy 1.03 -4.647)
        (xy 1.042 -4.626)
        (xy 1.05 -4.603)
        (xy 1.058 -4.583)
        (xy 1.064 -4.559)
        (xy 1.07 -4.538)
        (xy 1.074 -4.514)
        (xy 1.078 -4.491)
        (xy 1.078 -4.467)
        (xy 1.08 -4.445)
        (xy 1.078 -4.421)
        (xy 1.078 -4.397)
        (xy 1.074 -4.374)
        (xy 1.07 -4.352)
        (xy 1.064 -4.329)
        (xy 1.058 -4.307)
        (xy 1.05 -4.285)
        (xy 1.042 -4.264)
        (xy 1.03 -4.243)
        (xy 1.019 -4.222)
        (xy 1.007 -4.203)
        (xy 0.994 -4.182)
        (xy 0.98 -4.164)
        (xy 0.965 -4.147)
        (xy 0.949 -4.129)
        (xy 0.933 -4.113)
        (xy 0.915 -4.099)
        (xy 0.897 -4.084)
        (xy 0.876 -4.071)
        (xy 0.856 -4.059)
        (xy 0.836 -4.049)
        (xy 0.815 -4.038)
        (xy 0.794 -4.03)
        (xy 0.773 -4.022)
        (xy 0.749 -4.014)
        (xy 0.727 -4.009)
        (xy 0.704 -4.004)
        (xy 0.682 -4.001)
        (xy 0.658 -4.001)
        (xy 0.634 -3.999)
        (xy 0.61 -4.001)
        (xy 0.586 -4.001)
        (xy 0.563 -4.004)
        (xy 0.541 -4.009)
        (xy 0.519 -4.014)
        (xy 0.496 -4.022)
        (xy 0.474 -4.028)
        (xy 0.453 -4.038)
        (xy 0.431 -4.047)
        (xy 0.411 -4.059)
        (xy 0.392 -4.071)
        (xy 0.372 -4.084)
        (xy 0.353 -4.099)
        (xy 0.337 -4.113)
        (xy 0.32 -4.129)
        (xy 0.303 -4.147)
        (xy 0.288 -4.163)
        (xy 0.275 -4.182)
        (xy 0.262 -4.201)
        (xy 0.248 -4.222)
        (xy 0.237 -4.241)
        (xy 0.228 -4.262)
        (xy 0.218 -4.285)
        (xy 0.211 -4.307)
        (xy 0.204 -4.328)
        (xy 0.2 -4.35)
        (xy 0.195 -4.373)
        (xy 0.192 -4.397)
        (xy 0.19 -4.421)
        (xy 0.189 -4.442)
        (xy 0.634 -4.442)
        (xy 0.634 -4.446)
        (xy 0.634 -4.447)
      )

      (stroke (width 0.001) (type solid)) (fill solid) (layer "B.Paste"))
    (fp_poly
      (pts
        (xy 0.634 -1.907)
        (xy 0.189 -1.906)
        (xy 0.19 -1.929)
        (xy 0.192 -1.953)
        (xy 0.195 -1.975)
        (xy 0.2 -1.999)
        (xy 0.204 -2.02)
        (xy 0.211 -2.043)
        (xy 0.218 -2.064)
        (xy 0.228 -2.087)
        (xy 0.237 -2.108)
        (xy 0.248 -2.128)
        (xy 0.262 -2.148)
        (xy 0.275 -2.166)
        (xy 0.288 -2.185)
        (xy 0.303 -2.202)
        (xy 0.32 -2.22)
        (xy 0.337 -2.236)
        (xy 0.353 -2.25)
        (xy 0.372 -2.265)
        (xy 0.392 -2.277)
        (xy 0.411 -2.29)
        (xy 0.431 -2.301)
        (xy 0.453 -2.311)
        (xy 0.474 -2.321)
        (xy 0.496 -2.327)
        (xy 0.519 -2.334)
        (xy 0.541 -2.339)
        (xy 0.563 -2.345)
        (xy 0.586 -2.347)
        (xy 0.61 -2.349)
        (xy 0.634 -2.35)
        (xy 0.658 -2.349)
        (xy 0.682 -2.347)
        (xy 0.704 -2.345)
        (xy 0.727 -2.339)
        (xy 0.749 -2.334)
        (xy 0.773 -2.327)
        (xy 0.794 -2.319)
        (xy 0.815 -2.311)
        (xy 0.836 -2.301)
        (xy 0.857 -2.289)
        (xy 0.876 -2.277)
        (xy 0.897 -2.265)
        (xy 0.915 -2.25)
        (xy 0.933 -2.236)
        (xy 0.949 -2.22)
        (xy 0.965 -2.202)
        (xy 0.98 -2.185)
        (xy 0.994 -2.166)
        (xy 1.007 -2.146)
        (xy 1.019 -2.126)
        (xy 1.03 -2.107)
        (xy 1.042 -2.085)
        (xy 1.05 -2.064)
        (xy 1.058 -2.043)
        (xy 1.064 -2.019)
        (xy 1.07 -1.997)
        (xy 1.074 -1.975)
        (xy 1.078 -1.951)
        (xy 1.078 -1.927)
        (xy 1.08 -1.904)
        (xy 1.078 -1.881)
        (xy 1.078 -1.858)
        (xy 1.074 -1.834)
        (xy 1.07 -1.812)
        (xy 1.064 -1.789)
        (xy 1.058 -1.766)
        (xy 1.05 -1.745)
        (xy 1.042 -1.723)
        (xy 1.03 -1.703)
        (xy 1.019 -1.683)
        (xy 1.007 -1.662)
        (xy 0.994 -1.642)
        (xy 0.98 -1.624)
        (xy 0.965 -1.606)
        (xy 0.949 -1.59)
        (xy 0.933 -1.574)
        (xy 0.915 -1.558)
        (xy 0.897 -1.544)
        (xy 0.876 -1.531)
        (xy 0.857 -1.519)
        (xy 0.836 -1.508)
        (xy 0.815 -1.497)
        (xy 0.794 -1.489)
        (xy 0.773 -1.481)
        (xy 0.749 -1.475)
        (xy 0.727 -1.469)
        (xy 0.704 -1.465)
        (xy 0.682 -1.461)
        (xy 0.658 -1.461)
        (xy 0.634 -1.459)
        (xy 0.61 -1.461)
        (xy 0.586 -1.461)
        (xy 0.563 -1.465)
        (xy 0.541 -1.469)
        (xy 0.519 -1.475)
        (xy 0.496 -1.481)
        (xy 0.474 -1.489)
        (xy 0.453 -1.497)
        (xy 0.431 -1.507)
        (xy 0.411 -1.518)
        (xy 0.392 -1.531)
        (xy 0.372 -1.544)
        (xy 0.353 -1.558)
        (xy 0.337 -1.574)
        (xy 0.32 -1.59)
        (xy 0.303 -1.606)
        (xy 0.288 -1.624)
        (xy 0.275 -1.642)
        (xy 0.262 -1.661)
        (xy 0.248 -1.681)
        (xy 0.237 -1.701)
        (xy 0.228 -1.723)
        (xy 0.218 -1.745)
        (xy 0.211 -1.766)
        (xy 0.204 -1.788)
        (xy 0.2 -1.81)
        (xy 0.195 -1.834)
        (xy 0.192 -1.856)
        (xy 0.19 -1.88)
        (xy 0.189 -1.902)
        (xy 0.634 -1.902)
        (xy 0.634 -1.906)
        (xy 0.634 -1.907)
      )

      (stroke (width 0.001) (type solid)) (fill solid) (layer "B.Paste"))
    (fp_poly
      (pts
        (xy 0.634 -0.637)
        (xy 0.189 -0.636)
        (xy 0.19 -0.659)
        (xy 0.192 -0.683)
        (xy 0.195 -0.705)
        (xy 0.2 -0.728)
        (xy 0.204 -0.75)
        (xy 0.211 -0.773)
        (xy 0.218 -0.795)
        (xy 0.228 -0.816)
        (xy 0.237 -0.837)
        (xy 0.248 -0.857)
        (xy 0.262 -0.877)
        (xy 0.275 -0.897)
        (xy 0.288 -0.916)
        (xy 0.303 -0.933)
        (xy 0.32 -0.949)
        (xy 0.337 -0.965)
        (xy 0.353 -0.98)
        (xy 0.372 -0.994)
        (xy 0.392 -1.007)
        (xy 0.411 -1.02)
        (xy 0.431 -1.032)
        (xy 0.453 -1.042)
        (xy 0.474 -1.05)
        (xy 0.496 -1.058)
        (xy 0.519 -1.064)
        (xy 0.541 -1.07)
        (xy 0.563 -1.074)
        (xy 0.586 -1.078)
        (xy 0.61 -1.078)
        (xy 0.634 -1.08)
        (xy 0.658 -1.078)
        (xy 0.682 -1.078)
        (xy 0.704 -1.074)
        (xy 0.727 -1.07)
        (xy 0.749 -1.064)
        (xy 0.773 -1.058)
        (xy 0.794 -1.05)
        (xy 0.815 -1.042)
        (xy 0.836 -1.03)
        (xy 0.857 -1.019)
        (xy 0.876 -1.007)
        (xy 0.897 -0.994)
        (xy 0.915 -0.98)
        (xy 0.933 -0.965)
        (xy 0.949 -0.949)
        (xy 0.965 -0.933)
        (xy 0.98 -0.915)
        (xy 0.994 -0.897)
        (xy 1.007 -0.876)
        (xy 1.019 -0.857)
        (xy 1.03 -0.836)
        (xy 1.042 -0.815)
        (xy 1.05 -0.794)
        (xy 1.058 -0.773)
        (xy 1.064 -0.749)
        (xy 1.07 -0.727)
        (xy 1.074 -0.704)
        (xy 1.078 -0.682)
        (xy 1.078 -0.658)
        (xy 1.08 -0.634)
        (xy 1.078 -0.611)
        (xy 1.078 -0.587)
        (xy 1.074 -0.564)
        (xy 1.07 -0.542)
        (xy 1.064 -0.52)
        (xy 1.058 -0.496)
        (xy 1.05 -0.475)
        (xy 1.042 -0.454)
        (xy 1.03 -0.432)
        (xy 1.019 -0.411)
        (xy 1.007 -0.393)
        (xy 0.994 -0.372)
        (xy 0.98 -0.354)
        (xy 0.965 -0.337)
        (xy 0.949 -0.32)
        (xy 0.933 -0.303)
        (xy 0.915 -0.288)
        (xy 0.897 -0.275)
        (xy 0.876 -0.262)
        (xy 0.857 -0.249)
        (xy 0.836 -0.238)
        (xy 0.815 -0.228)
        (xy 0.794 -0.219)
        (xy 0.773 -0.211)
        (xy 0.749 -0.204)
        (xy 0.727 -0.2)
        (xy 0.704 -0.195)
        (xy 0.682 -0.192)
        (xy 0.658 -0.19)
        (xy 0.634 -0.189)
        (xy 0.61 -0.19)
        (xy 0.586 -0.192)
        (xy 0.563 -0.195)
        (xy 0.541 -0.2)
        (xy 0.519 -0.204)
        (xy 0.496 -0.211)
        (xy 0.474 -0.218)
        (xy 0.453 -0.228)
        (xy 0.431 -0.237)
        (xy 0.411 -0.248)
        (xy 0.392 -0.262)
        (xy 0.372 -0.275)
        (xy 0.353 -0.288)
        (xy 0.337 -0.303)
        (xy 0.32 -0.32)
        (xy 0.303 -0.337)
        (xy 0.288 -0.353)
        (xy 0.275 -0.372)
        (xy 0.262 -0.392)
        (xy 0.248 -0.411)
        (xy 0.237 -0.431)
        (xy 0.228 -0.453)
        (xy 0.218 -0.474)
        (xy 0.211 -0.496)
        (xy 0.204 -0.519)
        (xy 0.2 -0.541)
        (xy 0.195 -0.563)
        (xy 0.192 -0.586)
        (xy 0.19 -0.61)
        (xy 0.189 -0.631)
        (xy 0.634 -0.631)
        (xy 0.634 -0.636)
        (xy 0.634 -0.637)
      )

      (stroke (width 0.001) (type solid)) (fill solid) (layer "B.Paste"))
    (fp_poly
      (pts
        (xy 0.634 0.633)
        (xy 0.189 0.632)
        (xy 0.19 0.611)
        (xy 0.192 0.587)
        (xy 0.195 0.564)
        (xy 0.2 0.542)
        (xy 0.204 0.52)
        (xy 0.211 0.497)
        (xy 0.218 0.475)
        (xy 0.228 0.454)
        (xy 0.237 0.432)
        (xy 0.248 0.412)
        (xy 0.262 0.393)
        (xy 0.275 0.373)
        (xy 0.288 0.354)
        (xy 0.303 0.338)
        (xy 0.32 0.32)
        (xy 0.337 0.304)
        (xy 0.353 0.289)
        (xy 0.372 0.276)
        (xy 0.392 0.263)
        (xy 0.411 0.249)
        (xy 0.431 0.238)
        (xy 0.453 0.229)
        (xy 0.474 0.219)
        (xy 0.496 0.212)
        (xy 0.519 0.205)
        (xy 0.541 0.201)
        (xy 0.563 0.196)
        (xy 0.586 0.192)
        (xy 0.61 0.191)
        (xy 0.634 0.19)
        (xy 0.658 0.191)
        (xy 0.682 0.192)
        (xy 0.704 0.196)
        (xy 0.727 0.201)
        (xy 0.749 0.205)
        (xy 0.773 0.212)
        (xy 0.794 0.22)
        (xy 0.815 0.229)
        (xy 0.836 0.239)
        (xy 0.857 0.25)
        (xy 0.876 0.263)
        (xy 0.897 0.276)
        (xy 0.915 0.289)
        (xy 0.933 0.304)
        (xy 0.949 0.32)
        (xy 0.965 0.338)
        (xy 0.98 0.355)
        (xy 0.994 0.373)
        (xy 1.007 0.394)
        (xy 1.019 0.412)
        (xy 1.03 0.433)
        (xy 1.042 0.455)
        (xy 1.05 0.476)
        (xy 1.058 0.497)
        (xy 1.064 0.521)
        (xy 1.07 0.543)
        (xy 1.074 0.565)
        (xy 1.078 0.588)
        (xy 1.078 0.612)
        (xy 1.08 0.635)
        (xy 1.078 0.659)
        (xy 1.078 0.683)
        (xy 1.074 0.705)
        (xy 1.07 0.728)
        (xy 1.064 0.75)
        (xy 1.058 0.774)
        (xy 1.05 0.795)
        (xy 1.042 0.816)
        (xy 1.03 0.837)
        (xy 1.019 0.858)
        (xy 1.007 0.877)
        (xy 0.994 0.898)
        (xy 0.98 0.916)
        (xy 0.965 0.934)
        (xy 0.949 0.95)
        (xy 0.933 0.966)
        (xy 0.915 0.981)
        (xy 0.897 0.995)
        (xy 0.876 1.008)
        (xy 0.857 1.02)
        (xy 0.836 1.031)
        (xy 0.815 1.043)
        (xy 0.794 1.051)
        (xy 0.773 1.059)
        (xy 0.749 1.065)
        (xy 0.727 1.071)
        (xy 0.704 1.075)
        (xy 0.682 1.079)
        (xy 0.658 1.079)
        (xy 0.634 1.081)
        (xy 0.61 1.079)
        (xy 0.586 1.079)
        (xy 0.563 1.075)
        (xy 0.541 1.071)
        (xy 0.519 1.065)
        (xy 0.496 1.059)
        (xy 0.474 1.051)
        (xy 0.453 1.043)
        (xy 0.431 1.033)
        (xy 0.411 1.021)
        (xy 0.392 1.008)
        (xy 0.372 0.995)
        (xy 0.353 0.981)
        (xy 0.337 0.966)
        (xy 0.32 0.95)
        (xy 0.303 0.934)
        (xy 0.288 0.917)
        (xy 0.275 0.898)
        (xy 0.262 0.878)
        (xy 0.248 0.858)
        (xy 0.237 0.838)
        (xy 0.228 0.817)
        (xy 0.218 0.796)
        (xy 0.211 0.774)
        (xy 0.204 0.751)
        (xy 0.2 0.729)
        (xy 0.195 0.706)
        (xy 0.192 0.684)
        (xy 0.19 0.66)
        (xy 0.189 0.637)
        (xy 0.634 0.637)
        (xy 0.634 0.632)
        (xy 0.634 0.633)
      )

      (stroke (width 0.001) (type solid)) (fill solid) (layer "B.Paste"))
    (fp_poly
      (pts
        (xy 1.904 -4.447)
        (xy 1.459 -4.446)
        (xy 1.461 -4.469)
        (xy 1.461 -4.493)
        (xy 1.465 -4.515)
        (xy 1.469 -4.538)
        (xy 1.475 -4.56)
        (xy 1.481 -4.583)
        (xy 1.489 -4.605)
        (xy 1.497 -4.626)
        (xy 1.507 -4.647)
        (xy 1.518 -4.668)
        (xy 1.531 -4.687)
        (xy 1.544 -4.706)
        (xy 1.558 -4.725)
        (xy 1.574 -4.743)
        (xy 1.59 -4.759)
        (xy 1.606 -4.775)
        (xy 1.624 -4.791)
        (xy 1.642 -4.804)
        (xy 1.661 -4.817)
        (xy 1.681 -4.831)
        (xy 1.701 -4.841)
        (xy 1.723 -4.852)
        (xy 1.745 -4.86)
        (xy 1.766 -4.868)
        (xy 1.788 -4.874)
        (xy 1.81 -4.879)
        (xy 1.834 -4.884)
        (xy 1.856 -4.887)
        (xy 1.88 -4.889)
        (xy 1.904 -4.889)
        (xy 1.927 -4.889)
        (xy 1.951 -4.887)
        (xy 1.975 -4.884)
        (xy 1.997 -4.879)
        (xy 2.019 -4.874)
        (xy 2.043 -4.868)
        (xy 2.064 -4.86)
        (xy 2.085 -4.852)
        (xy 2.107 -4.841)
        (xy 2.128 -4.829)
        (xy 2.146 -4.817)
        (xy 2.166 -4.804)
        (xy 2.185 -4.791)
        (xy 2.202 -4.775)
        (xy 2.22 -4.759)
        (xy 2.236 -4.743)
        (xy 2.25 -4.724)
        (xy 2.265 -4.706)
        (xy 2.277 -4.687)
        (xy 2.289 -4.668)
        (xy 2.301 -4.647)
        (xy 2.311 -4.626)
        (xy 2.319 -4.603)
        (xy 2.327 -4.583)
        (xy 2.334 -4.559)
        (xy 2.339 -4.538)
        (xy 2.345 -4.514)
        (xy 2.347 -4.491)
        (xy 2.349 -4.467)
        (xy 2.35 -4.445)
        (xy 2.349 -4.421)
        (xy 2.347 -4.397)
        (xy 2.345 -4.374)
        (xy 2.339 -4.352)
        (xy 2.334 -4.329)
        (xy 2.327 -4.307)
        (xy 2.319 -4.285)
        (xy 2.311 -4.264)
        (xy 2.301 -4.243)
        (xy 2.289 -4.222)
        (xy 2.277 -4.203)
        (xy 2.265 -4.182)
        (xy 2.25 -4.164)
        (xy 2.236 -4.147)
        (xy 2.22 -4.129)
        (xy 2.202 -4.113)
        (xy 2.185 -4.099)
        (xy 2.166 -4.084)
        (xy 2.146 -4.071)
        (xy 2.126 -4.059)
        (xy 2.107 -4.049)
        (xy 2.085 -4.038)
        (xy 2.064 -4.03)
        (xy 2.043 -4.022)
        (xy 2.019 -4.014)
        (xy 1.997 -4.009)
        (xy 1.975 -4.004)
        (xy 1.951 -4.001)
        (xy 1.927 -4.001)
        (xy 1.904 -3.999)
        (xy 1.88 -4.001)
        (xy 1.856 -4.001)
        (xy 1.834 -4.004)
        (xy 1.81 -4.009)
        (xy 1.788 -4.014)
        (xy 1.766 -4.022)
        (xy 1.745 -4.028)
        (xy 1.723 -4.038)
        (xy 1.701 -4.047)
        (xy 1.681 -4.059)
        (xy 1.661 -4.071)
        (xy 1.642 -4.084)
        (xy 1.624 -4.099)
        (xy 1.606 -4.113)
        (xy 1.59 -4.129)
        (xy 1.574 -4.147)
        (xy 1.558 -4.163)
        (xy 1.544 -4.182)
        (xy 1.531 -4.201)
        (xy 1.518 -4.222)
        (xy 1.507 -4.241)
        (xy 1.497 -4.262)
        (xy 1.489 -4.285)
        (xy 1.481 -4.307)
        (xy 1.475 -4.328)
        (xy 1.469 -4.35)
        (xy 1.465 -4.373)
        (xy 1.461 -4.397)
        (xy 1.461 -4.421)
        (xy 1.459 -4.442)
        (xy 1.904 -4.442)
        (xy 1.904 -4.446)
        (xy 1.904 -4.447)
      )

      (stroke (width 0.001) (type solid)) (fill solid) (layer "B.Paste"))
    (fp_poly
      (pts
        (xy 1.904 -1.907)
        (xy 1.459 -1.906)
        (xy 1.461 -1.929)
        (xy 1.461 -1.953)
        (xy 1.465 -1.975)
        (xy 1.469 -1.999)
        (xy 1.475 -2.02)
        (xy 1.481 -2.043)
        (xy 1.489 -2.064)
        (xy 1.497 -2.087)
        (xy 1.507 -2.108)
        (xy 1.518 -2.128)
        (xy 1.531 -2.148)
        (xy 1.544 -2.166)
        (xy 1.558 -2.185)
        (xy 1.574 -2.202)
        (xy 1.59 -2.22)
        (xy 1.606 -2.236)
        (xy 1.624 -2.25)
        (xy 1.642 -2.265)
        (xy 1.661 -2.277)
        (xy 1.681 -2.29)
        (xy 1.701 -2.301)
        (xy 1.723 -2.311)
        (xy 1.745 -2.321)
        (xy 1.766 -2.327)
        (xy 1.788 -2.334)
        (xy 1.81 -2.339)
        (xy 1.834 -2.345)
        (xy 1.856 -2.347)
        (xy 1.88 -2.349)
        (xy 1.904 -2.35)
        (xy 1.927 -2.349)
        (xy 1.951 -2.347)
        (xy 1.975 -2.345)
        (xy 1.997 -2.339)
        (xy 2.019 -2.334)
        (xy 2.043 -2.327)
        (xy 2.064 -2.319)
        (xy 2.085 -2.311)
        (xy 2.107 -2.301)
        (xy 2.126 -2.289)
        (xy 2.146 -2.277)
        (xy 2.166 -2.265)
        (xy 2.185 -2.25)
        (xy 2.202 -2.236)
        (xy 2.22 -2.22)
        (xy 2.236 -2.202)
        (xy 2.25 -2.185)
        (xy 2.265 -2.166)
        (xy 2.277 -2.146)
        (xy 2.289 -2.126)
        (xy 2.301 -2.107)
        (xy 2.311 -2.085)
        (xy 2.319 -2.064)
        (xy 2.327 -2.043)
        (xy 2.334 -2.019)
        (xy 2.339 -1.997)
        (xy 2.345 -1.975)
        (xy 2.347 -1.951)
        (xy 2.349 -1.927)
        (xy 2.35 -1.904)
        (xy 2.349 -1.881)
        (xy 2.347 -1.858)
        (xy 2.345 -1.834)
        (xy 2.339 -1.812)
        (xy 2.334 -1.789)
        (xy 2.327 -1.766)
        (xy 2.319 -1.745)
        (xy 2.311 -1.723)
        (xy 2.301 -1.703)
        (xy 2.289 -1.683)
        (xy 2.277 -1.662)
        (xy 2.265 -1.642)
        (xy 2.25 -1.624)
        (xy 2.236 -1.606)
        (xy 2.22 -1.59)
        (xy 2.202 -1.574)
        (xy 2.185 -1.558)
        (xy 2.166 -1.544)
        (xy 2.146 -1.531)
        (xy 2.126 -1.519)
        (xy 2.107 -1.508)
        (xy 2.085 -1.497)
        (xy 2.064 -1.489)
        (xy 2.043 -1.481)
        (xy 2.019 -1.475)
        (xy 1.997 -1.469)
        (xy 1.975 -1.465)
        (xy 1.951 -1.461)
        (xy 1.927 -1.461)
        (xy 1.904 -1.459)
        (xy 1.88 -1.461)
        (xy 1.856 -1.461)
        (xy 1.834 -1.465)
        (xy 1.81 -1.469)
        (xy 1.788 -1.475)
        (xy 1.766 -1.481)
        (xy 1.745 -1.489)
        (xy 1.723 -1.497)
        (xy 1.701 -1.507)
        (xy 1.681 -1.518)
        (xy 1.661 -1.531)
        (xy 1.642 -1.544)
        (xy 1.624 -1.558)
        (xy 1.606 -1.574)
        (xy 1.59 -1.59)
        (xy 1.574 -1.606)
        (xy 1.558 -1.624)
        (xy 1.544 -1.642)
        (xy 1.531 -1.661)
        (xy 1.518 -1.681)
        (xy 1.507 -1.701)
        (xy 1.497 -1.723)
        (xy 1.489 -1.745)
        (xy 1.481 -1.766)
        (xy 1.475 -1.788)
        (xy 1.469 -1.81)
        (xy 1.465 -1.834)
        (xy 1.461 -1.856)
        (xy 1.461 -1.88)
        (xy 1.459 -1.902)
        (xy 1.904 -1.902)
        (xy 1.904 -1.906)
        (xy 1.904 -1.907)
      )

      (stroke (width 0.001) (type solid)) (fill solid) (layer "B.Paste"))
    (fp_poly
      (pts
        (xy 1.904 -0.637)
        (xy 1.459 -0.636)
        (xy 1.461 -0.659)
        (xy 1.461 -0.683)
        (xy 1.465 -0.705)
        (xy 1.469 -0.728)
        (xy 1.475 -0.75)
        (xy 1.481 -0.773)
        (xy 1.489 -0.795)
        (xy 1.497 -0.816)
        (xy 1.507 -0.837)
        (xy 1.518 -0.857)
        (xy 1.531 -0.877)
        (xy 1.544 -0.897)
        (xy 1.558 -0.916)
        (xy 1.574 -0.933)
        (xy 1.59 -0.949)
        (xy 1.606 -0.965)
        (xy 1.624 -0.98)
        (xy 1.642 -0.994)
        (xy 1.661 -1.007)
        (xy 1.681 -1.02)
        (xy 1.701 -1.032)
        (xy 1.723 -1.042)
        (xy 1.745 -1.05)
        (xy 1.766 -1.058)
        (xy 1.788 -1.064)
        (xy 1.81 -1.07)
        (xy 1.834 -1.074)
        (xy 1.856 -1.078)
        (xy 1.88 -1.078)
        (xy 1.904 -1.08)
        (xy 1.927 -1.078)
        (xy 1.951 -1.078)
        (xy 1.975 -1.074)
        (xy 1.997 -1.07)
        (xy 2.019 -1.064)
        (xy 2.043 -1.058)
        (xy 2.064 -1.05)
        (xy 2.085 -1.042)
        (xy 2.107 -1.03)
        (xy 2.126 -1.019)
        (xy 2.146 -1.007)
        (xy 2.166 -0.994)
        (xy 2.185 -0.98)
        (xy 2.202 -0.965)
        (xy 2.22 -0.949)
        (xy 2.236 -0.933)
        (xy 2.25 -0.915)
        (xy 2.265 -0.897)
        (xy 2.277 -0.876)
        (xy 2.289 -0.857)
        (xy 2.301 -0.836)
        (xy 2.311 -0.815)
        (xy 2.319 -0.794)
        (xy 2.327 -0.773)
        (xy 2.334 -0.749)
        (xy 2.339 -0.727)
        (xy 2.345 -0.704)
        (xy 2.347 -0.682)
        (xy 2.349 -0.658)
        (xy 2.35 -0.634)
        (xy 2.349 -0.611)
        (xy 2.347 -0.587)
        (xy 2.345 -0.564)
        (xy 2.339 -0.542)
        (xy 2.334 -0.52)
        (xy 2.327 -0.496)
        (xy 2.319 -0.475)
        (xy 2.311 -0.454)
        (xy 2.301 -0.432)
        (xy 2.289 -0.411)
        (xy 2.277 -0.393)
        (xy 2.265 -0.372)
        (xy 2.25 -0.354)
        (xy 2.236 -0.337)
        (xy 2.22 -0.32)
        (xy 2.202 -0.303)
        (xy 2.185 -0.288)
        (xy 2.166 -0.275)
        (xy 2.146 -0.262)
        (xy 2.126 -0.249)
        (xy 2.107 -0.238)
        (xy 2.085 -0.228)
        (xy 2.064 -0.219)
        (xy 2.043 -0.211)
        (xy 2.019 -0.204)
        (xy 1.997 -0.2)
        (xy 1.975 -0.195)
        (xy 1.951 -0.192)
        (xy 1.927 -0.19)
        (xy 1.904 -0.189)
        (xy 1.88 -0.19)
        (xy 1.856 -0.192)
        (xy 1.834 -0.195)
        (xy 1.81 -0.2)
        (xy 1.788 -0.204)
        (xy 1.766 -0.211)
        (xy 1.745 -0.218)
        (xy 1.723 -0.228)
        (xy 1.701 -0.237)
        (xy 1.681 -0.248)
        (xy 1.661 -0.262)
        (xy 1.642 -0.275)
        (xy 1.624 -0.288)
        (xy 1.606 -0.303)
        (xy 1.59 -0.32)
        (xy 1.574 -0.337)
        (xy 1.558 -0.353)
        (xy 1.544 -0.372)
        (xy 1.531 -0.392)
        (xy 1.518 -0.411)
        (xy 1.507 -0.431)
        (xy 1.497 -0.453)
        (xy 1.489 -0.474)
        (xy 1.481 -0.496)
        (xy 1.475 -0.519)
        (xy 1.469 -0.541)
        (xy 1.465 -0.563)
        (xy 1.461 -0.586)
        (xy 1.461 -0.61)
        (xy 1.459 -0.631)
        (xy 1.904 -0.631)
        (xy 1.904 -0.636)
        (xy 1.904 -0.637)
      )

      (stroke (width 0.001) (type solid)) (fill solid) (layer "B.Paste"))
    (fp_poly
      (pts
        (xy 1.904 0.633)
        (xy 1.459 0.632)
        (xy 1.461 0.611)
        (xy 1.461 0.587)
        (xy 1.465 0.564)
        (xy 1.469 0.542)
        (xy 1.475 0.52)
        (xy 1.481 0.497)
        (xy 1.489 0.475)
        (xy 1.497 0.454)
        (xy 1.507 0.432)
        (xy 1.518 0.412)
        (xy 1.531 0.393)
        (xy 1.544 0.373)
        (xy 1.558 0.354)
        (xy 1.574 0.338)
        (xy 1.59 0.32)
        (xy 1.606 0.304)
        (xy 1.624 0.289)
        (xy 1.642 0.276)
        (xy 1.661 0.263)
        (xy 1.681 0.249)
        (xy 1.701 0.238)
        (xy 1.723 0.229)
        (xy 1.745 0.219)
        (xy 1.766 0.212)
        (xy 1.788 0.205)
        (xy 1.81 0.201)
        (xy 1.834 0.196)
        (xy 1.856 0.192)
        (xy 1.88 0.191)
        (xy 1.904 0.19)
        (xy 1.927 0.191)
        (xy 1.951 0.192)
        (xy 1.975 0.196)
        (xy 1.997 0.201)
        (xy 2.019 0.205)
        (xy 2.043 0.212)
        (xy 2.064 0.22)
        (xy 2.085 0.229)
        (xy 2.107 0.239)
        (xy 2.126 0.25)
        (xy 2.146 0.263)
        (xy 2.166 0.276)
        (xy 2.185 0.289)
        (xy 2.202 0.304)
        (xy 2.22 0.32)
        (xy 2.236 0.338)
        (xy 2.25 0.355)
        (xy 2.265 0.373)
        (xy 2.277 0.394)
        (xy 2.289 0.412)
        (xy 2.301 0.433)
        (xy 2.311 0.455)
        (xy 2.319 0.476)
        (xy 2.327 0.497)
        (xy 2.334 0.521)
        (xy 2.339 0.543)
        (xy 2.345 0.565)
        (xy 2.347 0.588)
        (xy 2.349 0.612)
        (xy 2.35 0.635)
        (xy 2.349 0.659)
        (xy 2.347 0.683)
        (xy 2.345 0.705)
        (xy 2.339 0.728)
        (xy 2.334 0.75)
        (xy 2.327 0.774)
        (xy 2.319 0.795)
        (xy 2.311 0.816)
        (xy 2.301 0.837)
        (xy 2.289 0.858)
        (xy 2.277 0.877)
        (xy 2.265 0.898)
        (xy 2.25 0.916)
        (xy 2.236 0.934)
        (xy 2.22 0.95)
        (xy 2.202 0.966)
        (xy 2.185 0.981)
        (xy 2.166 0.995)
        (xy 2.146 1.008)
        (xy 2.126 1.02)
        (xy 2.107 1.031)
        (xy 2.085 1.043)
        (xy 2.064 1.051)
        (xy 2.043 1.059)
        (xy 2.019 1.065)
        (xy 1.997 1.071)
        (xy 1.975 1.075)
        (xy 1.951 1.079)
        (xy 1.927 1.079)
        (xy 1.904 1.081)
        (xy 1.88 1.079)
        (xy 1.856 1.079)
        (xy 1.834 1.075)
        (xy 1.81 1.071)
        (xy 1.788 1.065)
        (xy 1.766 1.059)
        (xy 1.745 1.051)
        (xy 1.723 1.043)
        (xy 1.701 1.033)
        (xy 1.681 1.021)
        (xy 1.661 1.008)
        (xy 1.642 0.995)
        (xy 1.624 0.981)
        (xy 1.606 0.966)
        (xy 1.59 0.95)
        (xy 1.574 0.934)
        (xy 1.558 0.917)
        (xy 1.544 0.898)
        (xy 1.531 0.878)
        (xy 1.518 0.858)
        (xy 1.507 0.838)
        (xy 1.497 0.817)
        (xy 1.489 0.796)
        (xy 1.481 0.774)
        (xy 1.475 0.751)
        (xy 1.469 0.729)
        (xy 1.465 0.706)
        (xy 1.461 0.684)
        (xy 1.461 0.66)
        (xy 1.459 0.637)
        (xy 1.904 0.637)
        (xy 1.904 0.632)
        (xy 1.904 0.633)
      )

      (stroke (width 0.001) (type solid)) (fill solid) (layer "B.Paste"))
    (fp_poly
      (pts
        (xy 3.174 -4.447)
        (xy 2.729 -4.446)
        (xy 2.73 -4.469)
        (xy 2.732 -4.493)
        (xy 2.734 -4.515)
        (xy 2.74 -4.538)
        (xy 2.745 -4.56)
        (xy 2.751 -4.583)
        (xy 2.758 -4.605)
        (xy 2.767 -4.626)
        (xy 2.777 -4.647)
        (xy 2.789 -4.668)
        (xy 2.801 -4.687)
        (xy 2.814 -4.706)
        (xy 2.829 -4.725)
        (xy 2.843 -4.743)
        (xy 2.859 -4.759)
        (xy 2.876 -4.775)
        (xy 2.894 -4.791)
        (xy 2.912 -4.804)
        (xy 2.931 -4.817)
        (xy 2.951 -4.831)
        (xy 2.971 -4.841)
        (xy 2.992 -4.852)
        (xy 3.015 -4.86)
        (xy 3.036 -4.868)
        (xy 3.059 -4.874)
        (xy 3.08 -4.879)
        (xy 3.104 -4.884)
        (xy 3.126 -4.887)
        (xy 3.15 -4.889)
        (xy 3.174 -4.889)
        (xy 3.197 -4.889)
        (xy 3.221 -4.887)
        (xy 3.245 -4.884)
        (xy 3.267 -4.879)
        (xy 3.289 -4.874)
        (xy 3.313 -4.868)
        (xy 3.334 -4.86)
        (xy 3.355 -4.852)
        (xy 3.376 -4.841)
        (xy 3.398 -4.829)
        (xy 3.416 -4.817)
        (xy 3.436 -4.804)
        (xy 3.454 -4.791)
        (xy 3.472 -4.775)
        (xy 3.49 -4.759)
        (xy 3.505 -4.743)
        (xy 3.52 -4.724)
        (xy 3.535 -4.706)
        (xy 3.547 -4.687)
        (xy 3.559 -4.668)
        (xy 3.571 -4.647)
        (xy 3.581 -4.626)
        (xy 3.589 -4.603)
        (xy 3.597 -4.583)
        (xy 3.604 -4.559)
        (xy 3.609 -4.538)
        (xy 3.615 -4.514)
        (xy 3.617 -4.491)
        (xy 3.619 -4.467)
        (xy 3.62 -4.445)
        (xy 3.619 -4.421)
        (xy 3.617 -4.397)
        (xy 3.615 -4.374)
        (xy 3.609 -4.352)
        (xy 3.604 -4.329)
        (xy 3.597 -4.307)
        (xy 3.589 -4.285)
        (xy 3.581 -4.264)
        (xy 3.571 -4.243)
        (xy 3.559 -4.222)
        (xy 3.547 -4.203)
        (xy 3.535 -4.182)
        (xy 3.52 -4.164)
        (xy 3.505 -4.147)
        (xy 3.49 -4.129)
        (xy 3.472 -4.113)
        (xy 3.454 -4.099)
        (xy 3.436 -4.084)
        (xy 3.416 -4.071)
        (xy 3.396 -4.059)
        (xy 3.376 -4.049)
        (xy 3.355 -4.038)
        (xy 3.334 -4.03)
        (xy 3.313 -4.022)
        (xy 3.289 -4.014)
        (xy 3.267 -4.009)
        (xy 3.245 -4.004)
        (xy 3.221 -4.001)
        (xy 3.197 -4.001)
        (xy 3.174 -3.999)
        (xy 3.15 -4.001)
        (xy 3.126 -4.001)
        (xy 3.104 -4.004)
        (xy 3.08 -4.009)
        (xy 3.059 -4.014)
        (xy 3.036 -4.022)
        (xy 3.015 -4.028)
        (xy 2.992 -4.038)
        (xy 2.971 -4.047)
        (xy 2.951 -4.059)
        (xy 2.931 -4.071)
        (xy 2.912 -4.084)
        (xy 2.894 -4.099)
        (xy 2.876 -4.113)
        (xy 2.859 -4.129)
        (xy 2.843 -4.147)
        (xy 2.829 -4.163)
        (xy 2.814 -4.182)
        (xy 2.801 -4.201)
        (xy 2.789 -4.222)
        (xy 2.777 -4.241)
        (xy 2.767 -4.262)
        (xy 2.758 -4.285)
        (xy 2.751 -4.307)
        (xy 2.745 -4.328)
        (xy 2.74 -4.35)
        (xy 2.734 -4.373)
        (xy 2.732 -4.397)
        (xy 2.73 -4.421)
        (xy 2.729 -4.442)
        (xy 3.174 -4.442)
        (xy 3.174 -4.446)
        (xy 3.174 -4.447)
      )

      (stroke (width 0.001) (type solid)) (fill solid) (layer "B.Paste"))
    (fp_poly
      (pts
        (xy 3.174 -1.907)
        (xy 2.729 -1.906)
        (xy 2.73 -1.929)
        (xy 2.732 -1.953)
        (xy 2.734 -1.975)
        (xy 2.74 -1.999)
        (xy 2.745 -2.02)
        (xy 2.751 -2.043)
        (xy 2.758 -2.064)
        (xy 2.767 -2.087)
        (xy 2.777 -2.108)
        (xy 2.789 -2.128)
        (xy 2.801 -2.148)
        (xy 2.814 -2.166)
        (xy 2.829 -2.185)
        (xy 2.843 -2.202)
        (xy 2.859 -2.22)
        (xy 2.876 -2.236)
        (xy 2.894 -2.25)
        (xy 2.912 -2.265)
        (xy 2.931 -2.277)
        (xy 2.951 -2.29)
        (xy 2.971 -2.301)
        (xy 2.992 -2.311)
        (xy 3.015 -2.321)
        (xy 3.036 -2.327)
        (xy 3.059 -2.334)
        (xy 3.08 -2.339)
        (xy 3.104 -2.345)
        (xy 3.126 -2.347)
        (xy 3.15 -2.349)
        (xy 3.174 -2.35)
        (xy 3.197 -2.349)
        (xy 3.221 -2.347)
        (xy 3.245 -2.345)
        (xy 3.267 -2.339)
        (xy 3.289 -2.334)
        (xy 3.313 -2.327)
        (xy 3.334 -2.319)
        (xy 3.355 -2.311)
        (xy 3.376 -2.301)
        (xy 3.396 -2.289)
        (xy 3.416 -2.277)
        (xy 3.436 -2.265)
        (xy 3.454 -2.25)
        (xy 3.472 -2.236)
        (xy 3.49 -2.22)
        (xy 3.505 -2.202)
        (xy 3.52 -2.185)
        (xy 3.535 -2.166)
        (xy 3.547 -2.146)
        (xy 3.559 -2.126)
        (xy 3.571 -2.107)
        (xy 3.581 -2.085)
        (xy 3.589 -2.064)
        (xy 3.597 -2.043)
        (xy 3.604 -2.019)
        (xy 3.609 -1.997)
        (xy 3.615 -1.975)
        (xy 3.617 -1.951)
        (xy 3.619 -1.927)
        (xy 3.62 -1.904)
        (xy 3.619 -1.881)
        (xy 3.617 -1.858)
        (xy 3.615 -1.834)
        (xy 3.609 -1.812)
        (xy 3.604 -1.789)
        (xy 3.597 -1.766)
        (xy 3.589 -1.745)
        (xy 3.581 -1.723)
        (xy 3.571 -1.703)
        (xy 3.559 -1.683)
        (xy 3.547 -1.662)
        (xy 3.535 -1.642)
        (xy 3.52 -1.624)
        (xy 3.505 -1.606)
        (xy 3.49 -1.59)
        (xy 3.472 -1.574)
        (xy 3.454 -1.558)
        (xy 3.436 -1.544)
        (xy 3.416 -1.531)
        (xy 3.396 -1.519)
        (xy 3.376 -1.508)
        (xy 3.355 -1.497)
        (xy 3.334 -1.489)
        (xy 3.313 -1.481)
        (xy 3.289 -1.475)
        (xy 3.267 -1.469)
        (xy 3.245 -1.465)
        (xy 3.221 -1.461)
        (xy 3.197 -1.461)
        (xy 3.174 -1.459)
        (xy 3.15 -1.461)
        (xy 3.126 -1.461)
        (xy 3.104 -1.465)
        (xy 3.08 -1.469)
        (xy 3.059 -1.475)
        (xy 3.036 -1.481)
        (xy 3.015 -1.489)
        (xy 2.992 -1.497)
        (xy 2.971 -1.507)
        (xy 2.951 -1.518)
        (xy 2.931 -1.531)
        (xy 2.912 -1.544)
        (xy 2.894 -1.558)
        (xy 2.876 -1.574)
        (xy 2.859 -1.59)
        (xy 2.843 -1.606)
        (xy 2.829 -1.624)
        (xy 2.814 -1.642)
        (xy 2.801 -1.661)
        (xy 2.789 -1.681)
        (xy 2.777 -1.701)
        (xy 2.767 -1.723)
        (xy 2.758 -1.745)
        (xy 2.751 -1.766)
        (xy 2.745 -1.788)
        (xy 2.74 -1.81)
        (xy 2.734 -1.834)
        (xy 2.732 -1.856)
        (xy 2.73 -1.88)
        (xy 2.729 -1.902)
        (xy 3.174 -1.902)
        (xy 3.174 -1.906)
        (xy 3.174 -1.907)
      )

      (stroke (width 0.001) (type solid)) (fill solid) (layer "B.Paste"))
    (fp_poly
      (pts
        (xy 3.174 -0.637)
        (xy 2.729 -0.636)
        (xy 2.73 -0.659)
        (xy 2.732 -0.683)
        (xy 2.734 -0.705)
        (xy 2.74 -0.728)
        (xy 2.745 -0.75)
        (xy 2.751 -0.773)
        (xy 2.758 -0.795)
        (xy 2.767 -0.816)
        (xy 2.777 -0.837)
        (xy 2.789 -0.857)
        (xy 2.801 -0.877)
        (xy 2.814 -0.897)
        (xy 2.829 -0.916)
        (xy 2.843 -0.933)
        (xy 2.859 -0.949)
        (xy 2.876 -0.965)
        (xy 2.894 -0.98)
        (xy 2.912 -0.994)
        (xy 2.931 -1.007)
        (xy 2.951 -1.02)
        (xy 2.971 -1.032)
        (xy 2.992 -1.042)
        (xy 3.015 -1.05)
        (xy 3.036 -1.058)
        (xy 3.059 -1.064)
        (xy 3.08 -1.07)
        (xy 3.104 -1.074)
        (xy 3.126 -1.078)
        (xy 3.15 -1.078)
        (xy 3.174 -1.08)
        (xy 3.197 -1.078)
        (xy 3.221 -1.078)
        (xy 3.245 -1.074)
        (xy 3.267 -1.07)
        (xy 3.289 -1.064)
        (xy 3.313 -1.058)
        (xy 3.334 -1.05)
        (xy 3.355 -1.042)
        (xy 3.376 -1.03)
        (xy 3.396 -1.019)
        (xy 3.416 -1.007)
        (xy 3.436 -0.994)
        (xy 3.454 -0.98)
        (xy 3.472 -0.965)
        (xy 3.49 -0.949)
        (xy 3.505 -0.933)
        (xy 3.52 -0.915)
        (xy 3.535 -0.897)
        (xy 3.547 -0.876)
        (xy 3.559 -0.856)
        (xy 3.571 -0.836)
        (xy 3.581 -0.815)
        (xy 3.589 -0.794)
        (xy 3.597 -0.773)
        (xy 3.604 -0.749)
        (xy 3.609 -0.727)
        (xy 3.615 -0.704)
        (xy 3.617 -0.682)
        (xy 3.619 -0.658)
        (xy 3.62 -0.634)
        (xy 3.619 -0.611)
        (xy 3.617 -0.587)
        (xy 3.615 -0.564)
        (xy 3.609 -0.542)
        (xy 3.604 -0.52)
        (xy 3.597 -0.496)
        (xy 3.589 -0.475)
        (xy 3.581 -0.454)
        (xy 3.571 -0.432)
        (xy 3.559 -0.412)
        (xy 3.547 -0.393)
        (xy 3.535 -0.372)
        (xy 3.52 -0.354)
        (xy 3.505 -0.337)
        (xy 3.49 -0.32)
        (xy 3.472 -0.303)
        (xy 3.454 -0.288)
        (xy 3.436 -0.275)
        (xy 3.416 -0.262)
        (xy 3.396 -0.249)
        (xy 3.376 -0.238)
        (xy 3.355 -0.228)
        (xy 3.334 -0.219)
        (xy 3.313 -0.211)
        (xy 3.289 -0.204)
        (xy 3.267 -0.2)
        (xy 3.245 -0.195)
        (xy 3.221 -0.192)
        (xy 3.197 -0.19)
        (xy 3.174 -0.189)
        (xy 3.15 -0.19)
        (xy 3.126 -0.192)
        (xy 3.104 -0.195)
        (xy 3.08 -0.2)
        (xy 3.059 -0.204)
        (xy 3.036 -0.211)
        (xy 3.015 -0.218)
        (xy 2.992 -0.228)
        (xy 2.971 -0.237)
        (xy 2.951 -0.248)
        (xy 2.931 -0.262)
        (xy 2.912 -0.275)
        (xy 2.894 -0.288)
        (xy 2.876 -0.303)
        (xy 2.859 -0.32)
        (xy 2.843 -0.337)
        (xy 2.829 -0.353)
        (xy 2.814 -0.372)
        (xy 2.801 -0.392)
        (xy 2.789 -0.411)
        (xy 2.777 -0.431)
        (xy 2.767 -0.453)
        (xy 2.758 -0.474)
        (xy 2.751 -0.496)
        (xy 2.745 -0.519)
        (xy 2.74 -0.541)
        (xy 2.734 -0.563)
        (xy 2.732 -0.586)
        (xy 2.73 -0.61)
        (xy 2.729 -0.631)
        (xy 3.174 -0.631)
        (xy 3.174 -0.636)
        (xy 3.174 -0.637)
      )

      (stroke (width 0.001) (type solid)) (fill solid) (layer "B.Paste"))
    (fp_poly
      (pts
        (xy 3.174 0.633)
        (xy 2.729 0.632)
        (xy 2.73 0.611)
        (xy 2.732 0.587)
        (xy 2.734 0.564)
        (xy 2.74 0.542)
        (xy 2.745 0.52)
        (xy 2.751 0.497)
        (xy 2.758 0.475)
        (xy 2.767 0.454)
        (xy 2.777 0.432)
        (xy 2.789 0.412)
        (xy 2.801 0.393)
        (xy 2.814 0.373)
        (xy 2.829 0.354)
        (xy 2.843 0.338)
        (xy 2.859 0.32)
        (xy 2.876 0.304)
        (xy 2.894 0.289)
        (xy 2.912 0.276)
        (xy 2.931 0.263)
        (xy 2.951 0.249)
        (xy 2.971 0.238)
        (xy 2.992 0.229)
        (xy 3.015 0.219)
        (xy 3.036 0.212)
        (xy 3.059 0.205)
        (xy 3.08 0.201)
        (xy 3.104 0.196)
        (xy 3.126 0.192)
        (xy 3.15 0.191)
        (xy 3.174 0.19)
        (xy 3.197 0.191)
        (xy 3.221 0.192)
        (xy 3.245 0.196)
        (xy 3.267 0.201)
        (xy 3.289 0.205)
        (xy 3.313 0.212)
        (xy 3.334 0.22)
        (xy 3.355 0.229)
        (xy 3.376 0.239)
        (xy 3.396 0.25)
        (xy 3.416 0.263)
        (xy 3.436 0.276)
        (xy 3.454 0.289)
        (xy 3.472 0.304)
        (xy 3.49 0.32)
        (xy 3.505 0.338)
        (xy 3.52 0.355)
        (xy 3.535 0.373)
        (xy 3.547 0.394)
        (xy 3.559 0.413)
        (xy 3.571 0.433)
        (xy 3.581 0.455)
        (xy 3.589 0.476)
        (xy 3.597 0.497)
        (xy 3.604 0.521)
        (xy 3.609 0.543)
        (xy 3.615 0.565)
        (xy 3.617 0.588)
        (xy 3.619 0.612)
        (xy 3.62 0.635)
        (xy 3.619 0.659)
        (xy 3.617 0.683)
        (xy 3.615 0.705)
        (xy 3.609 0.728)
        (xy 3.604 0.75)
        (xy 3.597 0.774)
        (xy 3.589 0.795)
        (xy 3.581 0.816)
        (xy 3.571 0.837)
        (xy 3.559 0.857)
        (xy 3.547 0.877)
        (xy 3.535 0.898)
        (xy 3.52 0.916)
        (xy 3.505 0.934)
        (xy 3.49 0.95)
        (xy 3.472 0.966)
        (xy 3.454 0.981)
        (xy 3.436 0.995)
        (xy 3.416 1.008)
        (xy 3.396 1.02)
        (xy 3.376 1.031)
        (xy 3.355 1.043)
        (xy 3.334 1.051)
        (xy 3.313 1.059)
        (xy 3.289 1.065)
        (xy 3.267 1.071)
        (xy 3.245 1.075)
        (xy 3.221 1.079)
        (xy 3.197 1.079)
        (xy 3.174 1.081)
        (xy 3.15 1.079)
        (xy 3.126 1.079)
        (xy 3.104 1.075)
        (xy 3.08 1.071)
        (xy 3.059 1.065)
        (xy 3.036 1.059)
        (xy 3.015 1.051)
        (xy 2.992 1.043)
        (xy 2.971 1.033)
        (xy 2.951 1.021)
        (xy 2.931 1.008)
        (xy 2.912 0.995)
        (xy 2.894 0.981)
        (xy 2.876 0.966)
        (xy 2.859 0.95)
        (xy 2.843 0.934)
        (xy 2.829 0.917)
        (xy 2.814 0.898)
        (xy 2.801 0.878)
        (xy 2.789 0.858)
        (xy 2.777 0.838)
        (xy 2.767 0.817)
        (xy 2.758 0.796)
        (xy 2.751 0.774)
        (xy 2.745 0.751)
        (xy 2.74 0.729)
        (xy 2.734 0.706)
        (xy 2.732 0.684)
        (xy 2.73 0.66)
        (xy 2.729 0.637)
        (xy 3.174 0.637)
        (xy 3.174 0.632)
        (xy 3.174 0.633)
      )

      (stroke (width 0.001) (type solid)) (fill solid) (layer "B.Paste"))
    (fp_poly
      (pts
        (xy 4.445 -4.447)
        (xy 3.999 -4.446)
        (xy 4.001 -4.469)
        (xy 4.001 -4.493)
        (xy 4.004 -4.515)
        (xy 4.009 -4.538)
        (xy 4.014 -4.56)
        (xy 4.022 -4.583)
        (xy 4.028 -4.605)
        (xy 4.038 -4.626)
        (xy 4.047 -4.647)
        (xy 4.059 -4.668)
        (xy 4.071 -4.687)
        (xy 4.084 -4.706)
        (xy 4.099 -4.725)
        (xy 4.113 -4.743)
        (xy 4.129 -4.759)
        (xy 4.147 -4.775)
        (xy 4.163 -4.791)
        (xy 4.182 -4.804)
        (xy 4.201 -4.817)
        (xy 4.222 -4.831)
        (xy 4.241 -4.841)
        (xy 4.262 -4.852)
        (xy 4.285 -4.86)
        (xy 4.307 -4.868)
        (xy 4.328 -4.874)
        (xy 4.35 -4.879)
        (xy 4.373 -4.884)
        (xy 4.397 -4.887)
        (xy 4.421 -4.889)
        (xy 4.445 -4.889)
        (xy 4.467 -4.889)
        (xy 4.491 -4.887)
        (xy 4.514 -4.884)
        (xy 4.538 -4.879)
        (xy 4.559 -4.874)
        (xy 4.583 -4.868)
        (xy 4.603 -4.86)
        (xy 4.626 -4.852)
        (xy 4.647 -4.841)
        (xy 4.668 -4.829)
        (xy 4.687 -4.817)
        (xy 4.706 -4.804)
        (xy 4.724 -4.791)
        (xy 4.743 -4.775)
        (xy 4.759 -4.759)
        (xy 4.775 -4.743)
        (xy 4.791 -4.724)
        (xy 4.804 -4.706)
        (xy 4.817 -4.687)
        (xy 4.829 -4.668)
        (xy 4.841 -4.647)
        (xy 4.852 -4.626)
        (xy 4.86 -4.603)
        (xy 4.868 -4.583)
        (xy 4.874 -4.559)
        (xy 4.879 -4.538)
        (xy 4.884 -4.514)
        (xy 4.887 -4.491)
        (xy 4.889 -4.467)
        (xy 4.889 -4.445)
        (xy 4.889 -4.421)
        (xy 4.887 -4.397)
        (xy 4.884 -4.374)
        (xy 4.879 -4.352)
        (xy 4.874 -4.329)
        (xy 4.868 -4.307)
        (xy 4.86 -4.285)
        (xy 4.852 -4.264)
        (xy 4.841 -4.243)
        (xy 4.829 -4.222)
        (xy 4.817 -4.203)
        (xy 4.804 -4.182)
        (xy 4.791 -4.164)
        (xy 4.775 -4.147)
        (xy 4.759 -4.129)
        (xy 4.743 -4.113)
        (xy 4.724 -4.099)
        (xy 4.706 -4.084)
        (xy 4.687 -4.071)
        (xy 4.668 -4.059)
        (xy 4.647 -4.049)
        (xy 4.626 -4.038)
        (xy 4.603 -4.03)
        (xy 4.583 -4.022)
        (xy 4.559 -4.014)
        (xy 4.538 -4.009)
        (xy 4.514 -4.004)
        (xy 4.491 -4.001)
        (xy 4.467 -4.001)
        (xy 4.445 -3.999)
        (xy 4.421 -4.001)
        (xy 4.397 -4.001)
        (xy 4.373 -4.004)
        (xy 4.35 -4.009)
        (xy 4.328 -4.014)
        (xy 4.307 -4.022)
        (xy 4.285 -4.028)
        (xy 4.262 -4.038)
        (xy 4.241 -4.047)
        (xy 4.222 -4.059)
        (xy 4.201 -4.071)
        (xy 4.182 -4.084)
        (xy 4.163 -4.099)
        (xy 4.147 -4.113)
        (xy 4.129 -4.129)
        (xy 4.113 -4.147)
        (xy 4.099 -4.163)
        (xy 4.084 -4.182)
        (xy 4.071 -4.201)
        (xy 4.059 -4.222)
        (xy 4.047 -4.241)
        (xy 4.038 -4.262)
        (xy 4.028 -4.285)
        (xy 4.022 -4.307)
        (xy 4.014 -4.328)
        (xy 4.009 -4.35)
        (xy 4.004 -4.373)
        (xy 4.001 -4.397)
        (xy 4.001 -4.421)
        (xy 3.999 -4.442)
        (xy 4.445 -4.442)
        (xy 4.445 -4.446)
        (xy 4.445 -4.447)
      )

      (stroke (width 0.001) (type solid)) (fill solid) (layer "B.Paste"))
    (fp_poly
      (pts
        (xy 4.445 -1.907)
        (xy 3.999 -1.906)
        (xy 4.001 -1.929)
        (xy 4.001 -1.953)
        (xy 4.004 -1.975)
        (xy 4.009 -1.999)
        (xy 4.014 -2.02)
        (xy 4.022 -2.043)
        (xy 4.028 -2.064)
        (xy 4.038 -2.087)
        (xy 4.047 -2.108)
        (xy 4.059 -2.128)
        (xy 4.071 -2.148)
        (xy 4.084 -2.166)
        (xy 4.099 -2.185)
        (xy 4.113 -2.202)
        (xy 4.129 -2.22)
        (xy 4.147 -2.236)
        (xy 4.163 -2.25)
        (xy 4.182 -2.265)
        (xy 4.201 -2.277)
        (xy 4.222 -2.29)
        (xy 4.241 -2.301)
        (xy 4.262 -2.311)
        (xy 4.285 -2.321)
        (xy 4.307 -2.327)
        (xy 4.328 -2.334)
        (xy 4.35 -2.339)
        (xy 4.373 -2.345)
        (xy 4.397 -2.347)
        (xy 4.421 -2.349)
        (xy 4.445 -2.35)
        (xy 4.467 -2.349)
        (xy 4.491 -2.347)
        (xy 4.514 -2.345)
        (xy 4.538 -2.339)
        (xy 4.559 -2.334)
        (xy 4.583 -2.327)
        (xy 4.603 -2.319)
        (xy 4.626 -2.311)
        (xy 4.647 -2.301)
        (xy 4.668 -2.289)
        (xy 4.687 -2.277)
        (xy 4.706 -2.265)
        (xy 4.724 -2.25)
        (xy 4.743 -2.236)
        (xy 4.759 -2.22)
        (xy 4.775 -2.202)
        (xy 4.791 -2.185)
        (xy 4.804 -2.166)
        (xy 4.817 -2.146)
        (xy 4.829 -2.126)
        (xy 4.841 -2.107)
        (xy 4.852 -2.085)
        (xy 4.86 -2.064)
        (xy 4.868 -2.043)
        (xy 4.874 -2.019)
        (xy 4.879 -1.997)
        (xy 4.884 -1.975)
        (xy 4.887 -1.951)
        (xy 4.889 -1.927)
        (xy 4.889 -1.904)
        (xy 4.889 -1.881)
        (xy 4.887 -1.858)
        (xy 4.884 -1.834)
        (xy 4.879 -1.812)
        (xy 4.874 -1.789)
        (xy 4.868 -1.766)
        (xy 4.86 -1.745)
        (xy 4.852 -1.723)
        (xy 4.841 -1.703)
        (xy 4.829 -1.681)
        (xy 4.817 -1.662)
        (xy 4.804 -1.642)
        (xy 4.791 -1.624)
        (xy 4.775 -1.606)
        (xy 4.759 -1.59)
        (xy 4.743 -1.574)
        (xy 4.724 -1.558)
        (xy 4.706 -1.544)
        (xy 4.687 -1.531)
        (xy 4.668 -1.519)
        (xy 4.647 -1.508)
        (xy 4.626 -1.497)
        (xy 4.603 -1.489)
        (xy 4.583 -1.481)
        (xy 4.559 -1.475)
        (xy 4.538 -1.469)
        (xy 4.514 -1.465)
        (xy 4.491 -1.461)
        (xy 4.467 -1.461)
        (xy 4.445 -1.459)
        (xy 4.421 -1.461)
        (xy 4.397 -1.461)
        (xy 4.373 -1.465)
        (xy 4.35 -1.469)
        (xy 4.328 -1.475)
        (xy 4.307 -1.481)
        (xy 4.285 -1.489)
        (xy 4.262 -1.497)
        (xy 4.241 -1.507)
        (xy 4.222 -1.518)
        (xy 4.201 -1.531)
        (xy 4.182 -1.544)
        (xy 4.163 -1.558)
        (xy 4.147 -1.574)
        (xy 4.129 -1.59)
        (xy 4.113 -1.606)
        (xy 4.099 -1.624)
        (xy 4.084 -1.642)
        (xy 4.071 -1.661)
        (xy 4.059 -1.681)
        (xy 4.047 -1.701)
        (xy 4.038 -1.723)
        (xy 4.028 -1.745)
        (xy 4.022 -1.766)
        (xy 4.014 -1.788)
        (xy 4.009 -1.81)
        (xy 4.004 -1.834)
        (xy 4.001 -1.856)
        (xy 4.001 -1.88)
        (xy 3.999 -1.902)
        (xy 4.445 -1.902)
        (xy 4.445 -1.906)
        (xy 4.445 -1.907)
      )

      (stroke (width 0.001) (type solid)) (fill solid) (layer "B.Paste"))
    (fp_poly
      (pts
        (xy 4.445 -0.637)
        (xy 3.999 -0.636)
        (xy 4.001 -0.659)
        (xy 4.001 -0.683)
        (xy 4.004 -0.705)
        (xy 4.009 -0.728)
        (xy 4.014 -0.75)
        (xy 4.022 -0.773)
        (xy 4.028 -0.795)
        (xy 4.038 -0.816)
        (xy 4.047 -0.837)
        (xy 4.059 -0.857)
        (xy 4.071 -0.877)
        (xy 4.084 -0.897)
        (xy 4.099 -0.916)
        (xy 4.113 -0.933)
        (xy 4.129 -0.949)
        (xy 4.147 -0.965)
        (xy 4.163 -0.98)
        (xy 4.182 -0.994)
        (xy 4.201 -1.007)
        (xy 4.222 -1.02)
        (xy 4.241 -1.032)
        (xy 4.262 -1.042)
        (xy 4.285 -1.05)
        (xy 4.307 -1.058)
        (xy 4.328 -1.064)
        (xy 4.35 -1.07)
        (xy 4.373 -1.074)
        (xy 4.397 -1.078)
        (xy 4.421 -1.078)
        (xy 4.445 -1.08)
        (xy 4.467 -1.078)
        (xy 4.491 -1.078)
        (xy 4.514 -1.074)
        (xy 4.538 -1.07)
        (xy 4.559 -1.064)
        (xy 4.583 -1.058)
        (xy 4.603 -1.05)
        (xy 4.626 -1.042)
        (xy 4.647 -1.03)
        (xy 4.668 -1.019)
        (xy 4.687 -1.007)
        (xy 4.706 -0.994)
        (xy 4.724 -0.98)
        (xy 4.743 -0.965)
        (xy 4.759 -0.949)
        (xy 4.775 -0.933)
        (xy 4.791 -0.915)
        (xy 4.804 -0.897)
        (xy 4.817 -0.876)
        (xy 4.829 -0.857)
        (xy 4.841 -0.836)
        (xy 4.852 -0.815)
        (xy 4.86 -0.794)
        (xy 4.868 -0.773)
        (xy 4.874 -0.749)
        (xy 4.879 -0.727)
        (xy 4.884 -0.704)
        (xy 4.887 -0.682)
        (xy 4.889 -0.658)
        (xy 4.889 -0.634)
        (xy 4.889 -0.611)
        (xy 4.887 -0.587)
        (xy 4.884 -0.564)
        (xy 4.879 -0.542)
        (xy 4.874 -0.52)
        (xy 4.868 -0.496)
        (xy 4.86 -0.475)
        (xy 4.852 -0.454)
        (xy 4.841 -0.432)
        (xy 4.829 -0.411)
        (xy 4.817 -0.393)
        (xy 4.804 -0.372)
        (xy 4.791 -0.354)
        (xy 4.775 -0.337)
        (xy 4.759 -0.32)
        (xy 4.743 -0.303)
        (xy 4.724 -0.288)
        (xy 4.706 -0.275)
        (xy 4.687 -0.262)
        (xy 4.668 -0.249)
        (xy 4.647 -0.238)
        (xy 4.626 -0.228)
        (xy 4.603 -0.219)
        (xy 4.583 -0.211)
        (xy 4.559 -0.204)
        (xy 4.538 -0.2)
        (xy 4.514 -0.195)
        (xy 4.491 -0.192)
        (xy 4.467 -0.19)
        (xy 4.445 -0.189)
        (xy 4.421 -0.19)
        (xy 4.397 -0.192)
        (xy 4.373 -0.195)
        (xy 4.35 -0.2)
        (xy 4.328 -0.204)
        (xy 4.307 -0.211)
        (xy 4.285 -0.218)
        (xy 4.262 -0.228)
        (xy 4.241 -0.237)
        (xy 4.222 -0.248)
        (xy 4.201 -0.262)
        (xy 4.182 -0.275)
        (xy 4.163 -0.288)
        (xy 4.147 -0.303)
        (xy 4.129 -0.32)
        (xy 4.113 -0.337)
        (xy 4.099 -0.353)
        (xy 4.084 -0.372)
        (xy 4.071 -0.392)
        (xy 4.059 -0.411)
        (xy 4.047 -0.431)
        (xy 4.038 -0.453)
        (xy 4.028 -0.474)
        (xy 4.022 -0.496)
        (xy 4.014 -0.519)
        (xy 4.009 -0.541)
        (xy 4.004 -0.563)
        (xy 4.001 -0.586)
        (xy 4.001 -0.61)
        (xy 3.999 -0.631)
        (xy 4.445 -0.631)
        (xy 4.445 -0.636)
        (xy 4.445 -0.637)
      )

      (stroke (width 0.001) (type solid)) (fill solid) (layer "B.Paste"))
    (fp_poly
      (pts
        (xy 4.445 0.633)
        (xy 3.999 0.632)
        (xy 4.001 0.611)
        (xy 4.001 0.587)
        (xy 4.004 0.564)
        (xy 4.009 0.542)
        (xy 4.014 0.52)
        (xy 4.022 0.497)
        (xy 4.028 0.475)
        (xy 4.038 0.454)
        (xy 4.047 0.432)
        (xy 4.059 0.412)
        (xy 4.071 0.393)
        (xy 4.084 0.373)
        (xy 4.099 0.354)
        (xy 4.113 0.338)
        (xy 4.129 0.32)
        (xy 4.147 0.304)
        (xy 4.163 0.289)
        (xy 4.182 0.276)
        (xy 4.201 0.263)
        (xy 4.222 0.249)
        (xy 4.241 0.238)
        (xy 4.262 0.229)
        (xy 4.285 0.219)
        (xy 4.307 0.212)
        (xy 4.328 0.205)
        (xy 4.35 0.201)
        (xy 4.373 0.196)
        (xy 4.397 0.192)
        (xy 4.421 0.191)
        (xy 4.445 0.19)
        (xy 4.467 0.191)
        (xy 4.491 0.192)
        (xy 4.514 0.196)
        (xy 4.538 0.201)
        (xy 4.559 0.205)
        (xy 4.583 0.212)
        (xy 4.603 0.22)
        (xy 4.626 0.229)
        (xy 4.647 0.239)
        (xy 4.668 0.25)
        (xy 4.687 0.263)
        (xy 4.706 0.276)
        (xy 4.724 0.289)
        (xy 4.743 0.304)
        (xy 4.759 0.32)
        (xy 4.775 0.338)
        (xy 4.791 0.355)
        (xy 4.804 0.373)
        (xy 4.817 0.394)
        (xy 4.829 0.412)
        (xy 4.841 0.433)
        (xy 4.852 0.455)
        (xy 4.86 0.476)
        (xy 4.868 0.497)
        (xy 4.874 0.521)
        (xy 4.879 0.543)
        (xy 4.884 0.565)
        (xy 4.887 0.588)
        (xy 4.889 0.612)
        (xy 4.889 0.635)
        (xy 4.889 0.659)
        (xy 4.887 0.683)
        (xy 4.884 0.705)
        (xy 4.879 0.728)
        (xy 4.874 0.75)
        (xy 4.868 0.774)
        (xy 4.86 0.795)
        (xy 4.852 0.816)
        (xy 4.841 0.837)
        (xy 4.829 0.858)
        (xy 4.817 0.877)
        (xy 4.804 0.898)
        (xy 4.791 0.916)
        (xy 4.775 0.934)
        (xy 4.759 0.95)
        (xy 4.743 0.966)
        (xy 4.724 0.981)
        (xy 4.706 0.995)
        (xy 4.687 1.008)
        (xy 4.668 1.02)
        (xy 4.647 1.031)
        (xy 4.626 1.043)
        (xy 4.603 1.051)
        (xy 4.583 1.059)
        (xy 4.559 1.065)
        (xy 4.538 1.071)
        (xy 4.514 1.075)
        (xy 4.491 1.079)
        (xy 4.467 1.079)
        (xy 4.445 1.081)
        (xy 4.421 1.079)
        (xy 4.397 1.079)
        (xy 4.373 1.075)
        (xy 4.35 1.071)
        (xy 4.328 1.065)
        (xy 4.307 1.059)
        (xy 4.285 1.051)
        (xy 4.262 1.043)
        (xy 4.241 1.033)
        (xy 4.222 1.021)
        (xy 4.201 1.008)
        (xy 4.182 0.995)
        (xy 4.163 0.981)
        (xy 4.147 0.966)
        (xy 4.129 0.95)
        (xy 4.113 0.934)
        (xy 4.099 0.917)
        (xy 4.084 0.898)
        (xy 4.071 0.878)
        (xy 4.059 0.858)
        (xy 4.047 0.838)
        (xy 4.038 0.817)
        (xy 4.028 0.796)
        (xy 4.022 0.774)
        (xy 4.014 0.751)
        (xy 4.009 0.729)
        (xy 4.004 0.706)
        (xy 4.001 0.684)
        (xy 4.001 0.66)
        (xy 3.999 0.637)
        (xy 4.445 0.637)
        (xy 4.445 0.632)
        (xy 4.445 0.633)
      )

      (stroke (width 0.001) (type solid)) (fill solid) (layer "B.Paste"))
    (fp_poly
      (pts
        (xy 5.714 -4.447)
        (xy 5.269 -4.446)
        (xy 5.27 -4.469)
        (xy 5.272 -4.493)
        (xy 5.275 -4.515)
        (xy 5.28 -4.538)
        (xy 5.285 -4.56)
        (xy 5.291 -4.583)
        (xy 5.299 -4.605)
        (xy 5.307 -4.626)
        (xy 5.317 -4.647)
        (xy 5.328 -4.668)
        (xy 5.341 -4.687)
        (xy 5.355 -4.706)
        (xy 5.368 -4.725)
        (xy 5.384 -4.743)
        (xy 5.4 -4.759)
        (xy 5.416 -4.775)
        (xy 5.434 -4.791)
        (xy 5.453 -4.804)
        (xy 5.472 -4.817)
        (xy 5.491 -4.831)
        (xy 5.511 -4.841)
        (xy 5.533 -4.852)
        (xy 5.554 -4.86)
        (xy 5.576 -4.868)
        (xy 5.599 -4.874)
        (xy 5.621 -4.879)
        (xy 5.644 -4.884)
        (xy 5.666 -4.887)
        (xy 5.69 -4.889)
        (xy 5.714 -4.889)
        (xy 5.738 -4.889)
        (xy 5.761 -4.887)
        (xy 5.785 -4.884)
        (xy 5.807 -4.879)
        (xy 5.829 -4.874)
        (xy 5.852 -4.868)
        (xy 5.873 -4.86)
        (xy 5.895 -4.852)
        (xy 5.916 -4.841)
        (xy 5.937 -4.829)
        (xy 5.956 -4.817)
        (xy 5.977 -4.804)
        (xy 5.994 -4.791)
        (xy 6.012 -4.775)
        (xy 6.03 -4.759)
        (xy 6.046 -4.743)
        (xy 6.06 -4.724)
        (xy 6.075 -4.706)
        (xy 6.087 -4.687)
        (xy 6.099 -4.668)
        (xy 6.11 -4.647)
        (xy 6.121 -4.626)
        (xy 6.129 -4.603)
        (xy 6.137 -4.583)
        (xy 6.144 -4.559)
        (xy 6.15 -4.538)
        (xy 6.155 -4.514)
        (xy 6.158 -4.491)
        (xy 6.158 -4.467)
        (xy 6.16 -4.445)
        (xy 6.158 -4.421)
        (xy 6.158 -4.397)
        (xy 6.155 -4.374)
        (xy 6.15 -4.352)
        (xy 6.144 -4.329)
        (xy 6.137 -4.307)
        (xy 6.129 -4.285)
        (xy 6.121 -4.264)
        (xy 6.11 -4.243)
        (xy 6.099 -4.222)
        (xy 6.087 -4.203)
        (xy 6.075 -4.182)
        (xy 6.06 -4.164)
        (xy 6.046 -4.147)
        (xy 6.03 -4.129)
        (xy 6.012 -4.113)
        (xy 5.994 -4.099)
        (xy 5.977 -4.084)
        (xy 5.956 -4.071)
        (xy 5.937 -4.059)
        (xy 5.916 -4.049)
        (xy 5.895 -4.038)
        (xy 5.873 -4.03)
        (xy 5.852 -4.022)
        (xy 5.829 -4.014)
        (xy 5.807 -4.009)
        (xy 5.785 -4.004)
        (xy 5.761 -4.001)
        (xy 5.738 -4.001)
        (xy 5.714 -3.999)
        (xy 5.69 -4.001)
        (xy 5.666 -4.001)
        (xy 5.644 -4.004)
        (xy 5.621 -4.009)
        (xy 5.599 -4.014)
        (xy 5.576 -4.022)
        (xy 5.554 -4.028)
        (xy 5.533 -4.038)
        (xy 5.511 -4.047)
        (xy 5.491 -4.059)
        (xy 5.472 -4.071)
        (xy 5.453 -4.084)
        (xy 5.434 -4.099)
        (xy 5.416 -4.113)
        (xy 5.4 -4.129)
        (xy 5.384 -4.147)
        (xy 5.368 -4.163)
        (xy 5.355 -4.182)
        (xy 5.341 -4.201)
        (xy 5.328 -4.222)
        (xy 5.317 -4.241)
        (xy 5.307 -4.262)
        (xy 5.299 -4.285)
        (xy 5.291 -4.307)
        (xy 5.285 -4.328)
        (xy 5.28 -4.35)
        (xy 5.275 -4.373)
        (xy 5.272 -4.397)
        (xy 5.27 -4.421)
        (xy 5.269 -4.442)
        (xy 5.714 -4.442)
        (xy 5.714 -4.446)
        (xy 5.714 -4.447)
      )

      (stroke (width 0.001) (type solid)) (fill solid) (layer "B.Paste"))
    (fp_poly
      (pts
        (xy 5.714 -1.907)
        (xy 5.269 -1.906)
        (xy 5.27 -1.929)
        (xy 5.272 -1.953)
        (xy 5.275 -1.975)
        (xy 5.28 -1.999)
        (xy 5.285 -2.02)
        (xy 5.291 -2.043)
        (xy 5.299 -2.064)
        (xy 5.307 -2.087)
        (xy 5.317 -2.108)
        (xy 5.328 -2.128)
        (xy 5.341 -2.148)
        (xy 5.355 -2.166)
        (xy 5.368 -2.185)
        (xy 5.384 -2.202)
        (xy 5.4 -2.22)
        (xy 5.416 -2.236)
        (xy 5.434 -2.25)
        (xy 5.453 -2.265)
        (xy 5.472 -2.277)
        (xy 5.491 -2.29)
        (xy 5.511 -2.301)
        (xy 5.533 -2.311)
        (xy 5.554 -2.321)
        (xy 5.576 -2.327)
        (xy 5.599 -2.334)
        (xy 5.621 -2.339)
        (xy 5.644 -2.345)
        (xy 5.666 -2.347)
        (xy 5.69 -2.349)
        (xy 5.714 -2.35)
        (xy 5.738 -2.349)
        (xy 5.761 -2.347)
        (xy 5.785 -2.345)
        (xy 5.807 -2.339)
        (xy 5.829 -2.334)
        (xy 5.852 -2.327)
        (xy 5.873 -2.319)
        (xy 5.895 -2.311)
        (xy 5.916 -2.301)
        (xy 5.937 -2.289)
        (xy 5.956 -2.277)
        (xy 5.977 -2.265)
        (xy 5.994 -2.25)
        (xy 6.012 -2.236)
        (xy 6.03 -2.22)
        (xy 6.046 -2.202)
        (xy 6.06 -2.185)
        (xy 6.075 -2.166)
        (xy 6.087 -2.146)
        (xy 6.099 -2.126)
        (xy 6.11 -2.107)
        (xy 6.121 -2.085)
        (xy 6.129 -2.064)
        (xy 6.137 -2.043)
        (xy 6.144 -2.019)
        (xy 6.15 -1.997)
        (xy 6.155 -1.975)
        (xy 6.158 -1.951)
        (xy 6.158 -1.927)
        (xy 6.16 -1.904)
        (xy 6.158 -1.881)
        (xy 6.158 -1.858)
        (xy 6.155 -1.834)
        (xy 6.15 -1.812)
        (xy 6.144 -1.789)
        (xy 6.137 -1.766)
        (xy 6.129 -1.745)
        (xy 6.121 -1.723)
        (xy 6.11 -1.703)
        (xy 6.099 -1.683)
        (xy 6.087 -1.662)
        (xy 6.075 -1.642)
        (xy 6.06 -1.624)
        (xy 6.046 -1.606)
        (xy 6.03 -1.59)
        (xy 6.012 -1.574)
        (xy 5.994 -1.558)
        (xy 5.977 -1.544)
        (xy 5.956 -1.531)
        (xy 5.937 -1.519)
        (xy 5.916 -1.508)
        (xy 5.895 -1.497)
        (xy 5.873 -1.489)
        (xy 5.852 -1.481)
        (xy 5.829 -1.475)
        (xy 5.807 -1.469)
        (xy 5.785 -1.465)
        (xy 5.761 -1.461)
        (xy 5.738 -1.461)
        (xy 5.714 -1.459)
        (xy 5.69 -1.461)
        (xy 5.666 -1.461)
        (xy 5.644 -1.465)
        (xy 5.621 -1.469)
        (xy 5.599 -1.475)
        (xy 5.576 -1.481)
        (xy 5.554 -1.489)
        (xy 5.533 -1.497)
        (xy 5.511 -1.507)
        (xy 5.491 -1.518)
        (xy 5.472 -1.531)
        (xy 5.453 -1.544)
        (xy 5.434 -1.558)
        (xy 5.416 -1.574)
        (xy 5.4 -1.59)
        (xy 5.384 -1.606)
        (xy 5.368 -1.624)
        (xy 5.355 -1.642)
        (xy 5.341 -1.661)
        (xy 5.328 -1.681)
        (xy 5.317 -1.701)
        (xy 5.307 -1.723)
        (xy 5.299 -1.745)
        (xy 5.291 -1.766)
        (xy 5.285 -1.788)
        (xy 5.28 -1.81)
        (xy 5.275 -1.834)
        (xy 5.272 -1.856)
        (xy 5.27 -1.88)
        (xy 5.269 -1.902)
        (xy 5.714 -1.902)
        (xy 5.714 -1.906)
        (xy 5.714 -1.907)
      )

      (stroke (width 0.001) (type solid)) (fill solid) (layer "B.Paste"))
    (fp_poly
      (pts
        (xy 5.714 -0.637)
        (xy 5.269 -0.636)
        (xy 5.27 -0.659)
        (xy 5.272 -0.683)
        (xy 5.275 -0.705)
        (xy 5.28 -0.728)
        (xy 5.285 -0.75)
        (xy 5.291 -0.773)
        (xy 5.299 -0.795)
        (xy 5.307 -0.816)
        (xy 5.317 -0.837)
        (xy 5.328 -0.857)
        (xy 5.341 -0.877)
        (xy 5.355 -0.897)
        (xy 5.368 -0.916)
        (xy 5.384 -0.933)
        (xy 5.4 -0.949)
        (xy 5.416 -0.965)
        (xy 5.434 -0.98)
        (xy 5.453 -0.994)
        (xy 5.472 -1.007)
        (xy 5.491 -1.02)
        (xy 5.511 -1.032)
        (xy 5.533 -1.042)
        (xy 5.554 -1.05)
        (xy 5.576 -1.058)
        (xy 5.599 -1.064)
        (xy 5.621 -1.07)
        (xy 5.644 -1.074)
        (xy 5.666 -1.078)
        (xy 5.69 -1.078)
        (xy 5.714 -1.08)
        (xy 5.738 -1.078)
        (xy 5.761 -1.078)
        (xy 5.785 -1.074)
        (xy 5.807 -1.07)
        (xy 5.829 -1.064)
        (xy 5.852 -1.058)
        (xy 5.873 -1.05)
        (xy 5.895 -1.042)
        (xy 5.916 -1.03)
        (xy 5.937 -1.019)
        (xy 5.956 -1.007)
        (xy 5.977 -0.994)
        (xy 5.994 -0.98)
        (xy 6.012 -0.965)
        (xy 6.03 -0.949)
        (xy 6.046 -0.933)
        (xy 6.06 -0.915)
        (xy 6.075 -0.897)
        (xy 6.087 -0.876)
        (xy 6.099 -0.856)
        (xy 6.11 -0.836)
        (xy 6.121 -0.815)
        (xy 6.129 -0.794)
        (xy 6.137 -0.773)
        (xy 6.144 -0.749)
        (xy 6.15 -0.727)
        (xy 6.155 -0.704)
        (xy 6.158 -0.682)
        (xy 6.158 -0.658)
        (xy 6.16 -0.634)
        (xy 6.158 -0.611)
        (xy 6.158 -0.587)
        (xy 6.155 -0.564)
        (xy 6.15 -0.542)
        (xy 6.144 -0.52)
        (xy 6.137 -0.496)
        (xy 6.129 -0.475)
        (xy 6.121 -0.454)
        (xy 6.11 -0.432)
        (xy 6.099 -0.412)
        (xy 6.087 -0.393)
        (xy 6.075 -0.372)
        (xy 6.06 -0.354)
        (xy 6.046 -0.337)
        (xy 6.03 -0.32)
        (xy 6.012 -0.303)
        (xy 5.994 -0.288)
        (xy 5.977 -0.275)
        (xy 5.956 -0.262)
        (xy 5.937 -0.249)
        (xy 5.916 -0.238)
        (xy 5.895 -0.228)
        (xy 5.873 -0.219)
        (xy 5.852 -0.211)
        (xy 5.829 -0.204)
        (xy 5.807 -0.2)
        (xy 5.785 -0.195)
        (xy 5.761 -0.192)
        (xy 5.738 -0.19)
        (xy 5.714 -0.189)
        (xy 5.69 -0.19)
        (xy 5.666 -0.192)
        (xy 5.644 -0.195)
        (xy 5.621 -0.2)
        (xy 5.599 -0.204)
        (xy 5.576 -0.211)
        (xy 5.554 -0.218)
        (xy 5.533 -0.228)
        (xy 5.511 -0.237)
        (xy 5.491 -0.248)
        (xy 5.472 -0.262)
        (xy 5.453 -0.275)
        (xy 5.434 -0.288)
        (xy 5.416 -0.303)
        (xy 5.4 -0.32)
        (xy 5.384 -0.337)
        (xy 5.368 -0.353)
        (xy 5.355 -0.372)
        (xy 5.341 -0.392)
        (xy 5.328 -0.411)
        (xy 5.317 -0.431)
        (xy 5.307 -0.453)
        (xy 5.299 -0.474)
        (xy 5.291 -0.496)
        (xy 5.285 -0.519)
        (xy 5.28 -0.541)
        (xy 5.275 -0.563)
        (xy 5.272 -0.586)
        (xy 5.27 -0.61)
        (xy 5.269 -0.631)
        (xy 5.714 -0.631)
        (xy 5.714 -0.636)
        (xy 5.714 -0.637)
      )

      (stroke (width 0.001) (type solid)) (fill solid) (layer "B.Paste"))
    (fp_poly
      (pts
        (xy 5.714 0.633)
        (xy 5.269 0.632)
        (xy 5.27 0.611)
        (xy 5.272 0.587)
        (xy 5.275 0.564)
        (xy 5.28 0.542)
        (xy 5.285 0.52)
        (xy 5.291 0.497)
        (xy 5.299 0.475)
        (xy 5.307 0.454)
        (xy 5.317 0.432)
        (xy 5.328 0.412)
        (xy 5.341 0.393)
        (xy 5.355 0.373)
        (xy 5.368 0.354)
        (xy 5.384 0.338)
        (xy 5.4 0.32)
        (xy 5.416 0.304)
        (xy 5.434 0.289)
        (xy 5.453 0.276)
        (xy 5.472 0.263)
        (xy 5.491 0.249)
        (xy 5.511 0.238)
        (xy 5.533 0.229)
        (xy 5.554 0.219)
        (xy 5.576 0.212)
        (xy 5.599 0.205)
        (xy 5.621 0.201)
        (xy 5.644 0.196)
        (xy 5.666 0.192)
        (xy 5.69 0.191)
        (xy 5.714 0.19)
        (xy 5.738 0.191)
        (xy 5.761 0.192)
        (xy 5.785 0.196)
        (xy 5.807 0.201)
        (xy 5.829 0.205)
        (xy 5.852 0.212)
        (xy 5.873 0.22)
        (xy 5.895 0.229)
        (xy 5.916 0.239)
        (xy 5.937 0.25)
        (xy 5.956 0.263)
        (xy 5.977 0.276)
        (xy 5.994 0.289)
        (xy 6.012 0.304)
        (xy 6.03 0.32)
        (xy 6.046 0.338)
        (xy 6.06 0.355)
        (xy 6.075 0.373)
        (xy 6.087 0.394)
        (xy 6.099 0.413)
        (xy 6.11 0.433)
        (xy 6.121 0.455)
        (xy 6.129 0.476)
        (xy 6.137 0.497)
        (xy 6.144 0.521)
        (xy 6.15 0.543)
        (xy 6.155 0.565)
        (xy 6.158 0.588)
        (xy 6.158 0.612)
        (xy 6.16 0.635)
        (xy 6.158 0.659)
        (xy 6.158 0.683)
        (xy 6.155 0.705)
        (xy 6.15 0.728)
        (xy 6.144 0.75)
        (xy 6.137 0.774)
        (xy 6.129 0.795)
        (xy 6.121 0.816)
        (xy 6.11 0.837)
        (xy 6.099 0.857)
        (xy 6.087 0.877)
        (xy 6.075 0.898)
        (xy 6.06 0.916)
        (xy 6.046 0.934)
        (xy 6.03 0.95)
        (xy 6.012 0.966)
        (xy 5.994 0.981)
        (xy 5.977 0.995)
        (xy 5.956 1.008)
        (xy 5.937 1.02)
        (xy 5.916 1.031)
        (xy 5.895 1.043)
        (xy 5.873 1.051)
        (xy 5.852 1.059)
        (xy 5.829 1.065)
        (xy 5.807 1.071)
        (xy 5.785 1.075)
        (xy 5.761 1.079)
        (xy 5.738 1.079)
        (xy 5.714 1.081)
        (xy 5.69 1.079)
        (xy 5.666 1.079)
        (xy 5.644 1.075)
        (xy 5.621 1.071)
        (xy 5.599 1.065)
        (xy 5.576 1.059)
        (xy 5.554 1.051)
        (xy 5.533 1.043)
        (xy 5.511 1.033)
        (xy 5.491 1.021)
        (xy 5.472 1.008)
        (xy 5.453 0.995)
        (xy 5.434 0.981)
        (xy 5.416 0.966)
        (xy 5.4 0.95)
        (xy 5.384 0.934)
        (xy 5.368 0.917)
        (xy 5.355 0.898)
        (xy 5.341 0.878)
        (xy 5.328 0.858)
        (xy 5.317 0.838)
        (xy 5.307 0.817)
        (xy 5.299 0.796)
        (xy 5.291 0.774)
        (xy 5.285 0.751)
        (xy 5.28 0.729)
        (xy 5.275 0.706)
        (xy 5.272 0.684)
        (xy 5.27 0.66)
        (xy 5.269 0.637)
        (xy 5.714 0.637)
        (xy 5.714 0.632)
        (xy 5.714 0.633)
      )

      (stroke (width 0.001) (type solid)) (fill solid) (layer "B.Paste"))
    (fp_poly
      (pts
        (xy 6.985 -4.447)
        (xy 6.539 -4.446)
        (xy 6.541 -4.469)
        (xy 6.541 -4.493)
        (xy 6.544 -4.515)
        (xy 6.549 -4.538)
        (xy 6.554 -4.56)
        (xy 6.562 -4.583)
        (xy 6.568 -4.605)
        (xy 6.578 -4.626)
        (xy 6.587 -4.647)
        (xy 6.599 -4.668)
        (xy 6.611 -4.687)
        (xy 6.624 -4.706)
        (xy 6.639 -4.725)
        (xy 6.653 -4.743)
        (xy 6.669 -4.759)
        (xy 6.687 -4.775)
        (xy 6.703 -4.791)
        (xy 6.722 -4.804)
        (xy 6.741 -4.817)
        (xy 6.761 -4.831)
        (xy 6.781 -4.841)
        (xy 6.802 -4.852)
        (xy 6.825 -4.86)
        (xy 6.847 -4.868)
        (xy 6.868 -4.874)
        (xy 6.89 -4.879)
        (xy 6.913 -4.884)
        (xy 6.937 -4.887)
        (xy 6.961 -4.889)
        (xy 6.985 -4.889)
        (xy 7.007 -4.889)
        (xy 7.031 -4.887)
        (xy 7.054 -4.884)
        (xy 7.078 -4.879)
        (xy 7.099 -4.874)
        (xy 7.123 -4.868)
        (xy 7.143 -4.86)
        (xy 7.166 -4.852)
        (xy 7.187 -4.841)
        (xy 7.206 -4.829)
        (xy 7.227 -4.817)
        (xy 7.246 -4.804)
        (xy 7.264 -4.791)
        (xy 7.283 -4.775)
        (xy 7.299 -4.759)
        (xy 7.315 -4.743)
        (xy 7.331 -4.724)
        (xy 7.344 -4.706)
        (xy 7.357 -4.687)
        (xy 7.369 -4.668)
        (xy 7.381 -4.647)
        (xy 7.392 -4.626)
        (xy 7.4 -4.603)
        (xy 7.408 -4.583)
        (xy 7.414 -4.559)
        (xy 7.419 -4.538)
        (xy 7.424 -4.514)
        (xy 7.427 -4.491)
        (xy 7.429 -4.467)
        (xy 7.429 -4.445)
        (xy 7.429 -4.421)
        (xy 7.427 -4.397)
        (xy 7.424 -4.374)
        (xy 7.419 -4.352)
        (xy 7.414 -4.329)
        (xy 7.408 -4.307)
        (xy 7.4 -4.285)
        (xy 7.392 -4.264)
        (xy 7.381 -4.243)
        (xy 7.369 -4.222)
        (xy 7.357 -4.203)
        (xy 7.344 -4.182)
        (xy 7.331 -4.164)
        (xy 7.315 -4.147)
        (xy 7.299 -4.129)
        (xy 7.283 -4.113)
        (xy 7.264 -4.099)
        (xy 7.246 -4.084)
        (xy 7.227 -4.071)
        (xy 7.206 -4.059)
        (xy 7.187 -4.049)
        (xy 7.166 -4.038)
        (xy 7.143 -4.03)
        (xy 7.123 -4.022)
        (xy 7.099 -4.014)
        (xy 7.078 -4.009)
        (xy 7.054 -4.004)
        (xy 7.031 -4.001)
        (xy 7.007 -4.001)
        (xy 6.985 -3.999)
        (xy 6.961 -4.001)
        (xy 6.937 -4.001)
        (xy 6.913 -4.004)
        (xy 6.89 -4.009)
        (xy 6.868 -4.014)
        (xy 6.847 -4.022)
        (xy 6.825 -4.028)
        (xy 6.802 -4.038)
        (xy 6.781 -4.047)
        (xy 6.761 -4.059)
        (xy 6.741 -4.071)
        (xy 6.722 -4.084)
        (xy 6.703 -4.099)
        (xy 6.687 -4.113)
        (xy 6.669 -4.129)
        (xy 6.653 -4.147)
        (xy 6.639 -4.163)
        (xy 6.624 -4.182)
        (xy 6.611 -4.201)
        (xy 6.599 -4.222)
        (xy 6.587 -4.241)
        (xy 6.578 -4.262)
        (xy 6.568 -4.285)
        (xy 6.562 -4.307)
        (xy 6.554 -4.328)
        (xy 6.549 -4.35)
        (xy 6.544 -4.373)
        (xy 6.541 -4.397)
        (xy 6.541 -4.421)
        (xy 6.539 -4.442)
        (xy 6.985 -4.442)
        (xy 6.985 -4.446)
        (xy 6.985 -4.447)
      )

      (stroke (width 0.001) (type solid)) (fill solid) (layer "B.Paste"))
    (fp_poly
      (pts
        (xy 6.985 -1.907)
        (xy 6.539 -1.906)
        (xy 6.541 -1.929)
        (xy 6.541 -1.953)
        (xy 6.544 -1.975)
        (xy 6.549 -1.999)
        (xy 6.554 -2.02)
        (xy 6.562 -2.043)
        (xy 6.568 -2.064)
        (xy 6.578 -2.087)
        (xy 6.587 -2.108)
        (xy 6.599 -2.128)
        (xy 6.611 -2.148)
        (xy 6.624 -2.166)
        (xy 6.639 -2.185)
        (xy 6.653 -2.202)
        (xy 6.669 -2.22)
        (xy 6.687 -2.236)
        (xy 6.703 -2.25)
        (xy 6.722 -2.265)
        (xy 6.741 -2.277)
        (xy 6.761 -2.29)
        (xy 6.781 -2.301)
        (xy 6.802 -2.311)
        (xy 6.825 -2.321)
        (xy 6.847 -2.327)
        (xy 6.868 -2.334)
        (xy 6.89 -2.339)
        (xy 6.913 -2.345)
        (xy 6.937 -2.347)
        (xy 6.961 -2.349)
        (xy 6.985 -2.35)
        (xy 7.007 -2.349)
        (xy 7.031 -2.347)
        (xy 7.054 -2.345)
        (xy 7.078 -2.339)
        (xy 7.099 -2.334)
        (xy 7.123 -2.327)
        (xy 7.143 -2.319)
        (xy 7.166 -2.311)
        (xy 7.187 -2.301)
        (xy 7.206 -2.289)
        (xy 7.227 -2.277)
        (xy 7.246 -2.265)
        (xy 7.264 -2.25)
        (xy 7.283 -2.236)
        (xy 7.299 -2.22)
        (xy 7.315 -2.202)
        (xy 7.331 -2.185)
        (xy 7.344 -2.166)
        (xy 7.357 -2.146)
        (xy 7.369 -2.126)
        (xy 7.381 -2.107)
        (xy 7.392 -2.085)
        (xy 7.4 -2.064)
        (xy 7.408 -2.043)
        (xy 7.414 -2.019)
        (xy 7.419 -1.997)
        (xy 7.424 -1.975)
        (xy 7.427 -1.951)
        (xy 7.429 -1.927)
        (xy 7.429 -1.904)
        (xy 7.429 -1.881)
        (xy 7.427 -1.858)
        (xy 7.424 -1.834)
        (xy 7.419 -1.812)
        (xy 7.414 -1.789)
        (xy 7.408 -1.766)
        (xy 7.4 -1.745)
        (xy 7.392 -1.723)
        (xy 7.381 -1.703)
        (xy 7.369 -1.681)
        (xy 7.357 -1.662)
        (xy 7.344 -1.642)
        (xy 7.331 -1.624)
        (xy 7.315 -1.606)
        (xy 7.299 -1.59)
        (xy 7.283 -1.574)
        (xy 7.264 -1.558)
        (xy 7.246 -1.544)
        (xy 7.227 -1.531)
        (xy 7.206 -1.519)
        (xy 7.187 -1.508)
        (xy 7.166 -1.497)
        (xy 7.143 -1.489)
        (xy 7.123 -1.481)
        (xy 7.099 -1.475)
        (xy 7.078 -1.469)
        (xy 7.054 -1.465)
        (xy 7.031 -1.461)
        (xy 7.007 -1.461)
        (xy 6.985 -1.459)
        (xy 6.961 -1.461)
        (xy 6.937 -1.461)
        (xy 6.913 -1.465)
        (xy 6.89 -1.469)
        (xy 6.868 -1.475)
        (xy 6.847 -1.481)
        (xy 6.825 -1.489)
        (xy 6.802 -1.497)
        (xy 6.781 -1.507)
        (xy 6.761 -1.518)
        (xy 6.741 -1.531)
        (xy 6.722 -1.544)
        (xy 6.703 -1.558)
        (xy 6.687 -1.574)
        (xy 6.669 -1.59)
        (xy 6.653 -1.606)
        (xy 6.639 -1.624)
        (xy 6.624 -1.642)
        (xy 6.611 -1.661)
        (xy 6.599 -1.681)
        (xy 6.587 -1.701)
        (xy 6.578 -1.723)
        (xy 6.568 -1.745)
        (xy 6.562 -1.766)
        (xy 6.554 -1.788)
        (xy 6.549 -1.81)
        (xy 6.544 -1.834)
        (xy 6.541 -1.856)
        (xy 6.541 -1.88)
        (xy 6.539 -1.902)
        (xy 6.985 -1.902)
        (xy 6.985 -1.906)
        (xy 6.985 -1.907)
      )

      (stroke (width 0.001) (type solid)) (fill solid) (layer "B.Paste"))
    (fp_poly
      (pts
        (xy 6.985 -0.637)
        (xy 6.539 -0.636)
        (xy 6.541 -0.659)
        (xy 6.541 -0.683)
        (xy 6.544 -0.705)
        (xy 6.549 -0.728)
        (xy 6.554 -0.75)
        (xy 6.562 -0.773)
        (xy 6.568 -0.795)
        (xy 6.578 -0.816)
        (xy 6.587 -0.837)
        (xy 6.599 -0.857)
        (xy 6.611 -0.877)
        (xy 6.624 -0.897)
        (xy 6.639 -0.916)
        (xy 6.653 -0.933)
        (xy 6.669 -0.949)
        (xy 6.687 -0.965)
        (xy 6.703 -0.98)
        (xy 6.722 -0.994)
        (xy 6.741 -1.007)
        (xy 6.761 -1.02)
        (xy 6.781 -1.032)
        (xy 6.802 -1.042)
        (xy 6.825 -1.05)
        (xy 6.847 -1.058)
        (xy 6.868 -1.064)
        (xy 6.89 -1.07)
        (xy 6.913 -1.074)
        (xy 6.937 -1.078)
        (xy 6.961 -1.078)
        (xy 6.985 -1.08)
        (xy 7.007 -1.078)
        (xy 7.031 -1.078)
        (xy 7.054 -1.074)
        (xy 7.078 -1.07)
        (xy 7.099 -1.064)
        (xy 7.123 -1.058)
        (xy 7.143 -1.05)
        (xy 7.166 -1.042)
        (xy 7.187 -1.03)
        (xy 7.206 -1.019)
        (xy 7.227 -1.007)
        (xy 7.246 -0.994)
        (xy 7.264 -0.98)
        (xy 7.283 -0.965)
        (xy 7.299 -0.949)
        (xy 7.315 -0.933)
        (xy 7.331 -0.915)
        (xy 7.344 -0.897)
        (xy 7.357 -0.876)
        (xy 7.369 -0.857)
        (xy 7.381 -0.836)
        (xy 7.392 -0.815)
        (xy 7.4 -0.794)
        (xy 7.408 -0.773)
        (xy 7.414 -0.749)
        (xy 7.419 -0.727)
        (xy 7.424 -0.704)
        (xy 7.427 -0.682)
        (xy 7.429 -0.658)
        (xy 7.429 -0.634)
        (xy 7.429 -0.611)
        (xy 7.427 -0.587)
        (xy 7.424 -0.564)
        (xy 7.419 -0.542)
        (xy 7.414 -0.52)
        (xy 7.408 -0.496)
        (xy 7.4 -0.475)
        (xy 7.392 -0.454)
        (xy 7.381 -0.432)
        (xy 7.369 -0.411)
        (xy 7.357 -0.393)
        (xy 7.344 -0.372)
        (xy 7.331 -0.354)
        (xy 7.315 -0.337)
        (xy 7.299 -0.32)
        (xy 7.283 -0.303)
        (xy 7.264 -0.288)
        (xy 7.246 -0.275)
        (xy 7.227 -0.262)
        (xy 7.206 -0.249)
        (xy 7.187 -0.238)
        (xy 7.166 -0.228)
        (xy 7.143 -0.219)
        (xy 7.123 -0.211)
        (xy 7.099 -0.204)
        (xy 7.078 -0.2)
        (xy 7.054 -0.195)
        (xy 7.031 -0.192)
        (xy 7.007 -0.19)
        (xy 6.985 -0.189)
        (xy 6.961 -0.19)
        (xy 6.937 -0.192)
        (xy 6.913 -0.195)
        (xy 6.89 -0.2)
        (xy 6.868 -0.204)
        (xy 6.847 -0.211)
        (xy 6.825 -0.218)
        (xy 6.802 -0.228)
        (xy 6.781 -0.237)
        (xy 6.761 -0.248)
        (xy 6.741 -0.262)
        (xy 6.722 -0.275)
        (xy 6.703 -0.288)
        (xy 6.687 -0.303)
        (xy 6.669 -0.32)
        (xy 6.653 -0.337)
        (xy 6.639 -0.353)
        (xy 6.624 -0.372)
        (xy 6.611 -0.392)
        (xy 6.599 -0.411)
        (xy 6.587 -0.431)
        (xy 6.578 -0.453)
        (xy 6.568 -0.474)
        (xy 6.562 -0.496)
        (xy 6.554 -0.519)
        (xy 6.549 -0.541)
        (xy 6.544 -0.563)
        (xy 6.541 -0.586)
        (xy 6.541 -0.61)
        (xy 6.539 -0.631)
        (xy 6.985 -0.631)
        (xy 6.985 -0.636)
        (xy 6.985 -0.637)
      )

      (stroke (width 0.001) (type solid)) (fill solid) (layer "B.Paste"))
    (fp_poly
      (pts
        (xy 6.985 0.633)
        (xy 6.539 0.632)
        (xy 6.541 0.611)
        (xy 6.541 0.587)
        (xy 6.544 0.564)
        (xy 6.549 0.542)
        (xy 6.554 0.52)
        (xy 6.562 0.497)
        (xy 6.568 0.475)
        (xy 6.578 0.454)
        (xy 6.587 0.432)
        (xy 6.599 0.412)
        (xy 6.611 0.393)
        (xy 6.624 0.373)
        (xy 6.639 0.354)
        (xy 6.653 0.338)
        (xy 6.669 0.32)
        (xy 6.687 0.304)
        (xy 6.703 0.289)
        (xy 6.722 0.276)
        (xy 6.741 0.263)
        (xy 6.761 0.249)
        (xy 6.781 0.238)
        (xy 6.802 0.229)
        (xy 6.825 0.219)
        (xy 6.847 0.212)
        (xy 6.868 0.205)
        (xy 6.89 0.201)
        (xy 6.913 0.196)
        (xy 6.937 0.192)
        (xy 6.961 0.191)
        (xy 6.985 0.19)
        (xy 7.007 0.191)
        (xy 7.031 0.192)
        (xy 7.054 0.196)
        (xy 7.078 0.201)
        (xy 7.099 0.205)
        (xy 7.123 0.212)
        (xy 7.143 0.22)
        (xy 7.166 0.229)
        (xy 7.187 0.239)
        (xy 7.206 0.25)
        (xy 7.227 0.263)
        (xy 7.246 0.276)
        (xy 7.264 0.289)
        (xy 7.283 0.304)
        (xy 7.299 0.32)
        (xy 7.315 0.338)
        (xy 7.331 0.355)
        (xy 7.344 0.373)
        (xy 7.357 0.394)
        (xy 7.369 0.412)
        (xy 7.381 0.433)
        (xy 7.392 0.455)
        (xy 7.4 0.476)
        (xy 7.408 0.497)
        (xy 7.414 0.521)
        (xy 7.419 0.543)
        (xy 7.424 0.565)
        (xy 7.427 0.588)
        (xy 7.429 0.612)
        (xy 7.429 0.635)
        (xy 7.429 0.659)
        (xy 7.427 0.683)
        (xy 7.424 0.705)
        (xy 7.419 0.728)
        (xy 7.414 0.75)
        (xy 7.408 0.774)
        (xy 7.4 0.795)
        (xy 7.392 0.816)
        (xy 7.381 0.837)
        (xy 7.369 0.858)
        (xy 7.357 0.877)
        (xy 7.344 0.898)
        (xy 7.331 0.916)
        (xy 7.315 0.934)
        (xy 7.299 0.95)
        (xy 7.283 0.966)
        (xy 7.264 0.981)
        (xy 7.246 0.995)
        (xy 7.227 1.008)
        (xy 7.206 1.02)
        (xy 7.187 1.031)
        (xy 7.166 1.043)
        (xy 7.143 1.051)
        (xy 7.123 1.059)
        (xy 7.099 1.065)
        (xy 7.078 1.071)
        (xy 7.054 1.075)
        (xy 7.031 1.079)
        (xy 7.007 1.079)
        (xy 6.985 1.081)
        (xy 6.961 1.079)
        (xy 6.937 1.079)
        (xy 6.913 1.075)
        (xy 6.89 1.071)
        (xy 6.868 1.065)
        (xy 6.847 1.059)
        (xy 6.825 1.051)
        (xy 6.802 1.043)
        (xy 6.781 1.033)
        (xy 6.761 1.021)
        (xy 6.741 1.008)
        (xy 6.722 0.995)
        (xy 6.703 0.981)
        (xy 6.687 0.966)
        (xy 6.669 0.95)
        (xy 6.653 0.934)
        (xy 6.639 0.917)
        (xy 6.624 0.898)
        (xy 6.611 0.878)
        (xy 6.599 0.858)
        (xy 6.587 0.838)
        (xy 6.578 0.817)
        (xy 6.568 0.796)
        (xy 6.562 0.774)
        (xy 6.554 0.751)
        (xy 6.549 0.729)
        (xy 6.544 0.706)
        (xy 6.541 0.684)
        (xy 6.541 0.66)
        (xy 6.539 0.637)
        (xy 6.985 0.637)
        (xy 6.985 0.632)
        (xy 6.985 0.633)
      )

      (stroke (width 0.001) (type solid)) (fill solid) (layer "B.Paste"))
    (fp_poly
      (pts
        (xy 8.255 -4.447)
        (xy 7.809 -4.446)
        (xy 7.81 -4.469)
        (xy 7.812 -4.493)
        (xy 7.815 -4.515)
        (xy 7.82 -4.538)
        (xy 7.825 -4.56)
        (xy 7.831 -4.583)
        (xy 7.839 -4.605)
        (xy 7.847 -4.626)
        (xy 7.857 -4.647)
        (xy 7.868 -4.668)
        (xy 7.881 -4.687)
        (xy 7.894 -4.706)
        (xy 7.908 -4.725)
        (xy 7.924 -4.743)
        (xy 7.94 -4.759)
        (xy 7.956 -4.775)
        (xy 7.974 -4.791)
        (xy 7.993 -4.804)
        (xy 8.012 -4.817)
        (xy 8.031 -4.831)
        (xy 8.051 -4.841)
        (xy 8.073 -4.852)
        (xy 8.095 -4.86)
        (xy 8.117 -4.868)
        (xy 8.138 -4.874)
        (xy 8.16 -4.879)
        (xy 8.183 -4.884)
        (xy 8.207 -4.887)
        (xy 8.23 -4.889)
        (xy 8.255 -4.889)
        (xy 8.278 -4.889)
        (xy 8.301 -4.887)
        (xy 8.324 -4.884)
        (xy 8.348 -4.879)
        (xy 8.369 -4.874)
        (xy 8.393 -4.868)
        (xy 8.413 -4.86)
        (xy 8.435 -4.852)
        (xy 8.457 -4.841)
        (xy 8.477 -4.829)
        (xy 8.496 -4.817)
        (xy 8.516 -4.804)
        (xy 8.534 -4.791)
        (xy 8.553 -4.775)
        (xy 8.57 -4.759)
        (xy 8.586 -4.743)
        (xy 8.601 -4.724)
        (xy 8.615 -4.706)
        (xy 8.627 -4.687)
        (xy 8.64 -4.668)
        (xy 8.65 -4.647)
        (xy 8.662 -4.626)
        (xy 8.669 -4.603)
        (xy 8.678 -4.583)
        (xy 8.685 -4.559)
        (xy 8.689 -4.538)
        (xy 8.695 -4.514)
        (xy 8.698 -4.491)
        (xy 8.698 -4.467)
        (xy 8.699 -4.445)
        (xy 8.698 -4.421)
        (xy 8.698 -4.397)
        (xy 8.695 -4.374)
        (xy 8.689 -4.352)
        (xy 8.685 -4.329)
        (xy 8.678 -4.307)
        (xy 8.669 -4.285)
        (xy 8.662 -4.264)
        (xy 8.65 -4.243)
        (xy 8.64 -4.222)
        (xy 8.627 -4.203)
        (xy 8.615 -4.182)
        (xy 8.601 -4.164)
        (xy 8.586 -4.147)
        (xy 8.57 -4.129)
        (xy 8.553 -4.113)
        (xy 8.534 -4.099)
        (xy 8.516 -4.084)
        (xy 8.496 -4.071)
        (xy 8.477 -4.059)
        (xy 8.457 -4.049)
        (xy 8.435 -4.038)
        (xy 8.413 -4.03)
        (xy 8.393 -4.022)
        (xy 8.369 -4.014)
        (xy 8.348 -4.009)
        (xy 8.324 -4.004)
        (xy 8.301 -4.001)
        (xy 8.278 -4.001)
        (xy 8.255 -3.999)
        (xy 8.23 -4.001)
        (xy 8.207 -4.001)
        (xy 8.183 -4.004)
        (xy 8.16 -4.009)
        (xy 8.138 -4.014)
        (xy 8.117 -4.022)
        (xy 8.095 -4.028)
        (xy 8.073 -4.038)
        (xy 8.051 -4.047)
        (xy 8.031 -4.059)
        (xy 8.012 -4.071)
        (xy 7.993 -4.084)
        (xy 7.974 -4.099)
        (xy 7.956 -4.113)
        (xy 7.94 -4.129)
        (xy 7.924 -4.147)
        (xy 7.908 -4.163)
        (xy 7.894 -4.182)
        (xy 7.881 -4.201)
        (xy 7.868 -4.222)
        (xy 7.857 -4.241)
        (xy 7.847 -4.262)
        (xy 7.839 -4.285)
        (xy 7.831 -4.307)
        (xy 7.825 -4.328)
        (xy 7.82 -4.35)
        (xy 7.815 -4.373)
        (xy 7.812 -4.397)
        (xy 7.81 -4.421)
        (xy 7.809 -4.442)
        (xy 8.255 -4.442)
        (xy 8.255 -4.446)
        (xy 8.255 -4.447)
      )

      (stroke (width 0.001) (type solid)) (fill solid) (layer "B.Paste"))
    (fp_poly
      (pts
        (xy 8.255 -1.907)
        (xy 7.809 -1.906)
        (xy 7.81 -1.929)
        (xy 7.812 -1.953)
        (xy 7.815 -1.975)
        (xy 7.82 -1.999)
        (xy 7.825 -2.02)
        (xy 7.831 -2.043)
        (xy 7.839 -2.064)
        (xy 7.847 -2.087)
        (xy 7.857 -2.108)
        (xy 7.868 -2.128)
        (xy 7.881 -2.148)
        (xy 7.894 -2.166)
        (xy 7.908 -2.185)
        (xy 7.924 -2.202)
        (xy 7.94 -2.22)
        (xy 7.956 -2.236)
        (xy 7.974 -2.25)
        (xy 7.993 -2.265)
        (xy 8.012 -2.277)
        (xy 8.031 -2.29)
        (xy 8.051 -2.301)
        (xy 8.073 -2.311)
        (xy 8.095 -2.321)
        (xy 8.117 -2.327)
        (xy 8.138 -2.334)
        (xy 8.16 -2.339)
        (xy 8.183 -2.345)
        (xy 8.207 -2.347)
        (xy 8.23 -2.349)
        (xy 8.255 -2.35)
        (xy 8.278 -2.349)
        (xy 8.301 -2.347)
        (xy 8.324 -2.345)
        (xy 8.348 -2.339)
        (xy 8.369 -2.334)
        (xy 8.393 -2.327)
        (xy 8.413 -2.319)
        (xy 8.435 -2.311)
        (xy 8.457 -2.301)
        (xy 8.477 -2.289)
        (xy 8.496 -2.277)
        (xy 8.516 -2.265)
        (xy 8.534 -2.25)
        (xy 8.553 -2.236)
        (xy 8.57 -2.22)
        (xy 8.586 -2.202)
        (xy 8.601 -2.185)
        (xy 8.615 -2.166)
        (xy 8.627 -2.146)
        (xy 8.64 -2.128)
        (xy 8.65 -2.107)
        (xy 8.662 -2.085)
        (xy 8.669 -2.064)
        (xy 8.678 -2.043)
        (xy 8.685 -2.019)
        (xy 8.689 -1.997)
        (xy 8.695 -1.975)
        (xy 8.698 -1.951)
        (xy 8.698 -1.927)
        (xy 8.699 -1.904)
        (xy 8.698 -1.881)
        (xy 8.698 -1.858)
        (xy 8.695 -1.834)
        (xy 8.689 -1.812)
        (xy 8.685 -1.789)
        (xy 8.678 -1.766)
        (xy 8.669 -1.745)
        (xy 8.662 -1.723)
        (xy 8.65 -1.703)
        (xy 8.64 -1.681)
        (xy 8.627 -1.662)
        (xy 8.615 -1.642)
        (xy 8.601 -1.624)
        (xy 8.586 -1.606)
        (xy 8.57 -1.59)
        (xy 8.553 -1.574)
        (xy 8.534 -1.558)
        (xy 8.516 -1.544)
        (xy 8.496 -1.531)
        (xy 8.477 -1.519)
        (xy 8.457 -1.508)
        (xy 8.435 -1.497)
        (xy 8.413 -1.489)
        (xy 8.393 -1.481)
        (xy 8.369 -1.475)
        (xy 8.348 -1.469)
        (xy 8.324 -1.465)
        (xy 8.301 -1.461)
        (xy 8.278 -1.461)
        (xy 8.255 -1.459)
        (xy 8.23 -1.461)
        (xy 8.207 -1.461)
        (xy 8.183 -1.465)
        (xy 8.16 -1.469)
        (xy 8.138 -1.475)
        (xy 8.117 -1.481)
        (xy 8.095 -1.489)
        (xy 8.073 -1.497)
        (xy 8.051 -1.507)
        (xy 8.031 -1.518)
        (xy 8.012 -1.531)
        (xy 7.993 -1.544)
        (xy 7.974 -1.558)
        (xy 7.956 -1.574)
        (xy 7.94 -1.59)
        (xy 7.924 -1.606)
        (xy 7.908 -1.624)
        (xy 7.894 -1.642)
        (xy 7.881 -1.661)
        (xy 7.868 -1.681)
        (xy 7.857 -1.701)
        (xy 7.847 -1.723)
        (xy 7.839 -1.745)
        (xy 7.831 -1.766)
        (xy 7.825 -1.788)
        (xy 7.82 -1.81)
        (xy 7.815 -1.834)
        (xy 7.812 -1.856)
        (xy 7.81 -1.88)
        (xy 7.809 -1.902)
        (xy 8.255 -1.902)
        (xy 8.255 -1.906)
        (xy 8.255 -1.907)
      )

      (stroke (width 0.001) (type solid)) (fill solid) (layer "B.Paste"))
    (fp_poly
      (pts
        (xy 8.255 -0.637)
        (xy 7.809 -0.636)
        (xy 7.81 -0.659)
        (xy 7.812 -0.683)
        (xy 7.815 -0.705)
        (xy 7.82 -0.728)
        (xy 7.825 -0.75)
        (xy 7.831 -0.773)
        (xy 7.839 -0.795)
        (xy 7.847 -0.816)
        (xy 7.857 -0.837)
        (xy 7.868 -0.857)
        (xy 7.881 -0.877)
        (xy 7.894 -0.897)
        (xy 7.908 -0.916)
        (xy 7.924 -0.933)
        (xy 7.94 -0.949)
        (xy 7.956 -0.965)
        (xy 7.974 -0.98)
        (xy 7.993 -0.994)
        (xy 8.012 -1.007)
        (xy 8.031 -1.02)
        (xy 8.051 -1.032)
        (xy 8.073 -1.042)
        (xy 8.095 -1.05)
        (xy 8.117 -1.058)
        (xy 8.138 -1.064)
        (xy 8.16 -1.07)
        (xy 8.183 -1.074)
        (xy 8.207 -1.078)
        (xy 8.23 -1.078)
        (xy 8.255 -1.08)
        (xy 8.278 -1.078)
        (xy 8.301 -1.078)
        (xy 8.324 -1.074)
        (xy 8.348 -1.07)
        (xy 8.369 -1.064)
        (xy 8.393 -1.058)
        (xy 8.413 -1.05)
        (xy 8.435 -1.042)
        (xy 8.457 -1.03)
        (xy 8.477 -1.019)
        (xy 8.496 -1.007)
        (xy 8.516 -0.994)
        (xy 8.534 -0.98)
        (xy 8.553 -0.965)
        (xy 8.57 -0.949)
        (xy 8.586 -0.933)
        (xy 8.601 -0.915)
        (xy 8.615 -0.897)
        (xy 8.627 -0.876)
        (xy 8.64 -0.857)
        (xy 8.65 -0.836)
        (xy 8.662 -0.815)
        (xy 8.669 -0.794)
        (xy 8.678 -0.773)
        (xy 8.685 -0.749)
        (xy 8.689 -0.727)
        (xy 8.695 -0.704)
        (xy 8.698 -0.682)
        (xy 8.698 -0.658)
        (xy 8.699 -0.634)
        (xy 8.698 -0.611)
        (xy 8.698 -0.587)
        (xy 8.695 -0.564)
        (xy 8.689 -0.542)
        (xy 8.685 -0.52)
        (xy 8.678 -0.496)
        (xy 8.669 -0.475)
        (xy 8.662 -0.454)
        (xy 8.65 -0.432)
        (xy 8.64 -0.411)
        (xy 8.627 -0.393)
        (xy 8.615 -0.372)
        (xy 8.601 -0.354)
        (xy 8.586 -0.337)
        (xy 8.57 -0.32)
        (xy 8.553 -0.303)
        (xy 8.534 -0.288)
        (xy 8.516 -0.275)
        (xy 8.496 -0.262)
        (xy 8.477 -0.249)
        (xy 8.457 -0.238)
        (xy 8.435 -0.228)
        (xy 8.413 -0.219)
        (xy 8.393 -0.211)
        (xy 8.369 -0.204)
        (xy 8.348 -0.2)
        (xy 8.324 -0.195)
        (xy 8.301 -0.192)
        (xy 8.278 -0.19)
        (xy 8.255 -0.189)
        (xy 8.23 -0.19)
        (xy 8.207 -0.192)
        (xy 8.183 -0.195)
        (xy 8.16 -0.2)
        (xy 8.138 -0.204)
        (xy 8.117 -0.211)
        (xy 8.095 -0.218)
        (xy 8.073 -0.228)
        (xy 8.051 -0.237)
        (xy 8.031 -0.248)
        (xy 8.012 -0.262)
        (xy 7.993 -0.275)
        (xy 7.974 -0.288)
        (xy 7.956 -0.303)
        (xy 7.94 -0.32)
        (xy 7.924 -0.337)
        (xy 7.908 -0.353)
        (xy 7.894 -0.372)
        (xy 7.881 -0.392)
        (xy 7.868 -0.411)
        (xy 7.857 -0.431)
        (xy 7.847 -0.453)
        (xy 7.839 -0.474)
        (xy 7.831 -0.496)
        (xy 7.825 -0.519)
        (xy 7.82 -0.541)
        (xy 7.815 -0.563)
        (xy 7.812 -0.586)
        (xy 7.81 -0.61)
        (xy 7.809 -0.631)
        (xy 8.255 -0.631)
        (xy 8.255 -0.636)
        (xy 8.255 -0.637)
      )

      (stroke (width 0.001) (type solid)) (fill solid) (layer "B.Paste"))
    (fp_poly
      (pts
        (xy 8.255 0.633)
        (xy 7.809 0.632)
        (xy 7.81 0.611)
        (xy 7.812 0.587)
        (xy 7.815 0.564)
        (xy 7.82 0.542)
        (xy 7.825 0.52)
        (xy 7.831 0.497)
        (xy 7.839 0.475)
        (xy 7.847 0.454)
        (xy 7.857 0.432)
        (xy 7.868 0.412)
        (xy 7.881 0.393)
        (xy 7.894 0.373)
        (xy 7.908 0.354)
        (xy 7.924 0.338)
        (xy 7.94 0.32)
        (xy 7.956 0.304)
        (xy 7.974 0.289)
        (xy 7.993 0.276)
        (xy 8.012 0.263)
        (xy 8.031 0.249)
        (xy 8.051 0.238)
        (xy 8.073 0.229)
        (xy 8.095 0.219)
        (xy 8.117 0.212)
        (xy 8.138 0.205)
        (xy 8.16 0.201)
        (xy 8.183 0.196)
        (xy 8.207 0.192)
        (xy 8.23 0.191)
        (xy 8.255 0.19)
        (xy 8.278 0.191)
        (xy 8.301 0.192)
        (xy 8.324 0.196)
        (xy 8.348 0.201)
        (xy 8.369 0.205)
        (xy 8.393 0.212)
        (xy 8.413 0.22)
        (xy 8.435 0.229)
        (xy 8.457 0.239)
        (xy 8.477 0.25)
        (xy 8.496 0.263)
        (xy 8.516 0.276)
        (xy 8.534 0.289)
        (xy 8.553 0.304)
        (xy 8.57 0.32)
        (xy 8.586 0.338)
        (xy 8.601 0.355)
        (xy 8.615 0.373)
        (xy 8.627 0.394)
        (xy 8.64 0.412)
        (xy 8.65 0.433)
        (xy 8.662 0.455)
        (xy 8.669 0.476)
        (xy 8.678 0.497)
        (xy 8.685 0.521)
        (xy 8.689 0.543)
        (xy 8.695 0.565)
        (xy 8.698 0.588)
        (xy 8.698 0.612)
        (xy 8.699 0.635)
        (xy 8.698 0.659)
        (xy 8.698 0.683)
        (xy 8.695 0.705)
        (xy 8.689 0.728)
        (xy 8.685 0.75)
        (xy 8.678 0.774)
        (xy 8.669 0.795)
        (xy 8.662 0.816)
        (xy 8.65 0.837)
        (xy 8.64 0.858)
        (xy 8.627 0.877)
        (xy 8.615 0.898)
        (xy 8.601 0.916)
        (xy 8.586 0.934)
        (xy 8.57 0.95)
        (xy 8.553 0.966)
        (xy 8.534 0.981)
        (xy 8.516 0.995)
        (xy 8.496 1.008)
        (xy 8.477 1.02)
        (xy 8.457 1.031)
        (xy 8.435 1.043)
        (xy 8.413 1.051)
        (xy 8.393 1.059)
        (xy 8.369 1.065)
        (xy 8.348 1.071)
        (xy 8.324 1.075)
        (xy 8.301 1.079)
        (xy 8.278 1.079)
        (xy 8.255 1.081)
        (xy 8.23 1.079)
        (xy 8.207 1.079)
        (xy 8.183 1.075)
        (xy 8.16 1.071)
        (xy 8.138 1.065)
        (xy 8.117 1.059)
        (xy 8.095 1.051)
        (xy 8.073 1.043)
        (xy 8.051 1.033)
        (xy 8.031 1.021)
        (xy 8.012 1.008)
        (xy 7.993 0.995)
        (xy 7.974 0.981)
        (xy 7.956 0.966)
        (xy 7.94 0.95)
        (xy 7.924 0.934)
        (xy 7.908 0.917)
        (xy 7.894 0.898)
        (xy 7.881 0.878)
        (xy 7.868 0.858)
        (xy 7.857 0.838)
        (xy 7.847 0.817)
        (xy 7.839 0.796)
        (xy 7.831 0.774)
        (xy 7.825 0.751)
        (xy 7.82 0.729)
        (xy 7.815 0.706)
        (xy 7.812 0.684)
        (xy 7.81 0.66)
        (xy 7.809 0.637)
        (xy 8.255 0.637)
        (xy 8.255 0.632)
        (xy 8.255 0.633)
      )

      (stroke (width 0.001) (type solid)) (fill solid) (layer "B.Paste"))
    (fp_poly
      (pts
        (xy 9.525 -4.447)
        (xy 9.079 -4.446)
        (xy 9.08 -4.469)
        (xy 9.082 -4.493)
        (xy 9.085 -4.515)
        (xy 9.089 -4.538)
        (xy 9.095 -4.56)
        (xy 9.102 -4.583)
        (xy 9.108 -4.605)
        (xy 9.118 -4.626)
        (xy 9.127 -4.647)
        (xy 9.138 -4.668)
        (xy 9.151 -4.687)
        (xy 9.164 -4.706)
        (xy 9.179 -4.725)
        (xy 9.194 -4.743)
        (xy 9.21 -4.759)
        (xy 9.227 -4.775)
        (xy 9.243 -4.791)
        (xy 9.262 -4.804)
        (xy 9.281 -4.817)
        (xy 9.301 -4.831)
        (xy 9.321 -4.841)
        (xy 9.342 -4.852)
        (xy 9.365 -4.86)
        (xy 9.387 -4.868)
        (xy 9.409 -4.874)
        (xy 9.43 -4.879)
        (xy 9.454 -4.884)
        (xy 9.477 -4.887)
        (xy 9.5 -4.889)
        (xy 9.525 -4.889)
        (xy 9.547 -4.889)
        (xy 9.571 -4.887)
        (xy 9.595 -4.884)
        (xy 9.618 -4.879)
        (xy 9.64 -4.874)
        (xy 9.663 -4.868)
        (xy 9.683 -4.86)
        (xy 9.705 -4.852)
        (xy 9.727 -4.841)
        (xy 9.747 -4.829)
        (xy 9.766 -4.817)
        (xy 9.787 -4.804)
        (xy 9.804 -4.791)
        (xy 9.823 -4.775)
        (xy 9.839 -4.759)
        (xy 9.855 -4.743)
        (xy 9.871 -4.724)
        (xy 9.884 -4.706)
        (xy 9.897 -4.687)
        (xy 9.909 -4.668)
        (xy 9.92 -4.647)
        (xy 9.932 -4.626)
        (xy 9.939 -4.603)
        (xy 9.948 -4.583)
        (xy 9.954 -4.559)
        (xy 9.96 -4.538)
        (xy 9.964 -4.514)
        (xy 9.967 -4.491)
        (xy 9.968 -4.467)
        (xy 9.97 -4.445)
        (xy 9.968 -4.421)
        (xy 9.967 -4.397)
        (xy 9.964 -4.374)
        (xy 9.96 -4.352)
        (xy 9.954 -4.329)
        (xy 9.948 -4.307)
        (xy 9.939 -4.285)
        (xy 9.932 -4.264)
        (xy 9.92 -4.243)
        (xy 9.909 -4.222)
        (xy 9.897 -4.203)
        (xy 9.884 -4.182)
        (xy 9.871 -4.164)
        (xy 9.855 -4.147)
        (xy 9.839 -4.129)
        (xy 9.823 -4.113)
        (xy 9.804 -4.099)
        (xy 9.787 -4.084)
        (xy 9.766 -4.071)
        (xy 9.747 -4.059)
        (xy 9.727 -4.049)
        (xy 9.705 -4.038)
        (xy 9.683 -4.03)
        (xy 9.663 -4.022)
        (xy 9.64 -4.014)
        (xy 9.618 -4.009)
        (xy 9.595 -4.004)
        (xy 9.571 -4.001)
        (xy 9.547 -4.001)
        (xy 9.525 -3.999)
        (xy 9.5 -4.001)
        (xy 9.477 -4.001)
        (xy 9.454 -4.004)
        (xy 9.43 -4.009)
        (xy 9.409 -4.014)
        (xy 9.387 -4.022)
        (xy 9.365 -4.028)
        (xy 9.342 -4.038)
        (xy 9.321 -4.047)
        (xy 9.301 -4.059)
        (xy 9.281 -4.071)
        (xy 9.262 -4.084)
        (xy 9.243 -4.099)
        (xy 9.227 -4.113)
        (xy 9.21 -4.129)
        (xy 9.194 -4.147)
        (xy 9.179 -4.163)
        (xy 9.164 -4.182)
        (xy 9.151 -4.201)
        (xy 9.138 -4.222)
        (xy 9.127 -4.241)
        (xy 9.118 -4.262)
        (xy 9.108 -4.285)
        (xy 9.102 -4.307)
        (xy 9.095 -4.328)
        (xy 9.089 -4.35)
        (xy 9.085 -4.373)
        (xy 9.082 -4.397)
        (xy 9.08 -4.421)
        (xy 9.079 -4.442)
        (xy 9.525 -4.442)
        (xy 9.525 -4.446)
        (xy 9.525 -4.447)
      )

      (stroke (width 0.001) (type solid)) (fill solid) (layer "B.Paste"))
    (fp_poly
      (pts
        (xy 9.525 -1.907)
        (xy 9.079 -1.906)
        (xy 9.08 -1.929)
        (xy 9.082 -1.953)
        (xy 9.085 -1.975)
        (xy 9.089 -1.999)
        (xy 9.095 -2.02)
        (xy 9.102 -2.043)
        (xy 9.108 -2.064)
        (xy 9.118 -2.087)
        (xy 9.127 -2.108)
        (xy 9.138 -2.128)
        (xy 9.151 -2.148)
        (xy 9.164 -2.166)
        (xy 9.179 -2.185)
        (xy 9.194 -2.202)
        (xy 9.21 -2.22)
        (xy 9.227 -2.236)
        (xy 9.243 -2.25)
        (xy 9.262 -2.265)
        (xy 9.281 -2.277)
        (xy 9.301 -2.29)
        (xy 9.321 -2.301)
        (xy 9.342 -2.311)
        (xy 9.365 -2.321)
        (xy 9.387 -2.327)
        (xy 9.409 -2.334)
        (xy 9.43 -2.339)
        (xy 9.454 -2.345)
        (xy 9.477 -2.347)
        (xy 9.5 -2.349)
        (xy 9.525 -2.35)
        (xy 9.547 -2.349)
        (xy 9.571 -2.347)
        (xy 9.595 -2.345)
        (xy 9.618 -2.339)
        (xy 9.64 -2.334)
        (xy 9.663 -2.327)
        (xy 9.683 -2.319)
        (xy 9.705 -2.311)
        (xy 9.727 -2.301)
        (xy 9.747 -2.289)
        (xy 9.766 -2.277)
        (xy 9.787 -2.265)
        (xy 9.804 -2.25)
        (xy 9.823 -2.236)
        (xy 9.839 -2.22)
        (xy 9.855 -2.202)
        (xy 9.871 -2.185)
        (xy 9.884 -2.166)
        (xy 9.897 -2.146)
        (xy 9.909 -2.126)
        (xy 9.92 -2.107)
        (xy 9.932 -2.085)
        (xy 9.939 -2.064)
        (xy 9.948 -2.043)
        (xy 9.954 -2.019)
        (xy 9.96 -1.997)
        (xy 9.964 -1.975)
        (xy 9.967 -1.951)
        (xy 9.968 -1.927)
        (xy 9.97 -1.904)
        (xy 9.968 -1.881)
        (xy 9.967 -1.858)
        (xy 9.964 -1.834)
        (xy 9.96 -1.812)
        (xy 9.954 -1.789)
        (xy 9.948 -1.766)
        (xy 9.939 -1.745)
        (xy 9.932 -1.723)
        (xy 9.92 -1.703)
        (xy 9.909 -1.683)
        (xy 9.897 -1.662)
        (xy 9.884 -1.642)
        (xy 9.871 -1.624)
        (xy 9.855 -1.606)
        (xy 9.839 -1.59)
        (xy 9.823 -1.574)
        (xy 9.804 -1.558)
        (xy 9.787 -1.544)
        (xy 9.766 -1.531)
        (xy 9.747 -1.519)
        (xy 9.727 -1.508)
        (xy 9.705 -1.497)
        (xy 9.683 -1.489)
        (xy 9.663 -1.481)
        (xy 9.64 -1.475)
        (xy 9.618 -1.469)
        (xy 9.595 -1.465)
        (xy 9.571 -1.461)
        (xy 9.547 -1.461)
        (xy 9.525 -1.459)
        (xy 9.5 -1.461)
        (xy 9.477 -1.461)
        (xy 9.454 -1.465)
        (xy 9.43 -1.469)
        (xy 9.409 -1.475)
        (xy 9.387 -1.481)
        (xy 9.365 -1.489)
        (xy 9.342 -1.497)
        (xy 9.321 -1.507)
        (xy 9.301 -1.518)
        (xy 9.281 -1.531)
        (xy 9.262 -1.544)
        (xy 9.243 -1.558)
        (xy 9.227 -1.574)
        (xy 9.21 -1.59)
        (xy 9.194 -1.606)
        (xy 9.179 -1.624)
        (xy 9.164 -1.642)
        (xy 9.151 -1.661)
        (xy 9.138 -1.681)
        (xy 9.127 -1.701)
        (xy 9.118 -1.723)
        (xy 9.108 -1.745)
        (xy 9.102 -1.766)
        (xy 9.095 -1.788)
        (xy 9.089 -1.81)
        (xy 9.085 -1.834)
        (xy 9.082 -1.856)
        (xy 9.08 -1.88)
        (xy 9.079 -1.902)
        (xy 9.525 -1.902)
        (xy 9.525 -1.906)
        (xy 9.525 -1.907)
      )

      (stroke (width 0.001) (type solid)) (fill solid) (layer "B.Paste"))
    (fp_poly
      (pts
        (xy 9.525 -0.637)
        (xy 9.079 -0.636)
        (xy 9.08 -0.659)
        (xy 9.082 -0.683)
        (xy 9.085 -0.705)
        (xy 9.089 -0.728)
        (xy 9.095 -0.75)
        (xy 9.102 -0.773)
        (xy 9.108 -0.795)
        (xy 9.118 -0.816)
        (xy 9.127 -0.837)
        (xy 9.138 -0.857)
        (xy 9.151 -0.877)
        (xy 9.164 -0.897)
        (xy 9.179 -0.916)
        (xy 9.194 -0.933)
        (xy 9.21 -0.949)
        (xy 9.227 -0.965)
        (xy 9.243 -0.98)
        (xy 9.262 -0.994)
        (xy 9.281 -1.007)
        (xy 9.301 -1.02)
        (xy 9.321 -1.032)
        (xy 9.342 -1.042)
        (xy 9.365 -1.05)
        (xy 9.387 -1.058)
        (xy 9.409 -1.064)
        (xy 9.43 -1.07)
        (xy 9.454 -1.074)
        (xy 9.477 -1.078)
        (xy 9.5 -1.078)
        (xy 9.525 -1.08)
        (xy 9.547 -1.078)
        (xy 9.571 -1.078)
        (xy 9.595 -1.074)
        (xy 9.618 -1.07)
        (xy 9.64 -1.064)
        (xy 9.663 -1.058)
        (xy 9.683 -1.05)
        (xy 9.705 -1.042)
        (xy 9.727 -1.03)
        (xy 9.747 -1.019)
        (xy 9.766 -1.007)
        (xy 9.787 -0.994)
        (xy 9.804 -0.98)
        (xy 9.823 -0.965)
        (xy 9.839 -0.949)
        (xy 9.855 -0.933)
        (xy 9.871 -0.915)
        (xy 9.884 -0.897)
        (xy 9.897 -0.876)
        (xy 9.909 -0.856)
        (xy 9.92 -0.836)
        (xy 9.932 -0.815)
        (xy 9.939 -0.794)
        (xy 9.948 -0.773)
        (xy 9.954 -0.749)
        (xy 9.96 -0.727)
        (xy 9.964 -0.704)
        (xy 9.967 -0.682)
        (xy 9.968 -0.658)
        (xy 9.97 -0.634)
        (xy 9.968 -0.611)
        (xy 9.967 -0.587)
        (xy 9.964 -0.564)
        (xy 9.96 -0.542)
        (xy 9.954 -0.52)
        (xy 9.948 -0.496)
        (xy 9.939 -0.475)
        (xy 9.932 -0.454)
        (xy 9.92 -0.432)
        (xy 9.909 -0.412)
        (xy 9.897 -0.393)
        (xy 9.884 -0.372)
        (xy 9.871 -0.354)
        (xy 9.855 -0.337)
        (xy 9.839 -0.32)
        (xy 9.823 -0.303)
        (xy 9.804 -0.288)
        (xy 9.787 -0.275)
        (xy 9.766 -0.262)
        (xy 9.747 -0.249)
        (xy 9.727 -0.238)
        (xy 9.705 -0.228)
        (xy 9.683 -0.219)
        (xy 9.663 -0.211)
        (xy 9.64 -0.204)
        (xy 9.618 -0.2)
        (xy 9.595 -0.195)
        (xy 9.571 -0.192)
        (xy 9.547 -0.19)
        (xy 9.525 -0.189)
        (xy 9.5 -0.19)
        (xy 9.477 -0.192)
        (xy 9.454 -0.195)
        (xy 9.43 -0.2)
        (xy 9.409 -0.204)
        (xy 9.387 -0.211)
        (xy 9.365 -0.218)
        (xy 9.342 -0.228)
        (xy 9.321 -0.237)
        (xy 9.301 -0.248)
        (xy 9.281 -0.262)
        (xy 9.262 -0.275)
        (xy 9.243 -0.288)
        (xy 9.227 -0.303)
        (xy 9.21 -0.32)
        (xy 9.194 -0.337)
        (xy 9.179 -0.353)
        (xy 9.164 -0.372)
        (xy 9.151 -0.392)
        (xy 9.138 -0.411)
        (xy 9.127 -0.431)
        (xy 9.118 -0.453)
        (xy 9.108 -0.474)
        (xy 9.102 -0.496)
        (xy 9.095 -0.519)
        (xy 9.089 -0.541)
        (xy 9.085 -0.563)
        (xy 9.082 -0.586)
        (xy 9.08 -0.61)
        (xy 9.079 -0.631)
        (xy 9.525 -0.631)
        (xy 9.525 -0.636)
        (xy 9.525 -0.637)
      )

      (stroke (width 0.001) (type solid)) (fill solid) (layer "B.Paste"))
    (fp_poly
      (pts
        (xy 9.525 0.633)
        (xy 9.079 0.632)
        (xy 9.08 0.611)
        (xy 9.082 0.587)
        (xy 9.085 0.564)
        (xy 9.089 0.542)
        (xy 9.095 0.52)
        (xy 9.102 0.497)
        (xy 9.108 0.475)
        (xy 9.118 0.454)
        (xy 9.127 0.432)
        (xy 9.138 0.412)
        (xy 9.151 0.393)
        (xy 9.164 0.373)
        (xy 9.179 0.354)
        (xy 9.194 0.338)
        (xy 9.21 0.32)
        (xy 9.227 0.304)
        (xy 9.243 0.289)
        (xy 9.262 0.276)
        (xy 9.281 0.263)
        (xy 9.301 0.249)
        (xy 9.321 0.238)
        (xy 9.342 0.229)
        (xy 9.365 0.219)
        (xy 9.387 0.212)
        (xy 9.409 0.205)
        (xy 9.43 0.201)
        (xy 9.454 0.196)
        (xy 9.477 0.192)
        (xy 9.5 0.191)
        (xy 9.525 0.19)
        (xy 9.547 0.191)
        (xy 9.571 0.192)
        (xy 9.595 0.196)
        (xy 9.618 0.201)
        (xy 9.64 0.205)
        (xy 9.663 0.212)
        (xy 9.683 0.22)
        (xy 9.705 0.229)
        (xy 9.727 0.239)
        (xy 9.747 0.25)
        (xy 9.766 0.263)
        (xy 9.787 0.276)
        (xy 9.804 0.289)
        (xy 9.823 0.304)
        (xy 9.839 0.32)
        (xy 9.855 0.338)
        (xy 9.871 0.355)
        (xy 9.884 0.373)
        (xy 9.897 0.394)
        (xy 9.909 0.413)
        (xy 9.92 0.433)
        (xy 9.932 0.455)
        (xy 9.939 0.476)
        (xy 9.948 0.497)
        (xy 9.954 0.521)
        (xy 9.96 0.543)
        (xy 9.964 0.565)
        (xy 9.967 0.588)
        (xy 9.968 0.612)
        (xy 9.97 0.635)
        (xy 9.968 0.659)
        (xy 9.967 0.683)
        (xy 9.964 0.705)
        (xy 9.96 0.728)
        (xy 9.954 0.75)
        (xy 9.948 0.774)
        (xy 9.939 0.795)
        (xy 9.932 0.816)
        (xy 9.92 0.837)
        (xy 9.909 0.857)
        (xy 9.897 0.877)
        (xy 9.884 0.898)
        (xy 9.871 0.916)
        (xy 9.855 0.934)
        (xy 9.839 0.95)
        (xy 9.823 0.966)
        (xy 9.804 0.981)
        (xy 9.787 0.995)
        (xy 9.766 1.008)
        (xy 9.747 1.02)
        (xy 9.727 1.031)
        (xy 9.705 1.043)
        (xy 9.683 1.051)
        (xy 9.663 1.059)
        (xy 9.64 1.065)
        (xy 9.618 1.071)
        (xy 9.595 1.075)
        (xy 9.571 1.079)
        (xy 9.547 1.079)
        (xy 9.525 1.081)
        (xy 9.5 1.079)
        (xy 9.477 1.079)
        (xy 9.454 1.075)
        (xy 9.43 1.071)
        (xy 9.409 1.065)
        (xy 9.387 1.059)
        (xy 9.365 1.051)
        (xy 9.342 1.043)
        (xy 9.321 1.033)
        (xy 9.301 1.021)
        (xy 9.281 1.008)
        (xy 9.262 0.995)
        (xy 9.243 0.981)
        (xy 9.227 0.966)
        (xy 9.21 0.95)
        (xy 9.194 0.934)
        (xy 9.179 0.917)
        (xy 9.164 0.898)
        (xy 9.151 0.878)
        (xy 9.138 0.858)
        (xy 9.127 0.838)
        (xy 9.118 0.817)
        (xy 9.108 0.796)
        (xy 9.102 0.774)
        (xy 9.095 0.751)
        (xy 9.089 0.729)
        (xy 9.085 0.706)
        (xy 9.082 0.684)
        (xy 9.08 0.66)
        (xy 9.079 0.637)
        (xy 9.525 0.637)
        (xy 9.525 0.632)
        (xy 9.525 0.633)
      )

      (stroke (width 0.001) (type solid)) (fill solid) (layer "B.Paste"))
    (fp_poly
      (pts
        (xy 10.794 -4.447)
        (xy 10.349 -4.446)
        (xy 10.351 -4.469)
        (xy 10.352 -4.493)
        (xy 10.355 -4.515)
        (xy 10.359 -4.538)
        (xy 10.364 -4.56)
        (xy 10.371 -4.583)
        (xy 10.378 -4.605)
        (xy 10.387 -4.626)
        (xy 10.397 -4.647)
        (xy 10.409 -4.668)
        (xy 10.422 -4.687)
        (xy 10.435 -4.706)
        (xy 10.448 -4.725)
        (xy 10.464 -4.743)
        (xy 10.48 -4.759)
        (xy 10.496 -4.775)
        (xy 10.513 -4.791)
        (xy 10.532 -4.804)
        (xy 10.551 -4.817)
        (xy 10.571 -4.831)
        (xy 10.592 -4.841)
        (xy 10.612 -4.852)
        (xy 10.634 -4.86)
        (xy 10.656 -4.868)
        (xy 10.679 -4.874)
        (xy 10.701 -4.879)
        (xy 10.723 -4.884)
        (xy 10.746 -4.887)
        (xy 10.771 -4.889)
        (xy 10.794 -4.889)
        (xy 10.817 -4.889)
        (xy 10.842 -4.887)
        (xy 10.864 -4.884)
        (xy 10.887 -4.879)
        (xy 10.909 -4.874)
        (xy 10.932 -4.868)
        (xy 10.954 -4.86)
        (xy 10.976 -4.852)
        (xy 10.996 -4.841)
        (xy 11.018 -4.829)
        (xy 11.037 -4.817)
        (xy 11.057 -4.804)
        (xy 11.074 -4.791)
        (xy 11.092 -4.775)
        (xy 11.109 -4.759)
        (xy 11.125 -4.743)
        (xy 11.14 -4.724)
        (xy 11.154 -4.706)
        (xy 11.167 -4.687)
        (xy 11.179 -4.668)
        (xy 11.191 -4.647)
        (xy 11.201 -4.626)
        (xy 11.21 -4.603)
        (xy 11.217 -4.583)
        (xy 11.224 -4.559)
        (xy 11.23 -4.538)
        (xy 11.234 -4.514)
        (xy 11.237 -4.491)
        (xy 11.239 -4.467)
        (xy 11.239 -4.445)
        (xy 11.239 -4.421)
        (xy 11.237 -4.397)
        (xy 11.234 -4.374)
        (xy 11.23 -4.352)
        (xy 11.224 -4.329)
        (xy 11.217 -4.307)
        (xy 11.21 -4.285)
        (xy 11.201 -4.264)
        (xy 11.191 -4.243)
        (xy 11.179 -4.222)
        (xy 11.167 -4.203)
        (xy 11.154 -4.182)
        (xy 11.14 -4.164)
        (xy 11.125 -4.147)
        (xy 11.109 -4.129)
        (xy 11.092 -4.113)
        (xy 11.074 -4.099)
        (xy 11.057 -4.084)
        (xy 11.037 -4.071)
        (xy 11.018 -4.059)
        (xy 10.996 -4.049)
        (xy 10.976 -4.038)
        (xy 10.954 -4.03)
        (xy 10.932 -4.022)
        (xy 10.909 -4.014)
        (xy 10.887 -4.009)
        (xy 10.864 -4.004)
        (xy 10.842 -4.001)
        (xy 10.817 -4.001)
        (xy 10.794 -3.999)
        (xy 10.771 -4.001)
        (xy 10.746 -4.001)
        (xy 10.723 -4.004)
        (xy 10.701 -4.009)
        (xy 10.679 -4.014)
        (xy 10.656 -4.022)
        (xy 10.634 -4.028)
        (xy 10.612 -4.038)
        (xy 10.592 -4.047)
        (xy 10.571 -4.059)
        (xy 10.551 -4.071)
        (xy 10.532 -4.084)
        (xy 10.513 -4.099)
        (xy 10.496 -4.113)
        (xy 10.48 -4.129)
        (xy 10.464 -4.147)
        (xy 10.448 -4.163)
        (xy 10.435 -4.182)
        (xy 10.422 -4.201)
        (xy 10.409 -4.222)
        (xy 10.397 -4.241)
        (xy 10.387 -4.262)
        (xy 10.378 -4.285)
        (xy 10.371 -4.307)
        (xy 10.364 -4.328)
        (xy 10.359 -4.35)
        (xy 10.355 -4.373)
        (xy 10.352 -4.397)
        (xy 10.351 -4.421)
        (xy 10.349 -4.442)
        (xy 10.794 -4.442)
        (xy 10.794 -4.446)
        (xy 10.794 -4.447)
      )

      (stroke (width 0.001) (type solid)) (fill solid) (layer "B.Paste"))
    (fp_poly
      (pts
        (xy 10.794 -1.907)
        (xy 10.349 -1.906)
        (xy 10.351 -1.929)
        (xy 10.352 -1.953)
        (xy 10.355 -1.975)
        (xy 10.359 -1.999)
        (xy 10.364 -2.02)
        (xy 10.371 -2.043)
        (xy 10.378 -2.064)
        (xy 10.387 -2.087)
        (xy 10.397 -2.108)
        (xy 10.409 -2.128)
        (xy 10.422 -2.148)
        (xy 10.435 -2.166)
        (xy 10.448 -2.185)
        (xy 10.464 -2.202)
        (xy 10.48 -2.22)
        (xy 10.496 -2.236)
        (xy 10.513 -2.25)
        (xy 10.532 -2.265)
        (xy 10.551 -2.277)
        (xy 10.571 -2.29)
        (xy 10.592 -2.301)
        (xy 10.612 -2.311)
        (xy 10.634 -2.321)
        (xy 10.656 -2.327)
        (xy 10.679 -2.334)
        (xy 10.701 -2.339)
        (xy 10.723 -2.345)
        (xy 10.746 -2.347)
        (xy 10.771 -2.349)
        (xy 10.794 -2.35)
        (xy 10.817 -2.349)
        (xy 10.842 -2.347)
        (xy 10.864 -2.345)
        (xy 10.887 -2.339)
        (xy 10.909 -2.334)
        (xy 10.932 -2.327)
        (xy 10.954 -2.319)
        (xy 10.976 -2.311)
        (xy 10.996 -2.301)
        (xy 11.018 -2.289)
        (xy 11.037 -2.277)
        (xy 11.057 -2.265)
        (xy 11.074 -2.25)
        (xy 11.092 -2.236)
        (xy 11.109 -2.22)
        (xy 11.125 -2.202)
        (xy 11.14 -2.185)
        (xy 11.154 -2.166)
        (xy 11.167 -2.146)
        (xy 11.179 -2.126)
        (xy 11.191 -2.107)
        (xy 11.201 -2.085)
        (xy 11.21 -2.064)
        (xy 11.217 -2.043)
        (xy 11.224 -2.019)
        (xy 11.23 -1.997)
        (xy 11.234 -1.975)
        (xy 11.237 -1.951)
        (xy 11.239 -1.927)
        (xy 11.239 -1.904)
        (xy 11.239 -1.881)
        (xy 11.237 -1.858)
        (xy 11.234 -1.834)
        (xy 11.23 -1.812)
        (xy 11.224 -1.789)
        (xy 11.217 -1.766)
        (xy 11.21 -1.745)
        (xy 11.201 -1.723)
        (xy 11.191 -1.703)
        (xy 11.179 -1.683)
        (xy 11.167 -1.662)
        (xy 11.154 -1.642)
        (xy 11.14 -1.624)
        (xy 11.125 -1.606)
        (xy 11.109 -1.59)
        (xy 11.092 -1.574)
        (xy 11.074 -1.558)
        (xy 11.057 -1.544)
        (xy 11.037 -1.531)
        (xy 11.018 -1.519)
        (xy 10.996 -1.508)
        (xy 10.976 -1.497)
        (xy 10.954 -1.489)
        (xy 10.932 -1.481)
        (xy 10.909 -1.475)
        (xy 10.887 -1.469)
        (xy 10.864 -1.465)
        (xy 10.842 -1.461)
        (xy 10.817 -1.461)
        (xy 10.794 -1.459)
        (xy 10.771 -1.461)
        (xy 10.746 -1.461)
        (xy 10.723 -1.465)
        (xy 10.701 -1.469)
        (xy 10.679 -1.475)
        (xy 10.656 -1.481)
        (xy 10.634 -1.489)
        (xy 10.612 -1.497)
        (xy 10.592 -1.507)
        (xy 10.571 -1.518)
        (xy 10.551 -1.531)
        (xy 10.532 -1.544)
        (xy 10.513 -1.558)
        (xy 10.496 -1.574)
        (xy 10.48 -1.59)
        (xy 10.464 -1.606)
        (xy 10.448 -1.624)
        (xy 10.435 -1.642)
        (xy 10.422 -1.661)
        (xy 10.409 -1.681)
        (xy 10.397 -1.701)
        (xy 10.387 -1.723)
        (xy 10.378 -1.745)
        (xy 10.371 -1.766)
        (xy 10.364 -1.788)
        (xy 10.359 -1.81)
        (xy 10.355 -1.834)
        (xy 10.352 -1.856)
        (xy 10.351 -1.88)
        (xy 10.349 -1.902)
        (xy 10.794 -1.902)
        (xy 10.794 -1.906)
        (xy 10.794 -1.907)
      )

      (stroke (width 0.001) (type solid)) (fill solid) (layer "B.Paste"))
    (fp_poly
      (pts
        (xy 10.794 -0.637)
        (xy 10.349 -0.636)
        (xy 10.351 -0.659)
        (xy 10.352 -0.683)
        (xy 10.355 -0.705)
        (xy 10.359 -0.728)
        (xy 10.364 -0.75)
        (xy 10.371 -0.773)
        (xy 10.378 -0.795)
        (xy 10.387 -0.816)
        (xy 10.397 -0.837)
        (xy 10.409 -0.857)
        (xy 10.422 -0.877)
        (xy 10.435 -0.897)
        (xy 10.448 -0.916)
        (xy 10.464 -0.933)
        (xy 10.48 -0.949)
        (xy 10.496 -0.965)
        (xy 10.513 -0.98)
        (xy 10.532 -0.994)
        (xy 10.551 -1.007)
        (xy 10.571 -1.02)
        (xy 10.592 -1.032)
        (xy 10.612 -1.042)
        (xy 10.634 -1.05)
        (xy 10.656 -1.058)
        (xy 10.679 -1.064)
        (xy 10.701 -1.07)
        (xy 10.723 -1.074)
        (xy 10.746 -1.078)
        (xy 10.771 -1.078)
        (xy 10.794 -1.08)
        (xy 10.817 -1.078)
        (xy 10.842 -1.078)
        (xy 10.864 -1.074)
        (xy 10.887 -1.07)
        (xy 10.909 -1.064)
        (xy 10.932 -1.058)
        (xy 10.954 -1.05)
        (xy 10.976 -1.042)
        (xy 10.996 -1.03)
        (xy 11.018 -1.019)
        (xy 11.037 -1.007)
        (xy 11.057 -0.994)
        (xy 11.074 -0.98)
        (xy 11.092 -0.965)
        (xy 11.109 -0.949)
        (xy 11.125 -0.933)
        (xy 11.14 -0.915)
        (xy 11.154 -0.897)
        (xy 11.167 -0.876)
        (xy 11.179 -0.856)
        (xy 11.191 -0.836)
        (xy 11.201 -0.815)
        (xy 11.21 -0.794)
        (xy 11.217 -0.773)
        (xy 11.224 -0.749)
        (xy 11.23 -0.727)
        (xy 11.234 -0.704)
        (xy 11.237 -0.682)
        (xy 11.239 -0.658)
        (xy 11.239 -0.634)
        (xy 11.239 -0.611)
        (xy 11.237 -0.587)
        (xy 11.234 -0.564)
        (xy 11.23 -0.542)
        (xy 11.224 -0.52)
        (xy 11.217 -0.496)
        (xy 11.21 -0.475)
        (xy 11.201 -0.454)
        (xy 11.191 -0.432)
        (xy 11.179 -0.412)
        (xy 11.167 -0.393)
        (xy 11.154 -0.372)
        (xy 11.14 -0.354)
        (xy 11.125 -0.337)
        (xy 11.109 -0.32)
        (xy 11.092 -0.303)
        (xy 11.074 -0.288)
        (xy 11.057 -0.275)
        (xy 11.037 -0.262)
        (xy 11.018 -0.249)
        (xy 10.996 -0.238)
        (xy 10.976 -0.228)
        (xy 10.954 -0.219)
        (xy 10.932 -0.211)
        (xy 10.909 -0.204)
        (xy 10.887 -0.2)
        (xy 10.864 -0.195)
        (xy 10.842 -0.192)
        (xy 10.817 -0.19)
        (xy 10.794 -0.189)
        (xy 10.771 -0.19)
        (xy 10.746 -0.192)
        (xy 10.723 -0.195)
        (xy 10.701 -0.2)
        (xy 10.679 -0.204)
        (xy 10.656 -0.211)
        (xy 10.634 -0.218)
        (xy 10.612 -0.228)
        (xy 10.592 -0.237)
        (xy 10.571 -0.248)
        (xy 10.551 -0.262)
        (xy 10.532 -0.275)
        (xy 10.513 -0.288)
        (xy 10.496 -0.303)
        (xy 10.48 -0.32)
        (xy 10.464 -0.337)
        (xy 10.448 -0.353)
        (xy 10.435 -0.372)
        (xy 10.422 -0.392)
        (xy 10.409 -0.411)
        (xy 10.397 -0.431)
        (xy 10.387 -0.453)
        (xy 10.378 -0.474)
        (xy 10.371 -0.496)
        (xy 10.364 -0.519)
        (xy 10.359 -0.541)
        (xy 10.355 -0.563)
        (xy 10.352 -0.586)
        (xy 10.351 -0.61)
        (xy 10.349 -0.631)
        (xy 10.794 -0.631)
        (xy 10.794 -0.636)
        (xy 10.794 -0.637)
      )

      (stroke (width 0.001) (type solid)) (fill solid) (layer "B.Paste"))
    (fp_poly
      (pts
        (xy 10.794 0.633)
        (xy 10.349 0.632)
        (xy 10.351 0.611)
        (xy 10.352 0.587)
        (xy 10.355 0.564)
        (xy 10.359 0.542)
        (xy 10.364 0.52)
        (xy 10.371 0.497)
        (xy 10.378 0.475)
        (xy 10.387 0.454)
        (xy 10.397 0.432)
        (xy 10.409 0.412)
        (xy 10.422 0.393)
        (xy 10.435 0.373)
        (xy 10.448 0.354)
        (xy 10.464 0.338)
        (xy 10.48 0.32)
        (xy 10.496 0.304)
        (xy 10.513 0.289)
        (xy 10.532 0.276)
        (xy 10.551 0.263)
        (xy 10.571 0.249)
        (xy 10.592 0.238)
        (xy 10.612 0.229)
        (xy 10.634 0.219)
        (xy 10.656 0.212)
        (xy 10.679 0.205)
        (xy 10.701 0.201)
        (xy 10.723 0.196)
        (xy 10.746 0.192)
        (xy 10.771 0.191)
        (xy 10.794 0.19)
        (xy 10.817 0.191)
        (xy 10.842 0.192)
        (xy 10.864 0.196)
        (xy 10.887 0.201)
        (xy 10.909 0.205)
        (xy 10.932 0.212)
        (xy 10.954 0.22)
        (xy 10.976 0.229)
        (xy 10.996 0.239)
        (xy 11.018 0.25)
        (xy 11.037 0.263)
        (xy 11.057 0.276)
        (xy 11.074 0.289)
        (xy 11.092 0.304)
        (xy 11.109 0.32)
        (xy 11.125 0.338)
        (xy 11.14 0.355)
        (xy 11.154 0.373)
        (xy 11.167 0.394)
        (xy 11.179 0.413)
        (xy 11.191 0.433)
        (xy 11.201 0.455)
        (xy 11.21 0.476)
        (xy 11.217 0.497)
        (xy 11.224 0.521)
        (xy 11.23 0.543)
        (xy 11.234 0.565)
        (xy 11.237 0.588)
        (xy 11.239 0.612)
        (xy 11.239 0.635)
        (xy 11.239 0.659)
        (xy 11.237 0.683)
        (xy 11.234 0.705)
        (xy 11.23 0.728)
        (xy 11.224 0.75)
        (xy 11.217 0.774)
        (xy 11.21 0.795)
        (xy 11.201 0.816)
        (xy 11.191 0.837)
        (xy 11.179 0.857)
        (xy 11.167 0.877)
        (xy 11.154 0.898)
        (xy 11.14 0.916)
        (xy 11.125 0.934)
        (xy 11.109 0.95)
        (xy 11.092 0.966)
        (xy 11.074 0.981)
        (xy 11.057 0.995)
        (xy 11.037 1.008)
        (xy 11.018 1.02)
        (xy 10.996 1.031)
        (xy 10.976 1.043)
        (xy 10.954 1.051)
        (xy 10.932 1.059)
        (xy 10.909 1.065)
        (xy 10.887 1.071)
        (xy 10.864 1.075)
        (xy 10.842 1.079)
        (xy 10.817 1.079)
        (xy 10.794 1.081)
        (xy 10.771 1.079)
        (xy 10.746 1.079)
        (xy 10.723 1.075)
        (xy 10.701 1.071)
        (xy 10.679 1.065)
        (xy 10.656 1.059)
        (xy 10.634 1.051)
        (xy 10.612 1.043)
        (xy 10.592 1.033)
        (xy 10.571 1.021)
        (xy 10.551 1.008)
        (xy 10.532 0.995)
        (xy 10.513 0.981)
        (xy 10.496 0.966)
        (xy 10.48 0.95)
        (xy 10.464 0.934)
        (xy 10.448 0.917)
        (xy 10.435 0.898)
        (xy 10.422 0.878)
        (xy 10.409 0.858)
        (xy 10.397 0.838)
        (xy 10.387 0.817)
        (xy 10.378 0.796)
        (xy 10.371 0.774)
        (xy 10.364 0.751)
        (xy 10.359 0.729)
        (xy 10.355 0.706)
        (xy 10.352 0.684)
        (xy 10.351 0.66)
        (xy 10.349 0.637)
        (xy 10.794 0.637)
        (xy 10.794 0.632)
        (xy 10.794 0.633)
      )

      (stroke (width 0.001) (type solid)) (fill solid) (layer "B.Paste"))
    (fp_poly
      (pts
        (xy 12.064 -4.447)
        (xy 11.619 -4.446)
        (xy 11.621 -4.469)
        (xy 11.621 -4.493)
        (xy 11.624 -4.515)
        (xy 11.63 -4.538)
        (xy 11.634 -4.56)
        (xy 11.641 -4.583)
        (xy 11.648 -4.605)
        (xy 11.657 -4.626)
        (xy 11.667 -4.647)
        (xy 11.679 -4.668)
        (xy 11.691 -4.687)
        (xy 11.704 -4.706)
        (xy 11.718 -4.725)
        (xy 11.733 -4.743)
        (xy 11.749 -4.759)
        (xy 11.766 -4.775)
        (xy 11.784 -4.791)
        (xy 11.803 -4.804)
        (xy 11.821 -4.817)
        (xy 11.842 -4.831)
        (xy 11.861 -4.841)
        (xy 11.882 -4.852)
        (xy 11.904 -4.86)
        (xy 11.926 -4.868)
        (xy 11.948 -4.874)
        (xy 11.97 -4.879)
        (xy 11.993 -4.884)
        (xy 12.016 -4.887)
        (xy 12.041 -4.889)
        (xy 12.064 -4.889)
        (xy 12.087 -4.889)
        (xy 12.111 -4.887)
        (xy 12.134 -4.884)
        (xy 12.157 -4.879)
        (xy 12.179 -4.874)
        (xy 12.202 -4.868)
        (xy 12.223 -4.86)
        (xy 12.246 -4.852)
        (xy 12.266 -4.841)
        (xy 12.287 -4.829)
        (xy 12.307 -4.817)
        (xy 12.326 -4.804)
        (xy 12.345 -4.791)
        (xy 12.362 -4.775)
        (xy 12.38 -4.759)
        (xy 12.396 -4.743)
        (xy 12.41 -4.724)
        (xy 12.425 -4.706)
        (xy 12.438 -4.687)
        (xy 12.449 -4.668)
        (xy 12.461 -4.647)
        (xy 12.471 -4.626)
        (xy 12.48 -4.603)
        (xy 12.487 -4.583)
        (xy 12.494 -4.559)
        (xy 12.499 -4.538)
        (xy 12.505 -4.514)
        (xy 12.507 -4.491)
        (xy 12.509 -4.467)
        (xy 12.509 -4.445)
        (xy 12.509 -4.421)
        (xy 12.507 -4.397)
        (xy 12.505 -4.374)
        (xy 12.499 -4.352)
        (xy 12.494 -4.329)
        (xy 12.487 -4.307)
        (xy 12.48 -4.285)
        (xy 12.471 -4.264)
        (xy 12.461 -4.243)
        (xy 12.449 -4.222)
        (xy 12.438 -4.203)
        (xy 12.425 -4.182)
        (xy 12.41 -4.164)
        (xy 12.396 -4.147)
        (xy 12.38 -4.129)
        (xy 12.362 -4.113)
        (xy 12.345 -4.099)
        (xy 12.326 -4.084)
        (xy 12.307 -4.071)
        (xy 12.287 -4.059)
        (xy 12.266 -4.049)
        (xy 12.246 -4.038)
        (xy 12.223 -4.03)
        (xy 12.202 -4.022)
        (xy 12.179 -4.014)
        (xy 12.157 -4.009)
        (xy 12.134 -4.004)
        (xy 12.111 -4.001)
        (xy 12.087 -4.001)
        (xy 12.064 -3.999)
        (xy 12.041 -4.001)
        (xy 12.016 -4.001)
        (xy 11.993 -4.004)
        (xy 11.97 -4.009)
        (xy 11.948 -4.014)
        (xy 11.926 -4.022)
        (xy 11.904 -4.028)
        (xy 11.882 -4.038)
        (xy 11.861 -4.047)
        (xy 11.842 -4.059)
        (xy 11.821 -4.071)
        (xy 11.803 -4.084)
        (xy 11.784 -4.099)
        (xy 11.766 -4.113)
        (xy 11.749 -4.129)
        (xy 11.733 -4.147)
        (xy 11.718 -4.163)
        (xy 11.704 -4.182)
        (xy 11.691 -4.201)
        (xy 11.679 -4.222)
        (xy 11.667 -4.241)
        (xy 11.657 -4.262)
        (xy 11.648 -4.285)
        (xy 11.641 -4.307)
        (xy 11.634 -4.328)
        (xy 11.63 -4.35)
        (xy 11.624 -4.373)
        (xy 11.621 -4.397)
        (xy 11.621 -4.421)
        (xy 11.619 -4.442)
        (xy 12.064 -4.442)
        (xy 12.064 -4.446)
        (xy 12.064 -4.447)
      )

      (stroke (width 0.001) (type solid)) (fill solid) (layer "B.Paste"))
    (fp_poly
      (pts
        (xy 12.064 -1.907)
        (xy 11.619 -1.906)
        (xy 11.621 -1.929)
        (xy 11.621 -1.953)
        (xy 11.624 -1.975)
        (xy 11.63 -1.999)
        (xy 11.634 -2.02)
        (xy 11.641 -2.043)
        (xy 11.648 -2.064)
        (xy 11.657 -2.087)
        (xy 11.667 -2.108)
        (xy 11.679 -2.128)
        (xy 11.691 -2.148)
        (xy 11.704 -2.166)
        (xy 11.718 -2.185)
        (xy 11.733 -2.202)
        (xy 11.749 -2.22)
        (xy 11.766 -2.236)
        (xy 11.784 -2.25)
        (xy 11.803 -2.265)
        (xy 11.821 -2.277)
        (xy 11.842 -2.29)
        (xy 11.861 -2.301)
        (xy 11.882 -2.311)
        (xy 11.904 -2.321)
        (xy 11.926 -2.327)
        (xy 11.948 -2.334)
        (xy 11.97 -2.339)
        (xy 11.993 -2.345)
        (xy 12.016 -2.347)
        (xy 12.041 -2.349)
        (xy 12.064 -2.35)
        (xy 12.087 -2.349)
        (xy 12.111 -2.347)
        (xy 12.134 -2.345)
        (xy 12.157 -2.339)
        (xy 12.179 -2.334)
        (xy 12.202 -2.327)
        (xy 12.223 -2.319)
        (xy 12.246 -2.311)
        (xy 12.266 -2.301)
        (xy 12.287 -2.289)
        (xy 12.307 -2.277)
        (xy 12.326 -2.265)
        (xy 12.345 -2.25)
        (xy 12.362 -2.236)
        (xy 12.38 -2.22)
        (xy 12.396 -2.202)
        (xy 12.41 -2.185)
        (xy 12.425 -2.166)
        (xy 12.438 -2.146)
        (xy 12.449 -2.126)
        (xy 12.461 -2.107)
        (xy 12.471 -2.085)
        (xy 12.48 -2.064)
        (xy 12.487 -2.043)
        (xy 12.494 -2.019)
        (xy 12.499 -1.997)
        (xy 12.505 -1.975)
        (xy 12.507 -1.951)
        (xy 12.509 -1.927)
        (xy 12.509 -1.904)
        (xy 12.509 -1.881)
        (xy 12.507 -1.858)
        (xy 12.505 -1.834)
        (xy 12.499 -1.812)
        (xy 12.494 -1.789)
        (xy 12.487 -1.766)
        (xy 12.48 -1.745)
        (xy 12.471 -1.723)
        (xy 12.461 -1.703)
        (xy 12.449 -1.683)
        (xy 12.438 -1.662)
        (xy 12.425 -1.642)
        (xy 12.41 -1.624)
        (xy 12.396 -1.606)
        (xy 12.38 -1.59)
        (xy 12.362 -1.574)
        (xy 12.345 -1.558)
        (xy 12.326 -1.544)
        (xy 12.307 -1.531)
        (xy 12.287 -1.519)
        (xy 12.266 -1.508)
        (xy 12.246 -1.497)
        (xy 12.223 -1.489)
        (xy 12.202 -1.481)
        (xy 12.179 -1.475)
        (xy 12.157 -1.469)
        (xy 12.134 -1.465)
        (xy 12.111 -1.461)
        (xy 12.087 -1.461)
        (xy 12.064 -1.459)
        (xy 12.041 -1.461)
        (xy 12.016 -1.461)
        (xy 11.993 -1.465)
        (xy 11.97 -1.469)
        (xy 11.948 -1.475)
        (xy 11.926 -1.481)
        (xy 11.904 -1.489)
        (xy 11.882 -1.497)
        (xy 11.861 -1.507)
        (xy 11.842 -1.518)
        (xy 11.821 -1.531)
        (xy 11.803 -1.544)
        (xy 11.784 -1.558)
        (xy 11.766 -1.574)
        (xy 11.749 -1.59)
        (xy 11.733 -1.606)
        (xy 11.718 -1.624)
        (xy 11.704 -1.642)
        (xy 11.691 -1.661)
        (xy 11.679 -1.681)
        (xy 11.667 -1.701)
        (xy 11.657 -1.723)
        (xy 11.648 -1.745)
        (xy 11.641 -1.766)
        (xy 11.634 -1.788)
        (xy 11.63 -1.81)
        (xy 11.624 -1.834)
        (xy 11.621 -1.856)
        (xy 11.621 -1.88)
        (xy 11.619 -1.902)
        (xy 12.064 -1.902)
        (xy 12.064 -1.906)
        (xy 12.064 -1.907)
      )

      (stroke (width 0.001) (type solid)) (fill solid) (layer "B.Paste"))
    (fp_poly
      (pts
        (xy 12.064 -0.637)
        (xy 11.619 -0.636)
        (xy 11.621 -0.659)
        (xy 11.621 -0.683)
        (xy 11.624 -0.705)
        (xy 11.63 -0.728)
        (xy 11.634 -0.75)
        (xy 11.641 -0.773)
        (xy 11.648 -0.795)
        (xy 11.657 -0.816)
        (xy 11.667 -0.837)
        (xy 11.679 -0.857)
        (xy 11.691 -0.877)
        (xy 11.704 -0.897)
        (xy 11.718 -0.916)
        (xy 11.733 -0.933)
        (xy 11.749 -0.949)
        (xy 11.766 -0.965)
        (xy 11.784 -0.98)
        (xy 11.803 -0.994)
        (xy 11.821 -1.007)
        (xy 11.842 -1.02)
        (xy 11.861 -1.032)
        (xy 11.882 -1.042)
        (xy 11.904 -1.05)
        (xy 11.926 -1.058)
        (xy 11.948 -1.064)
        (xy 11.97 -1.07)
        (xy 11.993 -1.074)
        (xy 12.016 -1.078)
        (xy 12.041 -1.078)
        (xy 12.064 -1.08)
        (xy 12.087 -1.078)
        (xy 12.111 -1.078)
        (xy 12.134 -1.074)
        (xy 12.157 -1.07)
        (xy 12.179 -1.064)
        (xy 12.202 -1.058)
        (xy 12.223 -1.05)
        (xy 12.246 -1.042)
        (xy 12.266 -1.03)
        (xy 12.287 -1.019)
        (xy 12.307 -1.007)
        (xy 12.326 -0.994)
        (xy 12.345 -0.98)
        (xy 12.362 -0.965)
        (xy 12.38 -0.949)
        (xy 12.396 -0.933)
        (xy 12.41 -0.915)
        (xy 12.425 -0.897)
        (xy 12.438 -0.876)
        (xy 12.449 -0.856)
        (xy 12.461 -0.836)
        (xy 12.471 -0.815)
        (xy 12.48 -0.794)
        (xy 12.487 -0.773)
        (xy 12.494 -0.749)
        (xy 12.499 -0.727)
        (xy 12.505 -0.704)
        (xy 12.507 -0.682)
        (xy 12.509 -0.658)
        (xy 12.509 -0.634)
        (xy 12.509 -0.611)
        (xy 12.507 -0.587)
        (xy 12.505 -0.564)
        (xy 12.499 -0.542)
        (xy 12.494 -0.52)
        (xy 12.487 -0.496)
        (xy 12.48 -0.475)
        (xy 12.471 -0.454)
        (xy 12.461 -0.432)
        (xy 12.449 -0.412)
        (xy 12.438 -0.393)
        (xy 12.425 -0.372)
        (xy 12.41 -0.354)
        (xy 12.396 -0.337)
        (xy 12.38 -0.32)
        (xy 12.362 -0.303)
        (xy 12.345 -0.288)
        (xy 12.326 -0.275)
        (xy 12.307 -0.262)
        (xy 12.287 -0.249)
        (xy 12.266 -0.238)
        (xy 12.246 -0.228)
        (xy 12.223 -0.219)
        (xy 12.202 -0.211)
        (xy 12.179 -0.204)
        (xy 12.157 -0.2)
        (xy 12.134 -0.195)
        (xy 12.111 -0.192)
        (xy 12.087 -0.19)
        (xy 12.064 -0.189)
        (xy 12.041 -0.19)
        (xy 12.016 -0.192)
        (xy 11.993 -0.195)
        (xy 11.97 -0.2)
        (xy 11.948 -0.204)
        (xy 11.926 -0.211)
        (xy 11.904 -0.218)
        (xy 11.882 -0.228)
        (xy 11.861 -0.237)
        (xy 11.842 -0.248)
        (xy 11.821 -0.262)
        (xy 11.803 -0.275)
        (xy 11.784 -0.288)
        (xy 11.766 -0.303)
        (xy 11.749 -0.32)
        (xy 11.733 -0.337)
        (xy 11.718 -0.353)
        (xy 11.704 -0.372)
        (xy 11.691 -0.392)
        (xy 11.679 -0.411)
        (xy 11.667 -0.431)
        (xy 11.657 -0.453)
        (xy 11.648 -0.474)
        (xy 11.641 -0.496)
        (xy 11.634 -0.519)
        (xy 11.63 -0.541)
        (xy 11.624 -0.563)
        (xy 11.621 -0.586)
        (xy 11.621 -0.61)
        (xy 11.619 -0.631)
        (xy 12.064 -0.631)
        (xy 12.064 -0.636)
        (xy 12.064 -0.637)
      )

      (stroke (width 0.001) (type solid)) (fill solid) (layer "B.Paste"))
    (fp_poly
      (pts
        (xy 12.064 0.633)
        (xy 11.619 0.632)
        (xy 11.621 0.611)
        (xy 11.621 0.587)
        (xy 11.624 0.564)
        (xy 11.63 0.542)
        (xy 11.634 0.52)
        (xy 11.641 0.497)
        (xy 11.648 0.475)
        (xy 11.657 0.454)
        (xy 11.667 0.432)
        (xy 11.679 0.412)
        (xy 11.691 0.393)
        (xy 11.704 0.373)
        (xy 11.718 0.354)
        (xy 11.733 0.338)
        (xy 11.749 0.32)
        (xy 11.766 0.304)
        (xy 11.784 0.289)
        (xy 11.803 0.276)
        (xy 11.821 0.263)
        (xy 11.842 0.249)
        (xy 11.861 0.238)
        (xy 11.882 0.229)
        (xy 11.904 0.219)
        (xy 11.926 0.212)
        (xy 11.948 0.205)
        (xy 11.97 0.201)
        (xy 11.993 0.196)
        (xy 12.016 0.192)
        (xy 12.041 0.191)
        (xy 12.064 0.19)
        (xy 12.087 0.191)
        (xy 12.111 0.192)
        (xy 12.134 0.196)
        (xy 12.157 0.201)
        (xy 12.179 0.205)
        (xy 12.202 0.212)
        (xy 12.223 0.22)
        (xy 12.246 0.229)
        (xy 12.266 0.239)
        (xy 12.287 0.25)
        (xy 12.307 0.263)
        (xy 12.326 0.276)
        (xy 12.345 0.289)
        (xy 12.362 0.304)
        (xy 12.38 0.32)
        (xy 12.396 0.338)
        (xy 12.41 0.355)
        (xy 12.425 0.373)
        (xy 12.438 0.394)
        (xy 12.449 0.413)
        (xy 12.461 0.433)
        (xy 12.471 0.455)
        (xy 12.48 0.476)
        (xy 12.487 0.497)
        (xy 12.494 0.521)
        (xy 12.499 0.543)
        (xy 12.505 0.565)
        (xy 12.507 0.588)
        (xy 12.509 0.612)
        (xy 12.509 0.635)
        (xy 12.509 0.659)
        (xy 12.507 0.683)
        (xy 12.505 0.705)
        (xy 12.499 0.728)
        (xy 12.494 0.75)
        (xy 12.487 0.774)
        (xy 12.48 0.795)
        (xy 12.471 0.816)
        (xy 12.461 0.837)
        (xy 12.449 0.857)
        (xy 12.438 0.877)
        (xy 12.425 0.898)
        (xy 12.41 0.916)
        (xy 12.396 0.934)
        (xy 12.38 0.95)
        (xy 12.362 0.966)
        (xy 12.345 0.981)
        (xy 12.326 0.995)
        (xy 12.307 1.008)
        (xy 12.287 1.02)
        (xy 12.266 1.031)
        (xy 12.246 1.043)
        (xy 12.223 1.051)
        (xy 12.202 1.059)
        (xy 12.179 1.065)
        (xy 12.157 1.071)
        (xy 12.134 1.075)
        (xy 12.111 1.079)
        (xy 12.087 1.079)
        (xy 12.064 1.081)
        (xy 12.041 1.079)
        (xy 12.016 1.079)
        (xy 11.993 1.075)
        (xy 11.97 1.071)
        (xy 11.948 1.065)
        (xy 11.926 1.059)
        (xy 11.904 1.051)
        (xy 11.882 1.043)
        (xy 11.861 1.033)
        (xy 11.842 1.021)
        (xy 11.821 1.008)
        (xy 11.803 0.995)
        (xy 11.784 0.981)
        (xy 11.766 0.966)
        (xy 11.749 0.95)
        (xy 11.733 0.934)
        (xy 11.718 0.917)
        (xy 11.704 0.898)
        (xy 11.691 0.878)
        (xy 11.679 0.858)
        (xy 11.667 0.838)
        (xy 11.657 0.817)
        (xy 11.648 0.796)
        (xy 11.641 0.774)
        (xy 11.634 0.751)
        (xy 11.63 0.729)
        (xy 11.624 0.706)
        (xy 11.621 0.684)
        (xy 11.621 0.66)
        (xy 11.619 0.637)
        (xy 12.064 0.637)
        (xy 12.064 0.632)
        (xy 12.064 0.633)
      )

      (stroke (width 0.001) (type solid)) (fill solid) (layer "B.Paste"))
    (fp_poly
      (pts
        (xy 13.335 -4.447)
        (xy 12.89 -4.446)
        (xy 12.89 -4.469)
        (xy 12.891 -4.493)
        (xy 12.894 -4.515)
        (xy 12.9 -4.538)
        (xy 12.904 -4.56)
        (xy 12.912 -4.583)
        (xy 12.919 -4.605)
        (xy 12.928 -4.626)
        (xy 12.938 -4.647)
        (xy 12.948 -4.668)
        (xy 12.961 -4.687)
        (xy 12.974 -4.706)
        (xy 12.989 -4.725)
        (xy 13.003 -4.743)
        (xy 13.019 -4.759)
        (xy 13.037 -4.775)
        (xy 13.053 -4.791)
        (xy 13.073 -4.804)
        (xy 13.092 -4.817)
        (xy 13.111 -4.831)
        (xy 13.131 -4.841)
        (xy 13.153 -4.852)
        (xy 13.175 -4.86)
        (xy 13.196 -4.868)
        (xy 13.218 -4.874)
        (xy 13.24 -4.879)
        (xy 13.263 -4.884)
        (xy 13.287 -4.887)
        (xy 13.31 -4.889)
        (xy 13.335 -4.889)
        (xy 13.358 -4.889)
        (xy 13.381 -4.887)
        (xy 13.404 -4.884)
        (xy 13.428 -4.879)
        (xy 13.449 -4.874)
        (xy 13.473 -4.868)
        (xy 13.493 -4.86)
        (xy 13.515 -4.852)
        (xy 13.537 -4.841)
        (xy 13.557 -4.829)
        (xy 13.576 -4.817)
        (xy 13.596 -4.804)
        (xy 13.614 -4.791)
        (xy 13.632 -4.775)
        (xy 13.65 -4.759)
        (xy 13.666 -4.743)
        (xy 13.68 -4.724)
        (xy 13.694 -4.706)
        (xy 13.707 -4.687)
        (xy 13.72 -4.668)
        (xy 13.73 -4.647)
        (xy 13.742 -4.626)
        (xy 13.749 -4.603)
        (xy 13.757 -4.583)
        (xy 13.765 -4.559)
        (xy 13.769 -4.538)
        (xy 13.775 -4.514)
        (xy 13.778 -4.491)
        (xy 13.778 -4.467)
        (xy 13.779 -4.445)
        (xy 13.778 -4.421)
        (xy 13.778 -4.397)
        (xy 13.775 -4.374)
        (xy 13.769 -4.352)
        (xy 13.765 -4.329)
        (xy 13.757 -4.307)
        (xy 13.749 -4.285)
        (xy 13.742 -4.264)
        (xy 13.73 -4.243)
        (xy 13.72 -4.222)
        (xy 13.707 -4.203)
        (xy 13.694 -4.182)
        (xy 13.68 -4.164)
        (xy 13.666 -4.147)
        (xy 13.65 -4.129)
        (xy 13.632 -4.113)
        (xy 13.614 -4.099)
        (xy 13.596 -4.084)
        (xy 13.576 -4.071)
        (xy 13.557 -4.059)
        (xy 13.537 -4.049)
        (xy 13.515 -4.038)
        (xy 13.493 -4.03)
        (xy 13.473 -4.022)
        (xy 13.449 -4.014)
        (xy 13.428 -4.009)
        (xy 13.404 -4.004)
        (xy 13.381 -4.001)
        (xy 13.358 -4.001)
        (xy 13.335 -3.999)
        (xy 13.31 -4.001)
        (xy 13.287 -4.001)
        (xy 13.263 -4.004)
        (xy 13.24 -4.009)
        (xy 13.218 -4.014)
        (xy 13.196 -4.022)
        (xy 13.175 -4.028)
        (xy 13.153 -4.038)
        (xy 13.131 -4.047)
        (xy 13.111 -4.059)
        (xy 13.092 -4.071)
        (xy 13.073 -4.084)
        (xy 13.053 -4.099)
        (xy 13.037 -4.113)
        (xy 13.019 -4.129)
        (xy 13.003 -4.147)
        (xy 12.989 -4.163)
        (xy 12.974 -4.182)
        (xy 12.961 -4.201)
        (xy 12.948 -4.222)
        (xy 12.938 -4.241)
        (xy 12.928 -4.262)
        (xy 12.919 -4.285)
        (xy 12.912 -4.307)
        (xy 12.904 -4.328)
        (xy 12.9 -4.35)
        (xy 12.894 -4.373)
        (xy 12.891 -4.397)
        (xy 12.89 -4.421)
        (xy 12.89 -4.442)
        (xy 13.335 -4.442)
        (xy 13.335 -4.446)
        (xy 13.335 -4.447)
      )

      (stroke (width 0.001) (type solid)) (fill solid) (layer "B.Paste"))
    (fp_poly
      (pts
        (xy 13.335 -1.907)
        (xy 12.89 -1.906)
        (xy 12.89 -1.929)
        (xy 12.891 -1.953)
        (xy 12.894 -1.975)
        (xy 12.9 -1.999)
        (xy 12.904 -2.02)
        (xy 12.912 -2.043)
        (xy 12.919 -2.064)
        (xy 12.928 -2.087)
        (xy 12.938 -2.108)
        (xy 12.948 -2.128)
        (xy 12.961 -2.148)
        (xy 12.974 -2.166)
        (xy 12.989 -2.185)
        (xy 13.003 -2.202)
        (xy 13.019 -2.22)
        (xy 13.037 -2.236)
        (xy 13.053 -2.25)
        (xy 13.073 -2.265)
        (xy 13.092 -2.277)
        (xy 13.111 -2.29)
        (xy 13.131 -2.301)
        (xy 13.153 -2.311)
        (xy 13.175 -2.321)
        (xy 13.196 -2.327)
        (xy 13.218 -2.334)
        (xy 13.24 -2.339)
        (xy 13.263 -2.345)
        (xy 13.287 -2.347)
        (xy 13.31 -2.349)
        (xy 13.335 -2.35)
        (xy 13.358 -2.349)
        (xy 13.381 -2.347)
        (xy 13.404 -2.345)
        (xy 13.428 -2.339)
        (xy 13.449 -2.334)
        (xy 13.473 -2.327)
        (xy 13.493 -2.319)
        (xy 13.515 -2.311)
        (xy 13.537 -2.301)
        (xy 13.557 -2.289)
        (xy 13.576 -2.277)
        (xy 13.596 -2.265)
        (xy 13.614 -2.25)
        (xy 13.632 -2.236)
        (xy 13.65 -2.22)
        (xy 13.666 -2.202)
        (xy 13.68 -2.185)
        (xy 13.694 -2.166)
        (xy 13.707 -2.146)
        (xy 13.72 -2.128)
        (xy 13.73 -2.107)
        (xy 13.742 -2.085)
        (xy 13.749 -2.064)
        (xy 13.757 -2.043)
        (xy 13.765 -2.019)
        (xy 13.769 -1.997)
        (xy 13.775 -1.975)
        (xy 13.778 -1.951)
        (xy 13.778 -1.927)
        (xy 13.779 -1.904)
        (xy 13.778 -1.881)
        (xy 13.778 -1.858)
        (xy 13.775 -1.834)
        (xy 13.769 -1.812)
        (xy 13.765 -1.789)
        (xy 13.757 -1.766)
        (xy 13.749 -1.745)
        (xy 13.742 -1.723)
        (xy 13.73 -1.703)
        (xy 13.72 -1.681)
        (xy 13.707 -1.662)
        (xy 13.694 -1.642)
        (xy 13.68 -1.624)
        (xy 13.666 -1.606)
        (xy 13.65 -1.59)
        (xy 13.632 -1.574)
        (xy 13.614 -1.558)
        (xy 13.596 -1.544)
        (xy 13.576 -1.531)
        (xy 13.557 -1.519)
        (xy 13.537 -1.508)
        (xy 13.515 -1.497)
        (xy 13.493 -1.489)
        (xy 13.473 -1.481)
        (xy 13.449 -1.475)
        (xy 13.428 -1.469)
        (xy 13.404 -1.465)
        (xy 13.381 -1.461)
        (xy 13.358 -1.461)
        (xy 13.335 -1.459)
        (xy 13.31 -1.461)
        (xy 13.287 -1.461)
        (xy 13.263 -1.465)
        (xy 13.24 -1.469)
        (xy 13.218 -1.475)
        (xy 13.196 -1.481)
        (xy 13.175 -1.489)
        (xy 13.153 -1.497)
        (xy 13.131 -1.507)
        (xy 13.111 -1.518)
        (xy 13.092 -1.531)
        (xy 13.073 -1.544)
        (xy 13.053 -1.558)
        (xy 13.037 -1.574)
        (xy 13.019 -1.59)
        (xy 13.003 -1.606)
        (xy 12.989 -1.624)
        (xy 12.974 -1.642)
        (xy 12.961 -1.661)
        (xy 12.948 -1.681)
        (xy 12.938 -1.701)
        (xy 12.928 -1.723)
        (xy 12.919 -1.745)
        (xy 12.912 -1.766)
        (xy 12.904 -1.788)
        (xy 12.9 -1.81)
        (xy 12.894 -1.834)
        (xy 12.891 -1.856)
        (xy 12.89 -1.88)
        (xy 12.89 -1.902)
        (xy 13.335 -1.902)
        (xy 13.335 -1.906)
        (xy 13.335 -1.907)
      )

      (stroke (width 0.001) (type solid)) (fill solid) (layer "B.Paste"))
    (fp_poly
      (pts
        (xy 13.335 -0.637)
        (xy 12.89 -0.636)
        (xy 12.89 -0.659)
        (xy 12.891 -0.683)
        (xy 12.894 -0.705)
        (xy 12.9 -0.728)
        (xy 12.904 -0.75)
        (xy 12.912 -0.773)
        (xy 12.919 -0.795)
        (xy 12.928 -0.816)
        (xy 12.938 -0.837)
        (xy 12.948 -0.857)
        (xy 12.961 -0.877)
        (xy 12.974 -0.897)
        (xy 12.989 -0.916)
        (xy 13.003 -0.933)
        (xy 13.019 -0.949)
        (xy 13.037 -0.965)
        (xy 13.053 -0.98)
        (xy 13.073 -0.994)
        (xy 13.092 -1.007)
        (xy 13.111 -1.02)
        (xy 13.131 -1.032)
        (xy 13.153 -1.042)
        (xy 13.175 -1.05)
        (xy 13.196 -1.058)
        (xy 13.218 -1.064)
        (xy 13.24 -1.07)
        (xy 13.263 -1.074)
        (xy 13.287 -1.078)
        (xy 13.31 -1.078)
        (xy 13.335 -1.08)
        (xy 13.358 -1.078)
        (xy 13.381 -1.078)
        (xy 13.404 -1.074)
        (xy 13.428 -1.07)
        (xy 13.449 -1.064)
        (xy 13.473 -1.058)
        (xy 13.493 -1.05)
        (xy 13.515 -1.042)
        (xy 13.537 -1.03)
        (xy 13.557 -1.019)
        (xy 13.576 -1.007)
        (xy 13.596 -0.994)
        (xy 13.614 -0.98)
        (xy 13.632 -0.965)
        (xy 13.65 -0.949)
        (xy 13.666 -0.933)
        (xy 13.68 -0.915)
        (xy 13.694 -0.897)
        (xy 13.707 -0.876)
        (xy 13.72 -0.857)
        (xy 13.73 -0.836)
        (xy 13.742 -0.815)
        (xy 13.749 -0.794)
        (xy 13.757 -0.773)
        (xy 13.765 -0.749)
        (xy 13.769 -0.727)
        (xy 13.775 -0.704)
        (xy 13.778 -0.682)
        (xy 13.778 -0.658)
        (xy 13.779 -0.634)
        (xy 13.778 -0.611)
        (xy 13.778 -0.587)
        (xy 13.775 -0.564)
        (xy 13.769 -0.542)
        (xy 13.765 -0.52)
        (xy 13.757 -0.496)
        (xy 13.749 -0.475)
        (xy 13.742 -0.454)
        (xy 13.73 -0.432)
        (xy 13.72 -0.411)
        (xy 13.707 -0.393)
        (xy 13.694 -0.372)
        (xy 13.68 -0.354)
        (xy 13.666 -0.337)
        (xy 13.65 -0.32)
        (xy 13.632 -0.303)
        (xy 13.614 -0.288)
        (xy 13.596 -0.275)
        (xy 13.576 -0.262)
        (xy 13.557 -0.249)
        (xy 13.537 -0.238)
        (xy 13.515 -0.228)
        (xy 13.493 -0.219)
        (xy 13.473 -0.211)
        (xy 13.449 -0.204)
        (xy 13.428 -0.2)
        (xy 13.404 -0.195)
        (xy 13.381 -0.192)
        (xy 13.358 -0.19)
        (xy 13.335 -0.189)
        (xy 13.31 -0.19)
        (xy 13.287 -0.192)
        (xy 13.263 -0.195)
        (xy 13.24 -0.2)
        (xy 13.218 -0.204)
        (xy 13.196 -0.211)
        (xy 13.175 -0.218)
        (xy 13.153 -0.228)
        (xy 13.131 -0.237)
        (xy 13.111 -0.248)
        (xy 13.092 -0.262)
        (xy 13.073 -0.275)
        (xy 13.053 -0.288)
        (xy 13.037 -0.303)
        (xy 13.019 -0.32)
        (xy 13.003 -0.337)
        (xy 12.989 -0.353)
        (xy 12.974 -0.372)
        (xy 12.961 -0.392)
        (xy 12.948 -0.411)
        (xy 12.938 -0.431)
        (xy 12.928 -0.453)
        (xy 12.919 -0.474)
        (xy 12.912 -0.496)
        (xy 12.904 -0.519)
        (xy 12.9 -0.541)
        (xy 12.894 -0.563)
        (xy 12.891 -0.586)
        (xy 12.89 -0.61)
        (xy 12.89 -0.631)
        (xy 13.335 -0.631)
        (xy 13.335 -0.636)
        (xy 13.335 -0.637)
      )

      (stroke (width 0.001) (type solid)) (fill solid) (layer "B.Paste"))
    (fp_poly
      (pts
        (xy 13.335 0.633)
        (xy 12.89 0.632)
        (xy 12.89 0.611)
        (xy 12.891 0.587)
        (xy 12.894 0.564)
        (xy 12.9 0.542)
        (xy 12.904 0.52)
        (xy 12.912 0.497)
        (xy 12.919 0.475)
        (xy 12.928 0.454)
        (xy 12.938 0.432)
        (xy 12.948 0.412)
        (xy 12.961 0.393)
        (xy 12.974 0.373)
        (xy 12.989 0.354)
        (xy 13.003 0.338)
        (xy 13.019 0.32)
        (xy 13.037 0.304)
        (xy 13.053 0.289)
        (xy 13.073 0.276)
        (xy 13.092 0.263)
        (xy 13.111 0.249)
        (xy 13.131 0.238)
        (xy 13.153 0.229)
        (xy 13.175 0.219)
        (xy 13.196 0.212)
        (xy 13.218 0.205)
        (xy 13.24 0.201)
        (xy 13.263 0.196)
        (xy 13.287 0.192)
        (xy 13.31 0.191)
        (xy 13.335 0.19)
        (xy 13.358 0.191)
        (xy 13.381 0.192)
        (xy 13.404 0.196)
        (xy 13.428 0.201)
        (xy 13.449 0.205)
        (xy 13.473 0.212)
        (xy 13.493 0.22)
        (xy 13.515 0.229)
        (xy 13.537 0.239)
        (xy 13.557 0.25)
        (xy 13.576 0.263)
        (xy 13.596 0.276)
        (xy 13.614 0.289)
        (xy 13.632 0.304)
        (xy 13.65 0.32)
        (xy 13.666 0.338)
        (xy 13.68 0.355)
        (xy 13.694 0.373)
        (xy 13.707 0.394)
        (xy 13.72 0.412)
        (xy 13.73 0.433)
        (xy 13.742 0.455)
        (xy 13.749 0.476)
        (xy 13.757 0.497)
        (xy 13.765 0.521)
        (xy 13.769 0.543)
        (xy 13.775 0.565)
        (xy 13.778 0.588)
        (xy 13.778 0.612)
        (xy 13.779 0.635)
        (xy 13.778 0.659)
        (xy 13.778 0.683)
        (xy 13.775 0.705)
        (xy 13.769 0.728)
        (xy 13.765 0.75)
        (xy 13.757 0.774)
        (xy 13.749 0.795)
        (xy 13.742 0.816)
        (xy 13.73 0.837)
        (xy 13.72 0.858)
        (xy 13.707 0.877)
        (xy 13.694 0.898)
        (xy 13.68 0.916)
        (xy 13.666 0.934)
        (xy 13.65 0.95)
        (xy 13.632 0.966)
        (xy 13.614 0.981)
        (xy 13.596 0.995)
        (xy 13.576 1.008)
        (xy 13.557 1.02)
        (xy 13.537 1.031)
        (xy 13.515 1.043)
        (xy 13.493 1.051)
        (xy 13.473 1.059)
        (xy 13.449 1.065)
        (xy 13.428 1.071)
        (xy 13.404 1.075)
        (xy 13.381 1.079)
        (xy 13.358 1.079)
        (xy 13.335 1.081)
        (xy 13.31 1.079)
        (xy 13.287 1.079)
        (xy 13.263 1.075)
        (xy 13.24 1.071)
        (xy 13.218 1.065)
        (xy 13.196 1.059)
        (xy 13.175 1.051)
        (xy 13.153 1.043)
        (xy 13.131 1.033)
        (xy 13.111 1.021)
        (xy 13.092 1.008)
        (xy 13.073 0.995)
        (xy 13.053 0.981)
        (xy 13.037 0.966)
        (xy 13.019 0.95)
        (xy 13.003 0.934)
        (xy 12.989 0.917)
        (xy 12.974 0.898)
        (xy 12.961 0.878)
        (xy 12.948 0.858)
        (xy 12.938 0.838)
        (xy 12.928 0.817)
        (xy 12.919 0.796)
        (xy 12.912 0.774)
        (xy 12.904 0.751)
        (xy 12.9 0.729)
        (xy 12.894 0.706)
        (xy 12.891 0.684)
        (xy 12.89 0.66)
        (xy 12.89 0.637)
        (xy 13.335 0.637)
        (xy 13.335 0.632)
        (xy 13.335 0.633)
      )

      (stroke (width 0.001) (type solid)) (fill solid) (layer "B.Paste"))
    (fp_poly
      (pts
        (xy 14.605 -4.447)
        (xy 14.159 -4.446)
        (xy 14.16 -4.469)
        (xy 14.162 -4.493)
        (xy 14.164 -4.515)
        (xy 14.169 -4.538)
        (xy 14.175 -4.56)
        (xy 14.182 -4.583)
        (xy 14.188 -4.605)
        (xy 14.198 -4.626)
        (xy 14.207 -4.647)
        (xy 14.218 -4.668)
        (xy 14.231 -4.687)
        (xy 14.244 -4.706)
        (xy 14.259 -4.725)
        (xy 14.273 -4.743)
        (xy 14.289 -4.759)
        (xy 14.307 -4.775)
        (xy 14.323 -4.791)
        (xy 14.342 -4.804)
        (xy 14.361 -4.817)
        (xy 14.381 -4.831)
        (xy 14.401 -4.841)
        (xy 14.422 -4.852)
        (xy 14.444 -4.86)
        (xy 14.467 -4.868)
        (xy 14.489 -4.874)
        (xy 14.51 -4.879)
        (xy 14.534 -4.884)
        (xy 14.557 -4.887)
        (xy 14.58 -4.889)
        (xy 14.605 -4.889)
        (xy 14.627 -4.889)
        (xy 14.651 -4.887)
        (xy 14.675 -4.884)
        (xy 14.698 -4.879)
        (xy 14.72 -4.874)
        (xy 14.743 -4.868)
        (xy 14.763 -4.86)
        (xy 14.785 -4.852)
        (xy 14.807 -4.841)
        (xy 14.827 -4.829)
        (xy 14.846 -4.817)
        (xy 14.867 -4.804)
        (xy 14.884 -4.791)
        (xy 14.903 -4.775)
        (xy 14.919 -4.759)
        (xy 14.935 -4.743)
        (xy 14.951 -4.724)
        (xy 14.964 -4.706)
        (xy 14.977 -4.687)
        (xy 14.989 -4.668)
        (xy 15 -4.647)
        (xy 15.012 -4.626)
        (xy 15.019 -4.603)
        (xy 15.028 -4.583)
        (xy 15.034 -4.559)
        (xy 15.039 -4.538)
        (xy 15.044 -4.514)
        (xy 15.047 -4.491)
        (xy 15.048 -4.467)
        (xy 15.05 -4.445)
        (xy 15.048 -4.421)
        (xy 15.047 -4.397)
        (xy 15.044 -4.374)
        (xy 15.039 -4.352)
        (xy 15.034 -4.329)
        (xy 15.028 -4.307)
        (xy 15.019 -4.285)
        (xy 15.012 -4.264)
        (xy 15 -4.243)
        (xy 14.989 -4.222)
        (xy 14.977 -4.203)
        (xy 14.964 -4.182)
        (xy 14.951 -4.164)
        (xy 14.935 -4.147)
        (xy 14.919 -4.129)
        (xy 14.903 -4.113)
        (xy 14.884 -4.099)
        (xy 14.867 -4.084)
        (xy 14.846 -4.071)
        (xy 14.827 -4.059)
        (xy 14.807 -4.049)
        (xy 14.785 -4.038)
        (xy 14.763 -4.03)
        (xy 14.743 -4.022)
        (xy 14.72 -4.014)
        (xy 14.698 -4.009)
        (xy 14.675 -4.004)
        (xy 14.651 -4.001)
        (xy 14.627 -4.001)
        (xy 14.605 -3.999)
        (xy 14.58 -4.001)
        (xy 14.557 -4.001)
        (xy 14.534 -4.004)
        (xy 14.51 -4.009)
        (xy 14.489 -4.014)
        (xy 14.467 -4.022)
        (xy 14.444 -4.028)
        (xy 14.422 -4.038)
        (xy 14.401 -4.047)
        (xy 14.381 -4.059)
        (xy 14.361 -4.071)
        (xy 14.342 -4.084)
        (xy 14.323 -4.099)
        (xy 14.307 -4.113)
        (xy 14.289 -4.129)
        (xy 14.273 -4.147)
        (xy 14.259 -4.163)
        (xy 14.244 -4.182)
        (xy 14.231 -4.201)
        (xy 14.218 -4.222)
        (xy 14.207 -4.241)
        (xy 14.198 -4.262)
        (xy 14.188 -4.285)
        (xy 14.182 -4.307)
        (xy 14.175 -4.328)
        (xy 14.169 -4.35)
        (xy 14.164 -4.373)
        (xy 14.162 -4.397)
        (xy 14.16 -4.421)
        (xy 14.159 -4.442)
        (xy 14.605 -4.442)
        (xy 14.605 -4.446)
        (xy 14.605 -4.447)
      )

      (stroke (width 0.001) (type solid)) (fill solid) (layer "B.Paste"))
    (fp_poly
      (pts
        (xy 14.605 -1.907)
        (xy 14.159 -1.906)
        (xy 14.16 -1.929)
        (xy 14.162 -1.953)
        (xy 14.164 -1.975)
        (xy 14.169 -1.999)
        (xy 14.175 -2.02)
        (xy 14.182 -2.043)
        (xy 14.188 -2.064)
        (xy 14.198 -2.087)
        (xy 14.207 -2.108)
        (xy 14.218 -2.128)
        (xy 14.231 -2.148)
        (xy 14.244 -2.166)
        (xy 14.259 -2.185)
        (xy 14.273 -2.202)
        (xy 14.289 -2.22)
        (xy 14.307 -2.236)
        (xy 14.323 -2.25)
        (xy 14.342 -2.265)
        (xy 14.361 -2.277)
        (xy 14.381 -2.29)
        (xy 14.401 -2.301)
        (xy 14.422 -2.311)
        (xy 14.444 -2.321)
        (xy 14.467 -2.327)
        (xy 14.489 -2.334)
        (xy 14.51 -2.339)
        (xy 14.534 -2.345)
        (xy 14.557 -2.347)
        (xy 14.58 -2.349)
        (xy 14.605 -2.35)
        (xy 14.627 -2.349)
        (xy 14.651 -2.347)
        (xy 14.675 -2.345)
        (xy 14.698 -2.339)
        (xy 14.72 -2.334)
        (xy 14.743 -2.327)
        (xy 14.763 -2.319)
        (xy 14.785 -2.311)
        (xy 14.807 -2.301)
        (xy 14.827 -2.289)
        (xy 14.846 -2.277)
        (xy 14.867 -2.265)
        (xy 14.884 -2.25)
        (xy 14.903 -2.236)
        (xy 14.919 -2.22)
        (xy 14.935 -2.202)
        (xy 14.951 -2.185)
        (xy 14.964 -2.166)
        (xy 14.977 -2.146)
        (xy 14.989 -2.126)
        (xy 15 -2.107)
        (xy 15.012 -2.085)
        (xy 15.019 -2.064)
        (xy 15.028 -2.043)
        (xy 15.034 -2.019)
        (xy 15.039 -1.997)
        (xy 15.044 -1.975)
        (xy 15.047 -1.951)
        (xy 15.048 -1.927)
        (xy 15.05 -1.904)
        (xy 15.048 -1.881)
        (xy 15.047 -1.858)
        (xy 15.044 -1.834)
        (xy 15.039 -1.812)
        (xy 15.034 -1.789)
        (xy 15.028 -1.766)
        (xy 15.019 -1.745)
        (xy 15.012 -1.723)
        (xy 15 -1.703)
        (xy 14.989 -1.683)
        (xy 14.977 -1.662)
        (xy 14.964 -1.642)
        (xy 14.951 -1.624)
        (xy 14.935 -1.606)
        (xy 14.919 -1.59)
        (xy 14.903 -1.574)
        (xy 14.884 -1.558)
        (xy 14.867 -1.544)
        (xy 14.846 -1.531)
        (xy 14.827 -1.519)
        (xy 14.807 -1.508)
        (xy 14.785 -1.497)
        (xy 14.763 -1.489)
        (xy 14.743 -1.481)
        (xy 14.72 -1.475)
        (xy 14.698 -1.469)
        (xy 14.675 -1.465)
        (xy 14.651 -1.461)
        (xy 14.627 -1.461)
        (xy 14.605 -1.459)
        (xy 14.58 -1.461)
        (xy 14.557 -1.461)
        (xy 14.534 -1.465)
        (xy 14.51 -1.469)
        (xy 14.489 -1.475)
        (xy 14.467 -1.481)
        (xy 14.444 -1.489)
        (xy 14.422 -1.497)
        (xy 14.401 -1.507)
        (xy 14.381 -1.518)
        (xy 14.361 -1.531)
        (xy 14.342 -1.544)
        (xy 14.323 -1.558)
        (xy 14.307 -1.574)
        (xy 14.289 -1.59)
        (xy 14.273 -1.606)
        (xy 14.259 -1.624)
        (xy 14.244 -1.642)
        (xy 14.231 -1.661)
        (xy 14.218 -1.681)
        (xy 14.207 -1.701)
        (xy 14.198 -1.723)
        (xy 14.188 -1.745)
        (xy 14.182 -1.766)
        (xy 14.175 -1.788)
        (xy 14.169 -1.81)
        (xy 14.164 -1.834)
        (xy 14.162 -1.856)
        (xy 14.16 -1.88)
        (xy 14.159 -1.902)
        (xy 14.605 -1.902)
        (xy 14.605 -1.906)
        (xy 14.605 -1.907)
      )

      (stroke (width 0.001) (type solid)) (fill solid) (layer "B.Paste"))
    (fp_poly
      (pts
        (xy 14.605 -0.637)
        (xy 14.159 -0.636)
        (xy 14.16 -0.659)
        (xy 14.162 -0.683)
        (xy 14.164 -0.705)
        (xy 14.169 -0.728)
        (xy 14.175 -0.75)
        (xy 14.182 -0.773)
        (xy 14.188 -0.795)
        (xy 14.198 -0.816)
        (xy 14.207 -0.837)
        (xy 14.218 -0.857)
        (xy 14.231 -0.877)
        (xy 14.244 -0.897)
        (xy 14.259 -0.916)
        (xy 14.273 -0.933)
        (xy 14.289 -0.949)
        (xy 14.307 -0.965)
        (xy 14.323 -0.98)
        (xy 14.342 -0.994)
        (xy 14.361 -1.007)
        (xy 14.381 -1.02)
        (xy 14.401 -1.032)
        (xy 14.422 -1.042)
        (xy 14.444 -1.05)
        (xy 14.467 -1.058)
        (xy 14.489 -1.064)
        (xy 14.51 -1.07)
        (xy 14.534 -1.074)
        (xy 14.557 -1.078)
        (xy 14.58 -1.078)
        (xy 14.605 -1.08)
        (xy 14.627 -1.078)
        (xy 14.651 -1.078)
        (xy 14.675 -1.074)
        (xy 14.698 -1.07)
        (xy 14.72 -1.064)
        (xy 14.743 -1.058)
        (xy 14.763 -1.05)
        (xy 14.785 -1.042)
        (xy 14.807 -1.03)
        (xy 14.827 -1.019)
        (xy 14.846 -1.007)
        (xy 14.867 -0.994)
        (xy 14.884 -0.98)
        (xy 14.903 -0.965)
        (xy 14.919 -0.949)
        (xy 14.935 -0.933)
        (xy 14.951 -0.915)
        (xy 14.964 -0.897)
        (xy 14.977 -0.876)
        (xy 14.989 -0.856)
        (xy 15 -0.836)
        (xy 15.012 -0.815)
        (xy 15.019 -0.794)
        (xy 15.028 -0.773)
        (xy 15.034 -0.749)
        (xy 15.039 -0.727)
        (xy 15.044 -0.704)
        (xy 15.047 -0.682)
        (xy 15.048 -0.658)
        (xy 15.05 -0.634)
        (xy 15.048 -0.611)
        (xy 15.047 -0.587)
        (xy 15.044 -0.564)
        (xy 15.039 -0.542)
        (xy 15.034 -0.52)
        (xy 15.028 -0.496)
        (xy 15.019 -0.475)
        (xy 15.012 -0.454)
        (xy 15 -0.432)
        (xy 14.989 -0.412)
        (xy 14.977 -0.393)
        (xy 14.964 -0.372)
        (xy 14.951 -0.354)
        (xy 14.935 -0.337)
        (xy 14.919 -0.32)
        (xy 14.903 -0.303)
        (xy 14.884 -0.288)
        (xy 14.867 -0.275)
        (xy 14.846 -0.262)
        (xy 14.827 -0.249)
        (xy 14.807 -0.238)
        (xy 14.785 -0.228)
        (xy 14.763 -0.219)
        (xy 14.743 -0.211)
        (xy 14.72 -0.204)
        (xy 14.698 -0.2)
        (xy 14.675 -0.195)
        (xy 14.651 -0.192)
        (xy 14.627 -0.19)
        (xy 14.605 -0.189)
        (xy 14.58 -0.19)
        (xy 14.557 -0.192)
        (xy 14.534 -0.195)
        (xy 14.51 -0.2)
        (xy 14.489 -0.204)
        (xy 14.467 -0.211)
        (xy 14.444 -0.218)
        (xy 14.422 -0.228)
        (xy 14.401 -0.237)
        (xy 14.381 -0.248)
        (xy 14.361 -0.262)
        (xy 14.342 -0.275)
        (xy 14.323 -0.288)
        (xy 14.307 -0.303)
        (xy 14.289 -0.32)
        (xy 14.273 -0.337)
        (xy 14.259 -0.353)
        (xy 14.244 -0.372)
        (xy 14.231 -0.392)
        (xy 14.218 -0.411)
        (xy 14.207 -0.431)
        (xy 14.198 -0.453)
        (xy 14.188 -0.474)
        (xy 14.182 -0.496)
        (xy 14.175 -0.519)
        (xy 14.169 -0.541)
        (xy 14.164 -0.563)
        (xy 14.162 -0.586)
        (xy 14.16 -0.61)
        (xy 14.159 -0.631)
        (xy 14.605 -0.631)
        (xy 14.605 -0.636)
        (xy 14.605 -0.637)
      )

      (stroke (width 0.001) (type solid)) (fill solid) (layer "B.Paste"))
    (fp_poly
      (pts
        (xy 14.605 0.633)
        (xy 14.159 0.632)
        (xy 14.16 0.611)
        (xy 14.162 0.587)
        (xy 14.164 0.564)
        (xy 14.169 0.542)
        (xy 14.175 0.52)
        (xy 14.182 0.497)
        (xy 14.188 0.475)
        (xy 14.198 0.454)
        (xy 14.207 0.432)
        (xy 14.218 0.412)
        (xy 14.231 0.393)
        (xy 14.244 0.373)
        (xy 14.259 0.354)
        (xy 14.273 0.338)
        (xy 14.289 0.32)
        (xy 14.307 0.304)
        (xy 14.323 0.289)
        (xy 14.342 0.276)
        (xy 14.361 0.263)
        (xy 14.381 0.249)
        (xy 14.401 0.238)
        (xy 14.422 0.229)
        (xy 14.444 0.219)
        (xy 14.467 0.212)
        (xy 14.489 0.205)
        (xy 14.51 0.201)
        (xy 14.534 0.196)
        (xy 14.557 0.192)
        (xy 14.58 0.191)
        (xy 14.605 0.19)
        (xy 14.627 0.191)
        (xy 14.651 0.192)
        (xy 14.675 0.196)
        (xy 14.698 0.201)
        (xy 14.72 0.205)
        (xy 14.743 0.212)
        (xy 14.763 0.22)
        (xy 14.785 0.229)
        (xy 14.807 0.239)
        (xy 14.827 0.25)
        (xy 14.846 0.263)
        (xy 14.867 0.276)
        (xy 14.884 0.289)
        (xy 14.903 0.304)
        (xy 14.919 0.32)
        (xy 14.935 0.338)
        (xy 14.951 0.355)
        (xy 14.964 0.373)
        (xy 14.977 0.394)
        (xy 14.989 0.413)
        (xy 15 0.433)
        (xy 15.012 0.455)
        (xy 15.019 0.476)
        (xy 15.028 0.497)
        (xy 15.034 0.521)
        (xy 15.039 0.543)
        (xy 15.044 0.565)
        (xy 15.047 0.588)
        (xy 15.048 0.612)
        (xy 15.05 0.635)
        (xy 15.048 0.659)
        (xy 15.047 0.683)
        (xy 15.044 0.705)
        (xy 15.039 0.728)
        (xy 15.034 0.75)
        (xy 15.028 0.774)
        (xy 15.019 0.795)
        (xy 15.012 0.816)
        (xy 15 0.837)
        (xy 14.989 0.857)
        (xy 14.977 0.877)
        (xy 14.964 0.898)
        (xy 14.951 0.916)
        (xy 14.935 0.934)
        (xy 14.919 0.95)
        (xy 14.903 0.966)
        (xy 14.884 0.981)
        (xy 14.867 0.995)
        (xy 14.846 1.008)
        (xy 14.827 1.02)
        (xy 14.807 1.031)
        (xy 14.785 1.043)
        (xy 14.763 1.051)
        (xy 14.743 1.059)
        (xy 14.72 1.065)
        (xy 14.698 1.071)
        (xy 14.675 1.075)
        (xy 14.651 1.079)
        (xy 14.627 1.079)
        (xy 14.605 1.081)
        (xy 14.58 1.079)
        (xy 14.557 1.079)
        (xy 14.534 1.075)
        (xy 14.51 1.071)
        (xy 14.489 1.065)
        (xy 14.467 1.059)
        (xy 14.444 1.051)
        (xy 14.422 1.043)
        (xy 14.401 1.033)
        (xy 14.381 1.021)
        (xy 14.361 1.008)
        (xy 14.342 0.995)
        (xy 14.323 0.981)
        (xy 14.307 0.966)
        (xy 14.289 0.95)
        (xy 14.273 0.934)
        (xy 14.259 0.917)
        (xy 14.244 0.898)
        (xy 14.231 0.878)
        (xy 14.218 0.858)
        (xy 14.207 0.838)
        (xy 14.198 0.817)
        (xy 14.188 0.796)
        (xy 14.182 0.774)
        (xy 14.175 0.751)
        (xy 14.169 0.729)
        (xy 14.164 0.706)
        (xy 14.162 0.684)
        (xy 14.16 0.66)
        (xy 14.159 0.637)
        (xy 14.605 0.637)
        (xy 14.605 0.632)
        (xy 14.605 0.633)
      )

      (stroke (width 0.001) (type solid)) (fill solid) (layer "B.Paste"))
    (fp_poly
      (pts
        (xy 15.874 -4.447)
        (xy 15.429 -4.446)
        (xy 15.43 -4.469)
        (xy 15.432 -4.493)
        (xy 15.435 -4.515)
        (xy 15.439 -4.538)
        (xy 15.444 -4.56)
        (xy 15.451 -4.583)
        (xy 15.458 -4.605)
        (xy 15.467 -4.626)
        (xy 15.477 -4.647)
        (xy 15.489 -4.668)
        (xy 15.502 -4.687)
        (xy 15.515 -4.706)
        (xy 15.528 -4.725)
        (xy 15.544 -4.743)
        (xy 15.56 -4.759)
        (xy 15.576 -4.775)
        (xy 15.593 -4.791)
        (xy 15.612 -4.804)
        (xy 15.631 -4.817)
        (xy 15.651 -4.831)
        (xy 15.672 -4.841)
        (xy 15.692 -4.852)
        (xy 15.714 -4.86)
        (xy 15.736 -4.868)
        (xy 15.759 -4.874)
        (xy 15.781 -4.879)
        (xy 15.803 -4.884)
        (xy 15.826 -4.887)
        (xy 15.851 -4.889)
        (xy 15.874 -4.889)
        (xy 15.897 -4.889)
        (xy 15.922 -4.887)
        (xy 15.944 -4.884)
        (xy 15.967 -4.879)
        (xy 15.989 -4.874)
        (xy 16.013 -4.868)
        (xy 16.033 -4.86)
        (xy 16.056 -4.852)
        (xy 16.077 -4.841)
        (xy 16.097 -4.829)
        (xy 16.117 -4.817)
        (xy 16.137 -4.804)
        (xy 16.155 -4.791)
        (xy 16.172 -4.775)
        (xy 16.19 -4.759)
        (xy 16.205 -4.743)
        (xy 16.22 -4.724)
        (xy 16.234 -4.706)
        (xy 16.248 -4.687)
        (xy 16.26 -4.668)
        (xy 16.271 -4.647)
        (xy 16.281 -4.626)
        (xy 16.289 -4.603)
        (xy 16.297 -4.583)
        (xy 16.304 -4.559)
        (xy 16.309 -4.538)
        (xy 16.315 -4.514)
        (xy 16.318 -4.491)
        (xy 16.318 -4.467)
        (xy 16.319 -4.445)
        (xy 16.318 -4.421)
        (xy 16.318 -4.397)
        (xy 16.315 -4.374)
        (xy 16.309 -4.352)
        (xy 16.304 -4.329)
        (xy 16.297 -4.307)
        (xy 16.289 -4.285)
        (xy 16.281 -4.264)
        (xy 16.271 -4.243)
        (xy 16.26 -4.222)
        (xy 16.248 -4.203)
        (xy 16.234 -4.182)
        (xy 16.22 -4.164)
        (xy 16.205 -4.147)
        (xy 16.19 -4.129)
        (xy 16.172 -4.113)
        (xy 16.155 -4.099)
        (xy 16.137 -4.084)
        (xy 16.117 -4.071)
        (xy 16.097 -4.059)
        (xy 16.077 -4.049)
        (xy 16.056 -4.038)
        (xy 16.033 -4.03)
        (xy 16.013 -4.022)
        (xy 15.989 -4.014)
        (xy 15.967 -4.009)
        (xy 15.944 -4.004)
        (xy 15.922 -4.001)
        (xy 15.897 -4.001)
        (xy 15.874 -3.999)
        (xy 15.851 -4.001)
        (xy 15.826 -4.001)
        (xy 15.803 -4.004)
        (xy 15.781 -4.009)
        (xy 15.759 -4.014)
        (xy 15.736 -4.022)
        (xy 15.714 -4.028)
        (xy 15.692 -4.038)
        (xy 15.672 -4.047)
        (xy 15.651 -4.059)
        (xy 15.631 -4.071)
        (xy 15.612 -4.084)
        (xy 15.593 -4.099)
        (xy 15.576 -4.113)
        (xy 15.56 -4.129)
        (xy 15.544 -4.147)
        (xy 15.528 -4.163)
        (xy 15.515 -4.182)
        (xy 15.502 -4.201)
        (xy 15.489 -4.222)
        (xy 15.477 -4.241)
        (xy 15.467 -4.262)
        (xy 15.458 -4.285)
        (xy 15.451 -4.307)
        (xy 15.444 -4.328)
        (xy 15.439 -4.35)
        (xy 15.435 -4.373)
        (xy 15.432 -4.397)
        (xy 15.43 -4.421)
        (xy 15.429 -4.442)
        (xy 15.874 -4.442)
        (xy 15.874 -4.446)
        (xy 15.874 -4.447)
      )

      (stroke (width 0.001) (type solid)) (fill solid) (layer "B.Paste"))
    (fp_poly
      (pts
        (xy 15.874 -1.907)
        (xy 15.429 -1.906)
        (xy 15.43 -1.929)
        (xy 15.432 -1.953)
        (xy 15.435 -1.975)
        (xy 15.439 -1.999)
        (xy 15.444 -2.02)
        (xy 15.451 -2.043)
        (xy 15.458 -2.064)
        (xy 15.467 -2.087)
        (xy 15.477 -2.108)
        (xy 15.489 -2.128)
        (xy 15.502 -2.148)
        (xy 15.515 -2.166)
        (xy 15.528 -2.185)
        (xy 15.544 -2.202)
        (xy 15.56 -2.22)
        (xy 15.576 -2.236)
        (xy 15.593 -2.25)
        (xy 15.612 -2.265)
        (xy 15.631 -2.277)
        (xy 15.651 -2.29)
        (xy 15.672 -2.301)
        (xy 15.692 -2.311)
        (xy 15.714 -2.321)
        (xy 15.736 -2.327)
        (xy 15.759 -2.334)
        (xy 15.781 -2.339)
        (xy 15.803 -2.345)
        (xy 15.826 -2.347)
        (xy 15.851 -2.349)
        (xy 15.874 -2.35)
        (xy 15.897 -2.349)
        (xy 15.922 -2.347)
        (xy 15.944 -2.345)
        (xy 15.967 -2.339)
        (xy 15.989 -2.334)
        (xy 16.013 -2.327)
        (xy 16.033 -2.319)
        (xy 16.056 -2.311)
        (xy 16.077 -2.301)
        (xy 16.097 -2.289)
        (xy 16.117 -2.277)
        (xy 16.137 -2.265)
        (xy 16.155 -2.25)
        (xy 16.172 -2.236)
        (xy 16.19 -2.22)
        (xy 16.205 -2.202)
        (xy 16.22 -2.185)
        (xy 16.234 -2.166)
        (xy 16.248 -2.146)
        (xy 16.26 -2.126)
        (xy 16.271 -2.107)
        (xy 16.281 -2.085)
        (xy 16.289 -2.064)
        (xy 16.297 -2.043)
        (xy 16.304 -2.019)
        (xy 16.309 -1.997)
        (xy 16.315 -1.975)
        (xy 16.318 -1.951)
        (xy 16.318 -1.927)
        (xy 16.319 -1.904)
        (xy 16.318 -1.881)
        (xy 16.318 -1.858)
        (xy 16.315 -1.834)
        (xy 16.309 -1.812)
        (xy 16.304 -1.789)
        (xy 16.297 -1.766)
        (xy 16.289 -1.745)
        (xy 16.281 -1.723)
        (xy 16.271 -1.703)
        (xy 16.26 -1.683)
        (xy 16.248 -1.662)
        (xy 16.234 -1.642)
        (xy 16.22 -1.624)
        (xy 16.205 -1.606)
        (xy 16.19 -1.59)
        (xy 16.172 -1.574)
        (xy 16.155 -1.558)
        (xy 16.137 -1.544)
        (xy 16.117 -1.531)
        (xy 16.097 -1.519)
        (xy 16.077 -1.508)
        (xy 16.056 -1.497)
        (xy 16.033 -1.489)
        (xy 16.013 -1.481)
        (xy 15.989 -1.475)
        (xy 15.967 -1.469)
        (xy 15.944 -1.465)
        (xy 15.922 -1.461)
        (xy 15.897 -1.461)
        (xy 15.874 -1.459)
        (xy 15.851 -1.461)
        (xy 15.826 -1.461)
        (xy 15.803 -1.465)
        (xy 15.781 -1.469)
        (xy 15.759 -1.475)
        (xy 15.736 -1.481)
        (xy 15.714 -1.489)
        (xy 15.692 -1.497)
        (xy 15.672 -1.507)
        (xy 15.651 -1.518)
        (xy 15.631 -1.531)
        (xy 15.612 -1.544)
        (xy 15.593 -1.558)
        (xy 15.576 -1.574)
        (xy 15.56 -1.59)
        (xy 15.544 -1.606)
        (xy 15.528 -1.624)
        (xy 15.515 -1.642)
        (xy 15.502 -1.661)
        (xy 15.489 -1.681)
        (xy 15.477 -1.701)
        (xy 15.467 -1.723)
        (xy 15.458 -1.745)
        (xy 15.451 -1.766)
        (xy 15.444 -1.788)
        (xy 15.439 -1.81)
        (xy 15.435 -1.834)
        (xy 15.432 -1.856)
        (xy 15.43 -1.88)
        (xy 15.429 -1.902)
        (xy 15.874 -1.902)
        (xy 15.874 -1.906)
        (xy 15.874 -1.907)
      )

      (stroke (width 0.001) (type solid)) (fill solid) (layer "B.Paste"))
    (fp_poly
      (pts
        (xy 15.874 -0.637)
        (xy 15.429 -0.636)
        (xy 15.43 -0.659)
        (xy 15.432 -0.683)
        (xy 15.435 -0.705)
        (xy 15.439 -0.728)
        (xy 15.444 -0.75)
        (xy 15.451 -0.773)
        (xy 15.458 -0.795)
        (xy 15.467 -0.816)
        (xy 15.477 -0.837)
        (xy 15.489 -0.857)
        (xy 15.502 -0.877)
        (xy 15.515 -0.897)
        (xy 15.528 -0.916)
        (xy 15.544 -0.933)
        (xy 15.56 -0.949)
        (xy 15.576 -0.965)
        (xy 15.593 -0.98)
        (xy 15.612 -0.994)
        (xy 15.631 -1.007)
        (xy 15.651 -1.02)
        (xy 15.672 -1.032)
        (xy 15.692 -1.042)
        (xy 15.714 -1.05)
        (xy 15.736 -1.058)
        (xy 15.759 -1.064)
        (xy 15.781 -1.07)
        (xy 15.803 -1.074)
        (xy 15.826 -1.078)
        (xy 15.851 -1.078)
        (xy 15.874 -1.08)
        (xy 15.897 -1.078)
        (xy 15.922 -1.078)
        (xy 15.944 -1.074)
        (xy 15.967 -1.07)
        (xy 15.989 -1.064)
        (xy 16.013 -1.058)
        (xy 16.033 -1.05)
        (xy 16.056 -1.042)
        (xy 16.077 -1.03)
        (xy 16.097 -1.019)
        (xy 16.117 -1.007)
        (xy 16.137 -0.994)
        (xy 16.155 -0.98)
        (xy 16.172 -0.965)
        (xy 16.19 -0.949)
        (xy 16.205 -0.933)
        (xy 16.22 -0.915)
        (xy 16.234 -0.897)
        (xy 16.248 -0.876)
        (xy 16.26 -0.856)
        (xy 16.271 -0.836)
        (xy 16.281 -0.815)
        (xy 16.289 -0.794)
        (xy 16.297 -0.773)
        (xy 16.304 -0.749)
        (xy 16.309 -0.727)
        (xy 16.315 -0.704)
        (xy 16.318 -0.682)
        (xy 16.318 -0.658)
        (xy 16.319 -0.634)
        (xy 16.318 -0.611)
        (xy 16.318 -0.587)
        (xy 16.315 -0.564)
        (xy 16.309 -0.542)
        (xy 16.304 -0.52)
        (xy 16.297 -0.496)
        (xy 16.289 -0.475)
        (xy 16.281 -0.454)
        (xy 16.271 -0.432)
        (xy 16.26 -0.412)
        (xy 16.248 -0.393)
        (xy 16.234 -0.372)
        (xy 16.22 -0.354)
        (xy 16.205 -0.337)
        (xy 16.19 -0.32)
        (xy 16.172 -0.303)
        (xy 16.155 -0.288)
        (xy 16.137 -0.275)
        (xy 16.117 -0.262)
        (xy 16.097 -0.249)
        (xy 16.077 -0.238)
        (xy 16.056 -0.228)
        (xy 16.033 -0.219)
        (xy 16.013 -0.211)
        (xy 15.989 -0.204)
        (xy 15.967 -0.2)
        (xy 15.944 -0.195)
        (xy 15.922 -0.192)
        (xy 15.897 -0.19)
        (xy 15.874 -0.189)
        (xy 15.851 -0.19)
        (xy 15.826 -0.192)
        (xy 15.803 -0.195)
        (xy 15.781 -0.2)
        (xy 15.759 -0.204)
        (xy 15.736 -0.211)
        (xy 15.714 -0.218)
        (xy 15.692 -0.228)
        (xy 15.672 -0.237)
        (xy 15.651 -0.248)
        (xy 15.631 -0.262)
        (xy 15.612 -0.275)
        (xy 15.593 -0.288)
        (xy 15.576 -0.303)
        (xy 15.56 -0.32)
        (xy 15.544 -0.337)
        (xy 15.528 -0.353)
        (xy 15.515 -0.372)
        (xy 15.502 -0.392)
        (xy 15.489 -0.411)
        (xy 15.477 -0.431)
        (xy 15.467 -0.453)
        (xy 15.458 -0.474)
        (xy 15.451 -0.496)
        (xy 15.444 -0.519)
        (xy 15.439 -0.541)
        (xy 15.435 -0.563)
        (xy 15.432 -0.586)
        (xy 15.43 -0.61)
        (xy 15.429 -0.631)
        (xy 15.874 -0.631)
        (xy 15.874 -0.636)
        (xy 15.874 -0.637)
      )

      (stroke (width 0.001) (type solid)) (fill solid) (layer "B.Paste"))
    (fp_poly
      (pts
        (xy 15.874 0.633)
        (xy 15.429 0.632)
        (xy 15.43 0.611)
        (xy 15.432 0.587)
        (xy 15.435 0.564)
        (xy 15.439 0.542)
        (xy 15.444 0.52)
        (xy 15.451 0.497)
        (xy 15.458 0.475)
        (xy 15.467 0.454)
        (xy 15.477 0.432)
        (xy 15.489 0.412)
        (xy 15.502 0.393)
        (xy 15.515 0.373)
        (xy 15.528 0.354)
        (xy 15.544 0.338)
        (xy 15.56 0.32)
        (xy 15.576 0.304)
        (xy 15.593 0.289)
        (xy 15.612 0.276)
        (xy 15.631 0.263)
        (xy 15.651 0.249)
        (xy 15.672 0.238)
        (xy 15.692 0.229)
        (xy 15.714 0.219)
        (xy 15.736 0.212)
        (xy 15.759 0.205)
        (xy 15.781 0.201)
        (xy 15.803 0.196)
        (xy 15.826 0.192)
        (xy 15.851 0.191)
        (xy 15.874 0.19)
        (xy 15.897 0.191)
        (xy 15.922 0.192)
        (xy 15.944 0.196)
        (xy 15.967 0.201)
        (xy 15.989 0.205)
        (xy 16.013 0.212)
        (xy 16.033 0.22)
        (xy 16.056 0.229)
        (xy 16.077 0.239)
        (xy 16.097 0.25)
        (xy 16.117 0.263)
        (xy 16.137 0.276)
        (xy 16.155 0.289)
        (xy 16.172 0.304)
        (xy 16.19 0.32)
        (xy 16.205 0.338)
        (xy 16.22 0.355)
        (xy 16.234 0.373)
        (xy 16.248 0.394)
        (xy 16.26 0.413)
        (xy 16.271 0.433)
        (xy 16.281 0.455)
        (xy 16.289 0.476)
        (xy 16.297 0.497)
        (xy 16.304 0.521)
        (xy 16.309 0.543)
        (xy 16.315 0.565)
        (xy 16.318 0.588)
        (xy 16.318 0.612)
        (xy 16.319 0.635)
        (xy 16.318 0.659)
        (xy 16.318 0.683)
        (xy 16.315 0.705)
        (xy 16.309 0.728)
        (xy 16.304 0.75)
        (xy 16.297 0.774)
        (xy 16.289 0.795)
        (xy 16.281 0.816)
        (xy 16.271 0.837)
        (xy 16.26 0.857)
        (xy 16.248 0.877)
        (xy 16.234 0.898)
        (xy 16.22 0.916)
        (xy 16.205 0.934)
        (xy 16.19 0.95)
        (xy 16.172 0.966)
        (xy 16.155 0.981)
        (xy 16.137 0.995)
        (xy 16.117 1.008)
        (xy 16.097 1.02)
        (xy 16.077 1.031)
        (xy 16.056 1.043)
        (xy 16.033 1.051)
        (xy 16.013 1.059)
        (xy 15.989 1.065)
        (xy 15.967 1.071)
        (xy 15.944 1.075)
        (xy 15.922 1.079)
        (xy 15.897 1.079)
        (xy 15.874 1.081)
        (xy 15.851 1.079)
        (xy 15.826 1.079)
        (xy 15.803 1.075)
        (xy 15.781 1.071)
        (xy 15.759 1.065)
        (xy 15.736 1.059)
        (xy 15.714 1.051)
        (xy 15.692 1.043)
        (xy 15.672 1.033)
        (xy 15.651 1.021)
        (xy 15.631 1.008)
        (xy 15.612 0.995)
        (xy 15.593 0.981)
        (xy 15.576 0.966)
        (xy 15.56 0.95)
        (xy 15.544 0.934)
        (xy 15.528 0.917)
        (xy 15.515 0.898)
        (xy 15.502 0.878)
        (xy 15.489 0.858)
        (xy 15.477 0.838)
        (xy 15.467 0.817)
        (xy 15.458 0.796)
        (xy 15.451 0.774)
        (xy 15.444 0.751)
        (xy 15.439 0.729)
        (xy 15.435 0.706)
        (xy 15.432 0.684)
        (xy 15.43 0.66)
        (xy 15.429 0.637)
        (xy 15.874 0.637)
        (xy 15.874 0.632)
        (xy 15.874 0.633)
      )

      (stroke (width 0.001) (type solid)) (fill solid) (layer "B.Paste"))
    (fp_poly
      (pts
        (xy 17.144 -4.447)
        (xy 16.699 -4.446)
        (xy 16.701 -4.469)
        (xy 16.702 -4.493)
        (xy 16.704 -4.515)
        (xy 16.71 -4.538)
        (xy 16.714 -4.56)
        (xy 16.722 -4.583)
        (xy 16.728 -4.605)
        (xy 16.737 -4.626)
        (xy 16.748 -4.647)
        (xy 16.758 -4.668)
        (xy 16.771 -4.687)
        (xy 16.784 -4.706)
        (xy 16.798 -4.725)
        (xy 16.813 -4.743)
        (xy 16.829 -4.759)
        (xy 16.847 -4.775)
        (xy 16.864 -4.791)
        (xy 16.882 -4.804)
        (xy 16.902 -4.817)
        (xy 16.922 -4.831)
        (xy 16.941 -4.841)
        (xy 16.963 -4.852)
        (xy 16.984 -4.86)
        (xy 17.007 -4.868)
        (xy 17.028 -4.874)
        (xy 17.05 -4.879)
        (xy 17.074 -4.884)
        (xy 17.097 -4.887)
        (xy 17.12 -4.889)
        (xy 17.144 -4.889)
        (xy 17.167 -4.889)
        (xy 17.191 -4.887)
        (xy 17.214 -4.884)
        (xy 17.237 -4.879)
        (xy 17.26 -4.874)
        (xy 17.283 -4.868)
        (xy 17.303 -4.86)
        (xy 17.326 -4.852)
        (xy 17.347 -4.841)
        (xy 17.367 -4.829)
        (xy 17.387 -4.817)
        (xy 17.406 -4.804)
        (xy 17.425 -4.791)
        (xy 17.443 -4.775)
        (xy 17.46 -4.759)
        (xy 17.475 -4.743)
        (xy 17.49 -4.724)
        (xy 17.504 -4.706)
        (xy 17.518 -4.687)
        (xy 17.53 -4.668)
        (xy 17.541 -4.647)
        (xy 17.551 -4.626)
        (xy 17.559 -4.603)
        (xy 17.568 -4.583)
        (xy 17.574 -4.559)
        (xy 17.579 -4.538)
        (xy 17.585 -4.514)
        (xy 17.588 -4.491)
        (xy 17.588 -4.467)
        (xy 17.589 -4.445)
        (xy 17.588 -4.421)
        (xy 17.588 -4.397)
        (xy 17.585 -4.374)
        (xy 17.579 -4.352)
        (xy 17.574 -4.329)
        (xy 17.568 -4.307)
        (xy 17.559 -4.285)
        (xy 17.551 -4.264)
        (xy 17.541 -4.243)
        (xy 17.53 -4.222)
        (xy 17.518 -4.203)
        (xy 17.504 -4.182)
        (xy 17.49 -4.164)
        (xy 17.475 -4.147)
        (xy 17.46 -4.129)
        (xy 17.443 -4.113)
        (xy 17.425 -4.099)
        (xy 17.406 -4.084)
        (xy 17.387 -4.071)
        (xy 17.367 -4.059)
        (xy 17.347 -4.049)
        (xy 17.326 -4.038)
        (xy 17.303 -4.03)
        (xy 17.283 -4.022)
        (xy 17.26 -4.014)
        (xy 17.237 -4.009)
        (xy 17.214 -4.004)
        (xy 17.191 -4.001)
        (xy 17.167 -4.001)
        (xy 17.144 -3.999)
        (xy 17.12 -4.001)
        (xy 17.097 -4.001)
        (xy 17.074 -4.004)
        (xy 17.05 -4.009)
        (xy 17.028 -4.014)
        (xy 17.007 -4.022)
        (xy 16.984 -4.028)
        (xy 16.963 -4.038)
        (xy 16.941 -4.047)
        (xy 16.922 -4.059)
        (xy 16.902 -4.071)
        (xy 16.882 -4.084)
        (xy 16.864 -4.099)
        (xy 16.847 -4.113)
        (xy 16.829 -4.129)
        (xy 16.813 -4.147)
        (xy 16.798 -4.163)
        (xy 16.784 -4.182)
        (xy 16.771 -4.201)
        (xy 16.758 -4.222)
        (xy 16.748 -4.241)
        (xy 16.737 -4.262)
        (xy 16.728 -4.285)
        (xy 16.722 -4.307)
        (xy 16.714 -4.328)
        (xy 16.71 -4.35)
        (xy 16.704 -4.373)
        (xy 16.702 -4.397)
        (xy 16.701 -4.421)
        (xy 16.699 -4.442)
        (xy 17.144 -4.442)
        (xy 17.144 -4.446)
        (xy 17.144 -4.447)
      )

      (stroke (width 0.001) (type solid)) (fill solid) (layer "B.Paste"))
    (fp_poly
      (pts
        (xy 17.144 -1.907)
        (xy 16.699 -1.906)
        (xy 16.701 -1.929)
        (xy 16.702 -1.953)
        (xy 16.704 -1.975)
        (xy 16.71 -1.999)
        (xy 16.714 -2.02)
        (xy 16.722 -2.043)
        (xy 16.728 -2.064)
        (xy 16.737 -2.087)
        (xy 16.748 -2.108)
        (xy 16.758 -2.128)
        (xy 16.771 -2.148)
        (xy 16.784 -2.166)
        (xy 16.798 -2.185)
        (xy 16.813 -2.202)
        (xy 16.829 -2.22)
        (xy 16.847 -2.236)
        (xy 16.864 -2.25)
        (xy 16.882 -2.265)
        (xy 16.902 -2.277)
        (xy 16.922 -2.29)
        (xy 16.941 -2.301)
        (xy 16.963 -2.311)
        (xy 16.984 -2.321)
        (xy 17.007 -2.327)
        (xy 17.028 -2.334)
        (xy 17.05 -2.339)
        (xy 17.074 -2.345)
        (xy 17.097 -2.347)
        (xy 17.12 -2.349)
        (xy 17.144 -2.35)
        (xy 17.167 -2.349)
        (xy 17.191 -2.347)
        (xy 17.214 -2.345)
        (xy 17.237 -2.339)
        (xy 17.26 -2.334)
        (xy 17.283 -2.327)
        (xy 17.303 -2.319)
        (xy 17.326 -2.311)
        (xy 17.347 -2.301)
        (xy 17.367 -2.289)
        (xy 17.387 -2.277)
        (xy 17.406 -2.265)
        (xy 17.425 -2.25)
        (xy 17.443 -2.236)
        (xy 17.46 -2.22)
        (xy 17.475 -2.202)
        (xy 17.49 -2.185)
        (xy 17.504 -2.166)
        (xy 17.518 -2.146)
        (xy 17.53 -2.126)
        (xy 17.541 -2.107)
        (xy 17.551 -2.085)
        (xy 17.559 -2.064)
        (xy 17.568 -2.043)
        (xy 17.574 -2.019)
        (xy 17.579 -1.997)
        (xy 17.585 -1.975)
        (xy 17.588 -1.951)
        (xy 17.588 -1.927)
        (xy 17.589 -1.904)
        (xy 17.588 -1.881)
        (xy 17.588 -1.858)
        (xy 17.585 -1.834)
        (xy 17.579 -1.812)
        (xy 17.574 -1.789)
        (xy 17.568 -1.766)
        (xy 17.559 -1.745)
        (xy 17.551 -1.723)
        (xy 17.541 -1.703)
        (xy 17.53 -1.683)
        (xy 17.518 -1.662)
        (xy 17.504 -1.642)
        (xy 17.49 -1.624)
        (xy 17.475 -1.606)
        (xy 17.46 -1.59)
        (xy 17.443 -1.574)
        (xy 17.425 -1.558)
        (xy 17.406 -1.544)
        (xy 17.387 -1.531)
        (xy 17.367 -1.519)
        (xy 17.347 -1.508)
        (xy 17.326 -1.497)
        (xy 17.303 -1.489)
        (xy 17.283 -1.481)
        (xy 17.26 -1.475)
        (xy 17.237 -1.469)
        (xy 17.214 -1.465)
        (xy 17.191 -1.461)
        (xy 17.167 -1.461)
        (xy 17.144 -1.459)
        (xy 17.12 -1.461)
        (xy 17.097 -1.461)
        (xy 17.074 -1.465)
        (xy 17.05 -1.469)
        (xy 17.028 -1.475)
        (xy 17.007 -1.481)
        (xy 16.984 -1.489)
        (xy 16.963 -1.497)
        (xy 16.941 -1.507)
        (xy 16.922 -1.518)
        (xy 16.902 -1.531)
        (xy 16.882 -1.544)
        (xy 16.864 -1.558)
        (xy 16.847 -1.574)
        (xy 16.829 -1.59)
        (xy 16.813 -1.606)
        (xy 16.798 -1.624)
        (xy 16.784 -1.642)
        (xy 16.771 -1.661)
        (xy 16.758 -1.681)
        (xy 16.748 -1.701)
        (xy 16.737 -1.723)
        (xy 16.728 -1.745)
        (xy 16.722 -1.766)
        (xy 16.714 -1.788)
        (xy 16.71 -1.81)
        (xy 16.704 -1.834)
        (xy 16.702 -1.856)
        (xy 16.701 -1.88)
        (xy 16.699 -1.902)
        (xy 17.144 -1.902)
        (xy 17.144 -1.906)
        (xy 17.144 -1.907)
      )

      (stroke (width 0.001) (type solid)) (fill solid) (layer "B.Paste"))
    (fp_poly
      (pts
        (xy 17.144 -0.637)
        (xy 16.699 -0.636)
        (xy 16.701 -0.659)
        (xy 16.702 -0.683)
        (xy 16.704 -0.705)
        (xy 16.71 -0.728)
        (xy 16.714 -0.75)
        (xy 16.722 -0.773)
        (xy 16.728 -0.795)
        (xy 16.737 -0.816)
        (xy 16.748 -0.837)
        (xy 16.758 -0.857)
        (xy 16.771 -0.877)
        (xy 16.784 -0.897)
        (xy 16.798 -0.916)
        (xy 16.813 -0.933)
        (xy 16.829 -0.949)
        (xy 16.847 -0.965)
        (xy 16.864 -0.98)
        (xy 16.882 -0.994)
        (xy 16.902 -1.007)
        (xy 16.922 -1.02)
        (xy 16.941 -1.032)
        (xy 16.963 -1.042)
        (xy 16.984 -1.05)
        (xy 17.007 -1.058)
        (xy 17.028 -1.064)
        (xy 17.05 -1.07)
        (xy 17.074 -1.074)
        (xy 17.097 -1.078)
        (xy 17.12 -1.078)
        (xy 17.144 -1.08)
        (xy 17.167 -1.078)
        (xy 17.191 -1.078)
        (xy 17.214 -1.074)
        (xy 17.237 -1.07)
        (xy 17.26 -1.064)
        (xy 17.283 -1.058)
        (xy 17.303 -1.05)
        (xy 17.326 -1.042)
        (xy 17.347 -1.03)
        (xy 17.367 -1.019)
        (xy 17.387 -1.007)
        (xy 17.406 -0.994)
        (xy 17.425 -0.98)
        (xy 17.443 -0.965)
        (xy 17.46 -0.949)
        (xy 17.475 -0.933)
        (xy 17.49 -0.915)
        (xy 17.504 -0.897)
        (xy 17.518 -0.876)
        (xy 17.53 -0.856)
        (xy 17.541 -0.836)
        (xy 17.551 -0.815)
        (xy 17.559 -0.794)
        (xy 17.568 -0.773)
        (xy 17.574 -0.749)
        (xy 17.579 -0.727)
        (xy 17.585 -0.704)
        (xy 17.588 -0.682)
        (xy 17.588 -0.658)
        (xy 17.589 -0.634)
        (xy 17.588 -0.611)
        (xy 17.588 -0.587)
        (xy 17.585 -0.564)
        (xy 17.579 -0.542)
        (xy 17.574 -0.52)
        (xy 17.568 -0.496)
        (xy 17.559 -0.475)
        (xy 17.551 -0.454)
        (xy 17.541 -0.432)
        (xy 17.53 -0.412)
        (xy 17.518 -0.393)
        (xy 17.504 -0.372)
        (xy 17.49 -0.354)
        (xy 17.475 -0.337)
        (xy 17.46 -0.32)
        (xy 17.443 -0.303)
        (xy 17.425 -0.288)
        (xy 17.406 -0.275)
        (xy 17.387 -0.262)
        (xy 17.367 -0.249)
        (xy 17.347 -0.238)
        (xy 17.326 -0.228)
        (xy 17.303 -0.219)
        (xy 17.283 -0.211)
        (xy 17.26 -0.204)
        (xy 17.237 -0.2)
        (xy 17.214 -0.195)
        (xy 17.191 -0.192)
        (xy 17.167 -0.19)
        (xy 17.144 -0.189)
        (xy 17.12 -0.19)
        (xy 17.097 -0.192)
        (xy 17.074 -0.195)
        (xy 17.05 -0.2)
        (xy 17.028 -0.204)
        (xy 17.007 -0.211)
        (xy 16.984 -0.218)
        (xy 16.963 -0.228)
        (xy 16.941 -0.237)
        (xy 16.922 -0.248)
        (xy 16.902 -0.262)
        (xy 16.882 -0.275)
        (xy 16.864 -0.288)
        (xy 16.847 -0.303)
        (xy 16.829 -0.32)
        (xy 16.813 -0.337)
        (xy 16.798 -0.353)
        (xy 16.784 -0.372)
        (xy 16.771 -0.392)
        (xy 16.758 -0.411)
        (xy 16.748 -0.431)
        (xy 16.737 -0.453)
        (xy 16.728 -0.474)
        (xy 16.722 -0.496)
        (xy 16.714 -0.519)
        (xy 16.71 -0.541)
        (xy 16.704 -0.563)
        (xy 16.702 -0.586)
        (xy 16.701 -0.61)
        (xy 16.699 -0.631)
        (xy 17.144 -0.631)
        (xy 17.144 -0.636)
        (xy 17.144 -0.637)
      )

      (stroke (width 0.001) (type solid)) (fill solid) (layer "B.Paste"))
    (fp_poly
      (pts
        (xy 17.144 0.633)
        (xy 16.699 0.632)
        (xy 16.701 0.611)
        (xy 16.702 0.587)
        (xy 16.704 0.564)
        (xy 16.71 0.542)
        (xy 16.714 0.52)
        (xy 16.722 0.497)
        (xy 16.728 0.475)
        (xy 16.737 0.454)
        (xy 16.748 0.432)
        (xy 16.758 0.412)
        (xy 16.771 0.393)
        (xy 16.784 0.373)
        (xy 16.798 0.354)
        (xy 16.813 0.338)
        (xy 16.829 0.32)
        (xy 16.847 0.304)
        (xy 16.864 0.289)
        (xy 16.882 0.276)
        (xy 16.902 0.263)
        (xy 16.922 0.249)
        (xy 16.941 0.238)
        (xy 16.963 0.229)
        (xy 16.984 0.219)
        (xy 17.007 0.212)
        (xy 17.028 0.205)
        (xy 17.05 0.201)
        (xy 17.074 0.196)
        (xy 17.097 0.192)
        (xy 17.12 0.191)
        (xy 17.144 0.19)
        (xy 17.167 0.191)
        (xy 17.191 0.192)
        (xy 17.214 0.196)
        (xy 17.237 0.201)
        (xy 17.26 0.205)
        (xy 17.283 0.212)
        (xy 17.303 0.22)
        (xy 17.326 0.229)
        (xy 17.347 0.239)
        (xy 17.367 0.25)
        (xy 17.387 0.263)
        (xy 17.406 0.276)
        (xy 17.425 0.289)
        (xy 17.443 0.304)
        (xy 17.46 0.32)
        (xy 17.475 0.338)
        (xy 17.49 0.355)
        (xy 17.504 0.373)
        (xy 17.518 0.394)
        (xy 17.53 0.413)
        (xy 17.541 0.433)
        (xy 17.551 0.455)
        (xy 17.559 0.476)
        (xy 17.568 0.497)
        (xy 17.574 0.521)
        (xy 17.579 0.543)
        (xy 17.585 0.565)
        (xy 17.588 0.588)
        (xy 17.588 0.612)
        (xy 17.589 0.635)
        (xy 17.588 0.659)
        (xy 17.588 0.683)
        (xy 17.585 0.705)
        (xy 17.579 0.728)
        (xy 17.574 0.75)
        (xy 17.568 0.774)
        (xy 17.559 0.795)
        (xy 17.551 0.816)
        (xy 17.541 0.837)
        (xy 17.53 0.857)
        (xy 17.518 0.877)
        (xy 17.504 0.898)
        (xy 17.49 0.916)
        (xy 17.475 0.934)
        (xy 17.46 0.95)
        (xy 17.443 0.966)
        (xy 17.425 0.981)
        (xy 17.406 0.995)
        (xy 17.387 1.008)
        (xy 17.367 1.02)
        (xy 17.347 1.031)
        (xy 17.326 1.043)
        (xy 17.303 1.051)
        (xy 17.283 1.059)
        (xy 17.26 1.065)
        (xy 17.237 1.071)
        (xy 17.214 1.075)
        (xy 17.191 1.079)
        (xy 17.167 1.079)
        (xy 17.144 1.081)
        (xy 17.12 1.079)
        (xy 17.097 1.079)
        (xy 17.074 1.075)
        (xy 17.05 1.071)
        (xy 17.028 1.065)
        (xy 17.007 1.059)
        (xy 16.984 1.051)
        (xy 16.963 1.043)
        (xy 16.941 1.033)
        (xy 16.922 1.021)
        (xy 16.902 1.008)
        (xy 16.882 0.995)
        (xy 16.864 0.981)
        (xy 16.847 0.966)
        (xy 16.829 0.95)
        (xy 16.813 0.934)
        (xy 16.798 0.917)
        (xy 16.784 0.898)
        (xy 16.771 0.878)
        (xy 16.758 0.858)
        (xy 16.748 0.838)
        (xy 16.737 0.817)
        (xy 16.728 0.796)
        (xy 16.722 0.774)
        (xy 16.714 0.751)
        (xy 16.71 0.729)
        (xy 16.704 0.706)
        (xy 16.702 0.684)
        (xy 16.701 0.66)
        (xy 16.699 0.637)
        (xy 17.144 0.637)
        (xy 17.144 0.632)
        (xy 17.144 0.633)
      )

      (stroke (width 0.001) (type solid)) (fill solid) (layer "B.Paste"))
    (fp_poly
      (pts
        (xy 18.414 -4.447)
        (xy 17.969 -4.446)
        (xy 17.97 -4.469)
        (xy 17.972 -4.493)
        (xy 17.975 -4.515)
        (xy 17.98 -4.538)
        (xy 17.984 -4.56)
        (xy 17.992 -4.583)
        (xy 17.998 -4.605)
        (xy 18.007 -4.626)
        (xy 18.018 -4.647)
        (xy 18.028 -4.668)
        (xy 18.042 -4.687)
        (xy 18.054 -4.706)
        (xy 18.068 -4.725)
        (xy 18.083 -4.743)
        (xy 18.1 -4.759)
        (xy 18.117 -4.775)
        (xy 18.133 -4.791)
        (xy 18.152 -4.804)
        (xy 18.172 -4.817)
        (xy 18.191 -4.831)
        (xy 18.211 -4.841)
        (xy 18.233 -4.852)
        (xy 18.254 -4.86)
        (xy 18.277 -4.868)
        (xy 18.298 -4.874)
        (xy 18.321 -4.879)
        (xy 18.344 -4.884)
        (xy 18.367 -4.887)
        (xy 18.39 -4.889)
        (xy 18.414 -4.889)
        (xy 18.437 -4.889)
        (xy 18.461 -4.887)
        (xy 18.484 -4.884)
        (xy 18.507 -4.879)
        (xy 18.53 -4.874)
        (xy 18.553 -4.868)
        (xy 18.574 -4.86)
        (xy 18.595 -4.852)
        (xy 18.617 -4.841)
        (xy 18.637 -4.829)
        (xy 18.656 -4.817)
        (xy 18.676 -4.804)
        (xy 18.694 -4.791)
        (xy 18.713 -4.775)
        (xy 18.73 -4.759)
        (xy 18.745 -4.743)
        (xy 18.76 -4.724)
        (xy 18.774 -4.706)
        (xy 18.787 -4.687)
        (xy 18.8 -4.668)
        (xy 18.81 -4.647)
        (xy 18.821 -4.626)
        (xy 18.829 -4.603)
        (xy 18.838 -4.583)
        (xy 18.844 -4.559)
        (xy 18.85 -4.538)
        (xy 18.855 -4.514)
        (xy 18.858 -4.491)
        (xy 18.859 -4.467)
        (xy 18.859 -4.445)
        (xy 18.859 -4.421)
        (xy 18.858 -4.397)
        (xy 18.855 -4.374)
        (xy 18.85 -4.352)
        (xy 18.844 -4.329)
        (xy 18.838 -4.307)
        (xy 18.829 -4.285)
        (xy 18.821 -4.264)
        (xy 18.81 -4.243)
        (xy 18.8 -4.222)
        (xy 18.787 -4.203)
        (xy 18.774 -4.182)
        (xy 18.76 -4.164)
        (xy 18.745 -4.147)
        (xy 18.73 -4.129)
        (xy 18.713 -4.113)
        (xy 18.694 -4.099)
        (xy 18.676 -4.084)
        (xy 18.656 -4.071)
        (xy 18.637 -4.059)
        (xy 18.617 -4.049)
        (xy 18.595 -4.038)
        (xy 18.574 -4.03)
        (xy 18.553 -4.022)
        (xy 18.53 -4.014)
        (xy 18.507 -4.009)
        (xy 18.484 -4.004)
        (xy 18.461 -4.001)
        (xy 18.437 -4.001)
        (xy 18.414 -3.999)
        (xy 18.39 -4.001)
        (xy 18.367 -4.001)
        (xy 18.344 -4.004)
        (xy 18.321 -4.009)
        (xy 18.298 -4.014)
        (xy 18.277 -4.022)
        (xy 18.254 -4.028)
        (xy 18.233 -4.038)
        (xy 18.211 -4.047)
        (xy 18.191 -4.059)
        (xy 18.172 -4.071)
        (xy 18.152 -4.084)
        (xy 18.133 -4.099)
        (xy 18.117 -4.113)
        (xy 18.1 -4.129)
        (xy 18.083 -4.147)
        (xy 18.068 -4.163)
        (xy 18.054 -4.182)
        (xy 18.042 -4.201)
        (xy 18.028 -4.222)
        (xy 18.018 -4.241)
        (xy 18.007 -4.262)
        (xy 17.998 -4.285)
        (xy 17.992 -4.307)
        (xy 17.984 -4.328)
        (xy 17.98 -4.35)
        (xy 17.975 -4.373)
        (xy 17.972 -4.397)
        (xy 17.97 -4.421)
        (xy 17.969 -4.442)
        (xy 18.414 -4.442)
        (xy 18.414 -4.446)
        (xy 18.414 -4.447)
      )

      (stroke (width 0.001) (type solid)) (fill solid) (layer "B.Paste"))
    (fp_poly
      (pts
        (xy 18.414 -1.907)
        (xy 17.969 -1.906)
        (xy 17.97 -1.929)
        (xy 17.972 -1.953)
        (xy 17.975 -1.975)
        (xy 17.98 -1.999)
        (xy 17.984 -2.02)
        (xy 17.992 -2.043)
        (xy 17.998 -2.064)
        (xy 18.007 -2.087)
        (xy 18.018 -2.108)
        (xy 18.028 -2.128)
        (xy 18.042 -2.148)
        (xy 18.054 -2.166)
        (xy 18.068 -2.185)
        (xy 18.083 -2.202)
        (xy 18.1 -2.22)
        (xy 18.117 -2.236)
        (xy 18.133 -2.25)
        (xy 18.152 -2.265)
        (xy 18.172 -2.277)
        (xy 18.191 -2.29)
        (xy 18.211 -2.301)
        (xy 18.233 -2.311)
        (xy 18.254 -2.321)
        (xy 18.277 -2.327)
        (xy 18.298 -2.334)
        (xy 18.321 -2.339)
        (xy 18.344 -2.345)
        (xy 18.367 -2.347)
        (xy 18.39 -2.349)
        (xy 18.414 -2.35)
        (xy 18.437 -2.349)
        (xy 18.461 -2.347)
        (xy 18.484 -2.345)
        (xy 18.507 -2.339)
        (xy 18.53 -2.334)
        (xy 18.553 -2.327)
        (xy 18.574 -2.319)
        (xy 18.595 -2.311)
        (xy 18.617 -2.301)
        (xy 18.637 -2.289)
        (xy 18.656 -2.277)
        (xy 18.676 -2.265)
        (xy 18.694 -2.25)
        (xy 18.713 -2.236)
        (xy 18.73 -2.22)
        (xy 18.745 -2.202)
        (xy 18.76 -2.185)
        (xy 18.774 -2.166)
        (xy 18.787 -2.146)
        (xy 18.8 -2.126)
        (xy 18.81 -2.107)
        (xy 18.821 -2.085)
        (xy 18.829 -2.064)
        (xy 18.838 -2.043)
        (xy 18.844 -2.019)
        (xy 18.85 -1.997)
        (xy 18.855 -1.975)
        (xy 18.858 -1.951)
        (xy 18.859 -1.927)
        (xy 18.859 -1.904)
        (xy 18.859 -1.881)
        (xy 18.858 -1.858)
        (xy 18.855 -1.834)
        (xy 18.85 -1.812)
        (xy 18.844 -1.789)
        (xy 18.838 -1.766)
        (xy 18.829 -1.745)
        (xy 18.821 -1.723)
        (xy 18.81 -1.703)
        (xy 18.8 -1.683)
        (xy 18.787 -1.662)
        (xy 18.774 -1.642)
        (xy 18.76 -1.624)
        (xy 18.745 -1.606)
        (xy 18.73 -1.59)
        (xy 18.713 -1.574)
        (xy 18.694 -1.558)
        (xy 18.676 -1.544)
        (xy 18.656 -1.531)
        (xy 18.637 -1.519)
        (xy 18.617 -1.508)
        (xy 18.595 -1.497)
        (xy 18.574 -1.489)
        (xy 18.553 -1.481)
        (xy 18.53 -1.475)
        (xy 18.507 -1.469)
        (xy 18.484 -1.465)
        (xy 18.461 -1.461)
        (xy 18.437 -1.461)
        (xy 18.414 -1.459)
        (xy 18.39 -1.461)
        (xy 18.367 -1.461)
        (xy 18.344 -1.465)
        (xy 18.321 -1.469)
        (xy 18.298 -1.475)
        (xy 18.277 -1.481)
        (xy 18.254 -1.489)
        (xy 18.233 -1.497)
        (xy 18.211 -1.507)
        (xy 18.191 -1.518)
        (xy 18.172 -1.531)
        (xy 18.152 -1.544)
        (xy 18.133 -1.558)
        (xy 18.117 -1.574)
        (xy 18.1 -1.59)
        (xy 18.083 -1.606)
        (xy 18.068 -1.624)
        (xy 18.054 -1.642)
        (xy 18.042 -1.661)
        (xy 18.028 -1.681)
        (xy 18.018 -1.701)
        (xy 18.007 -1.723)
        (xy 17.998 -1.745)
        (xy 17.992 -1.766)
        (xy 17.984 -1.788)
        (xy 17.98 -1.81)
        (xy 17.975 -1.834)
        (xy 17.972 -1.856)
        (xy 17.97 -1.88)
        (xy 17.969 -1.902)
        (xy 18.414 -1.902)
        (xy 18.414 -1.906)
        (xy 18.414 -1.907)
      )

      (stroke (width 0.001) (type solid)) (fill solid) (layer "B.Paste"))
    (fp_poly
      (pts
        (xy 18.414 -0.637)
        (xy 17.969 -0.636)
        (xy 17.97 -0.659)
        (xy 17.972 -0.683)
        (xy 17.975 -0.705)
        (xy 17.98 -0.728)
        (xy 17.984 -0.75)
        (xy 17.992 -0.773)
        (xy 17.998 -0.795)
        (xy 18.007 -0.816)
        (xy 18.018 -0.837)
        (xy 18.028 -0.857)
        (xy 18.042 -0.877)
        (xy 18.054 -0.897)
        (xy 18.068 -0.916)
        (xy 18.083 -0.933)
        (xy 18.1 -0.949)
        (xy 18.117 -0.965)
        (xy 18.133 -0.98)
        (xy 18.152 -0.994)
        (xy 18.172 -1.007)
        (xy 18.191 -1.02)
        (xy 18.211 -1.032)
        (xy 18.233 -1.042)
        (xy 18.254 -1.05)
        (xy 18.277 -1.058)
        (xy 18.298 -1.064)
        (xy 18.321 -1.07)
        (xy 18.344 -1.074)
        (xy 18.367 -1.078)
        (xy 18.39 -1.078)
        (xy 18.414 -1.08)
        (xy 18.437 -1.078)
        (xy 18.461 -1.078)
        (xy 18.484 -1.074)
        (xy 18.507 -1.07)
        (xy 18.53 -1.064)
        (xy 18.553 -1.058)
        (xy 18.574 -1.05)
        (xy 18.595 -1.042)
        (xy 18.617 -1.03)
        (xy 18.637 -1.019)
        (xy 18.656 -1.007)
        (xy 18.676 -0.994)
        (xy 18.694 -0.98)
        (xy 18.713 -0.965)
        (xy 18.73 -0.949)
        (xy 18.745 -0.933)
        (xy 18.76 -0.915)
        (xy 18.774 -0.897)
        (xy 18.787 -0.876)
        (xy 18.8 -0.856)
        (xy 18.81 -0.836)
        (xy 18.821 -0.815)
        (xy 18.829 -0.794)
        (xy 18.838 -0.773)
        (xy 18.844 -0.749)
        (xy 18.85 -0.727)
        (xy 18.855 -0.704)
        (xy 18.858 -0.682)
        (xy 18.859 -0.658)
        (xy 18.859 -0.634)
        (xy 18.859 -0.611)
        (xy 18.858 -0.587)
        (xy 18.855 -0.564)
        (xy 18.85 -0.542)
        (xy 18.844 -0.52)
        (xy 18.838 -0.496)
        (xy 18.829 -0.475)
        (xy 18.821 -0.454)
        (xy 18.81 -0.432)
        (xy 18.8 -0.412)
        (xy 18.787 -0.393)
        (xy 18.774 -0.372)
        (xy 18.76 -0.354)
        (xy 18.745 -0.337)
        (xy 18.73 -0.32)
        (xy 18.713 -0.303)
        (xy 18.694 -0.288)
        (xy 18.676 -0.275)
        (xy 18.656 -0.262)
        (xy 18.637 -0.249)
        (xy 18.617 -0.238)
        (xy 18.595 -0.228)
        (xy 18.574 -0.219)
        (xy 18.553 -0.211)
        (xy 18.53 -0.204)
        (xy 18.507 -0.2)
        (xy 18.484 -0.195)
        (xy 18.461 -0.192)
        (xy 18.437 -0.19)
        (xy 18.414 -0.189)
        (xy 18.39 -0.19)
        (xy 18.367 -0.192)
        (xy 18.344 -0.195)
        (xy 18.321 -0.2)
        (xy 18.298 -0.204)
        (xy 18.277 -0.211)
        (xy 18.254 -0.218)
        (xy 18.233 -0.228)
        (xy 18.211 -0.237)
        (xy 18.191 -0.248)
        (xy 18.172 -0.262)
        (xy 18.152 -0.275)
        (xy 18.133 -0.288)
        (xy 18.117 -0.303)
        (xy 18.1 -0.32)
        (xy 18.083 -0.337)
        (xy 18.068 -0.353)
        (xy 18.054 -0.372)
        (xy 18.042 -0.392)
        (xy 18.028 -0.411)
        (xy 18.018 -0.431)
        (xy 18.007 -0.453)
        (xy 17.998 -0.474)
        (xy 17.992 -0.496)
        (xy 17.984 -0.519)
        (xy 17.98 -0.541)
        (xy 17.975 -0.563)
        (xy 17.972 -0.586)
        (xy 17.97 -0.61)
        (xy 17.969 -0.631)
        (xy 18.414 -0.631)
        (xy 18.414 -0.636)
        (xy 18.414 -0.637)
      )

      (stroke (width 0.001) (type solid)) (fill solid) (layer "B.Paste"))
    (fp_poly
      (pts
        (xy 18.414 0.633)
        (xy 17.969 0.632)
        (xy 17.97 0.611)
        (xy 17.972 0.587)
        (xy 17.975 0.564)
        (xy 17.98 0.542)
        (xy 17.984 0.52)
        (xy 17.992 0.497)
        (xy 17.998 0.475)
        (xy 18.007 0.454)
        (xy 18.018 0.432)
        (xy 18.028 0.412)
        (xy 18.042 0.393)
        (xy 18.054 0.373)
        (xy 18.068 0.354)
        (xy 18.083 0.338)
        (xy 18.1 0.32)
        (xy 18.117 0.304)
        (xy 18.133 0.289)
        (xy 18.152 0.276)
        (xy 18.172 0.263)
        (xy 18.191 0.249)
        (xy 18.211 0.238)
        (xy 18.233 0.229)
        (xy 18.254 0.219)
        (xy 18.277 0.212)
        (xy 18.298 0.205)
        (xy 18.321 0.201)
        (xy 18.344 0.196)
        (xy 18.367 0.192)
        (xy 18.39 0.191)
        (xy 18.414 0.19)
        (xy 18.437 0.191)
        (xy 18.461 0.192)
        (xy 18.484 0.196)
        (xy 18.507 0.201)
        (xy 18.53 0.205)
        (xy 18.553 0.212)
        (xy 18.574 0.22)
        (xy 18.595 0.229)
        (xy 18.617 0.239)
        (xy 18.637 0.25)
        (xy 18.656 0.263)
        (xy 18.676 0.276)
        (xy 18.694 0.289)
        (xy 18.713 0.304)
        (xy 18.73 0.32)
        (xy 18.745 0.338)
        (xy 18.76 0.355)
        (xy 18.774 0.373)
        (xy 18.787 0.394)
        (xy 18.8 0.413)
        (xy 18.81 0.433)
        (xy 18.821 0.455)
        (xy 18.829 0.476)
        (xy 18.838 0.497)
        (xy 18.844 0.521)
        (xy 18.85 0.543)
        (xy 18.855 0.565)
        (xy 18.858 0.588)
        (xy 18.859 0.612)
        (xy 18.859 0.635)
        (xy 18.859 0.659)
        (xy 18.858 0.683)
        (xy 18.855 0.705)
        (xy 18.85 0.728)
        (xy 18.844 0.75)
        (xy 18.838 0.774)
        (xy 18.829 0.795)
        (xy 18.821 0.816)
        (xy 18.81 0.837)
        (xy 18.8 0.857)
        (xy 18.787 0.877)
        (xy 18.774 0.898)
        (xy 18.76 0.916)
        (xy 18.745 0.934)
        (xy 18.73 0.95)
        (xy 18.713 0.966)
        (xy 18.694 0.981)
        (xy 18.676 0.995)
        (xy 18.656 1.008)
        (xy 18.637 1.02)
        (xy 18.617 1.031)
        (xy 18.595 1.043)
        (xy 18.574 1.051)
        (xy 18.553 1.059)
        (xy 18.53 1.065)
        (xy 18.507 1.071)
        (xy 18.484 1.075)
        (xy 18.461 1.079)
        (xy 18.437 1.079)
        (xy 18.414 1.081)
        (xy 18.39 1.079)
        (xy 18.367 1.079)
        (xy 18.344 1.075)
        (xy 18.321 1.071)
        (xy 18.298 1.065)
        (xy 18.277 1.059)
        (xy 18.254 1.051)
        (xy 18.233 1.043)
        (xy 18.211 1.033)
        (xy 18.191 1.021)
        (xy 18.172 1.008)
        (xy 18.152 0.995)
        (xy 18.133 0.981)
        (xy 18.117 0.966)
        (xy 18.1 0.95)
        (xy 18.083 0.934)
        (xy 18.068 0.917)
        (xy 18.054 0.898)
        (xy 18.042 0.878)
        (xy 18.028 0.858)
        (xy 18.018 0.838)
        (xy 18.007 0.817)
        (xy 17.998 0.796)
        (xy 17.992 0.774)
        (xy 17.984 0.751)
        (xy 17.98 0.729)
        (xy 17.975 0.706)
        (xy 17.972 0.684)
        (xy 17.97 0.66)
        (xy 17.969 0.637)
        (xy 18.414 0.637)
        (xy 18.414 0.632)
        (xy 18.414 0.633)
      )

      (stroke (width 0.001) (type solid)) (fill solid) (layer "B.Paste"))
    (fp_poly
      (pts
        (xy 19.684 -4.447)
        (xy 19.239 -4.446)
        (xy 19.24 -4.469)
        (xy 19.242 -4.493)
        (xy 19.245 -4.515)
        (xy 19.249 -4.538)
        (xy 19.254 -4.56)
        (xy 19.262 -4.583)
        (xy 19.268 -4.605)
        (xy 19.277 -4.626)
        (xy 19.287 -4.647)
        (xy 19.298 -4.668)
        (xy 19.312 -4.687)
        (xy 19.324 -4.706)
        (xy 19.338 -4.725)
        (xy 19.353 -4.743)
        (xy 19.37 -4.759)
        (xy 19.387 -4.775)
        (xy 19.403 -4.791)
        (xy 19.422 -4.804)
        (xy 19.441 -4.817)
        (xy 19.461 -4.831)
        (xy 19.481 -4.841)
        (xy 19.502 -4.852)
        (xy 19.524 -4.86)
        (xy 19.547 -4.868)
        (xy 19.568 -4.874)
        (xy 19.591 -4.879)
        (xy 19.614 -4.884)
        (xy 19.637 -4.887)
        (xy 19.661 -4.889)
        (xy 19.684 -4.889)
        (xy 19.707 -4.889)
        (xy 19.731 -4.887)
        (xy 19.754 -4.884)
        (xy 19.777 -4.879)
        (xy 19.8 -4.874)
        (xy 19.822 -4.868)
        (xy 19.844 -4.86)
        (xy 19.865 -4.852)
        (xy 19.887 -4.841)
        (xy 19.906 -4.829)
        (xy 19.926 -4.817)
        (xy 19.946 -4.804)
        (xy 19.964 -4.791)
        (xy 19.983 -4.775)
        (xy 19.999 -4.759)
        (xy 20.015 -4.743)
        (xy 20.03 -4.724)
        (xy 20.045 -4.706)
        (xy 20.057 -4.687)
        (xy 20.069 -4.668)
        (xy 20.08 -4.647)
        (xy 20.091 -4.626)
        (xy 20.1 -4.603)
        (xy 20.108 -4.583)
        (xy 20.114 -4.559)
        (xy 20.12 -4.538)
        (xy 20.124 -4.514)
        (xy 20.127 -4.491)
        (xy 20.129 -4.467)
        (xy 20.129 -4.445)
        (xy 20.129 -4.421)
        (xy 20.127 -4.397)
        (xy 20.124 -4.374)
        (xy 20.12 -4.352)
        (xy 20.114 -4.329)
        (xy 20.108 -4.307)
        (xy 20.1 -4.285)
        (xy 20.091 -4.264)
        (xy 20.08 -4.243)
        (xy 20.069 -4.222)
        (xy 20.057 -4.203)
        (xy 20.045 -4.182)
        (xy 20.03 -4.164)
        (xy 20.015 -4.147)
        (xy 19.999 -4.129)
        (xy 19.983 -4.113)
        (xy 19.964 -4.099)
        (xy 19.946 -4.084)
        (xy 19.926 -4.071)
        (xy 19.906 -4.059)
        (xy 19.887 -4.049)
        (xy 19.865 -4.038)
        (xy 19.844 -4.03)
        (xy 19.822 -4.022)
        (xy 19.8 -4.014)
        (xy 19.777 -4.009)
        (xy 19.754 -4.004)
        (xy 19.731 -4.001)
        (xy 19.707 -4.001)
        (xy 19.684 -3.999)
        (xy 19.661 -4.001)
        (xy 19.637 -4.001)
        (xy 19.614 -4.004)
        (xy 19.591 -4.009)
        (xy 19.568 -4.014)
        (xy 19.547 -4.022)
        (xy 19.524 -4.028)
        (xy 19.502 -4.038)
        (xy 19.481 -4.047)
        (xy 19.461 -4.059)
        (xy 19.441 -4.071)
        (xy 19.422 -4.084)
        (xy 19.403 -4.099)
        (xy 19.387 -4.113)
        (xy 19.37 -4.129)
        (xy 19.353 -4.147)
        (xy 19.338 -4.163)
        (xy 19.324 -4.182)
        (xy 19.312 -4.201)
        (xy 19.298 -4.222)
        (xy 19.287 -4.241)
        (xy 19.277 -4.262)
        (xy 19.268 -4.285)
        (xy 19.262 -4.307)
        (xy 19.254 -4.328)
        (xy 19.249 -4.35)
        (xy 19.245 -4.373)
        (xy 19.242 -4.397)
        (xy 19.24 -4.421)
        (xy 19.239 -4.442)
        (xy 19.684 -4.442)
        (xy 19.684 -4.446)
        (xy 19.684 -4.447)
      )

      (stroke (width 0.001) (type solid)) (fill solid) (layer "B.Paste"))
    (fp_poly
      (pts
        (xy 19.684 -1.907)
        (xy 19.239 -1.906)
        (xy 19.24 -1.929)
        (xy 19.242 -1.953)
        (xy 19.245 -1.975)
        (xy 19.249 -1.999)
        (xy 19.254 -2.02)
        (xy 19.262 -2.043)
        (xy 19.268 -2.064)
        (xy 19.277 -2.087)
        (xy 19.287 -2.108)
        (xy 19.298 -2.128)
        (xy 19.312 -2.148)
        (xy 19.324 -2.166)
        (xy 19.338 -2.185)
        (xy 19.353 -2.202)
        (xy 19.37 -2.22)
        (xy 19.387 -2.236)
        (xy 19.403 -2.25)
        (xy 19.422 -2.265)
        (xy 19.441 -2.277)
        (xy 19.461 -2.29)
        (xy 19.481 -2.301)
        (xy 19.502 -2.311)
        (xy 19.524 -2.321)
        (xy 19.547 -2.327)
        (xy 19.568 -2.334)
        (xy 19.591 -2.339)
        (xy 19.614 -2.345)
        (xy 19.637 -2.347)
        (xy 19.661 -2.349)
        (xy 19.684 -2.35)
        (xy 19.707 -2.349)
        (xy 19.731 -2.347)
        (xy 19.754 -2.345)
        (xy 19.777 -2.339)
        (xy 19.8 -2.334)
        (xy 19.822 -2.327)
        (xy 19.844 -2.319)
        (xy 19.865 -2.311)
        (xy 19.887 -2.301)
        (xy 19.906 -2.289)
        (xy 19.926 -2.277)
        (xy 19.946 -2.265)
        (xy 19.964 -2.25)
        (xy 19.983 -2.236)
        (xy 19.999 -2.22)
        (xy 20.015 -2.202)
        (xy 20.03 -2.185)
        (xy 20.045 -2.166)
        (xy 20.057 -2.146)
        (xy 20.069 -2.126)
        (xy 20.08 -2.107)
        (xy 20.091 -2.085)
        (xy 20.1 -2.064)
        (xy 20.108 -2.043)
        (xy 20.114 -2.019)
        (xy 20.12 -1.997)
        (xy 20.124 -1.975)
        (xy 20.127 -1.951)
        (xy 20.129 -1.927)
        (xy 20.129 -1.904)
        (xy 20.129 -1.881)
        (xy 20.127 -1.858)
        (xy 20.124 -1.834)
        (xy 20.12 -1.812)
        (xy 20.114 -1.789)
        (xy 20.108 -1.766)
        (xy 20.1 -1.745)
        (xy 20.091 -1.723)
        (xy 20.08 -1.703)
        (xy 20.069 -1.683)
        (xy 20.057 -1.662)
        (xy 20.045 -1.642)
        (xy 20.03 -1.624)
        (xy 20.015 -1.606)
        (xy 19.999 -1.59)
        (xy 19.983 -1.574)
        (xy 19.964 -1.558)
        (xy 19.946 -1.544)
        (xy 19.926 -1.531)
        (xy 19.906 -1.519)
        (xy 19.887 -1.508)
        (xy 19.865 -1.497)
        (xy 19.844 -1.489)
        (xy 19.822 -1.481)
        (xy 19.8 -1.475)
        (xy 19.777 -1.469)
        (xy 19.754 -1.465)
        (xy 19.731 -1.461)
        (xy 19.707 -1.461)
        (xy 19.684 -1.459)
        (xy 19.661 -1.461)
        (xy 19.637 -1.461)
        (xy 19.614 -1.465)
        (xy 19.591 -1.469)
        (xy 19.568 -1.475)
        (xy 19.547 -1.481)
        (xy 19.524 -1.489)
        (xy 19.502 -1.497)
        (xy 19.481 -1.507)
        (xy 19.461 -1.518)
        (xy 19.441 -1.531)
        (xy 19.422 -1.544)
        (xy 19.403 -1.558)
        (xy 19.387 -1.574)
        (xy 19.37 -1.59)
        (xy 19.353 -1.606)
        (xy 19.338 -1.624)
        (xy 19.324 -1.642)
        (xy 19.312 -1.661)
        (xy 19.298 -1.681)
        (xy 19.287 -1.701)
        (xy 19.277 -1.723)
        (xy 19.268 -1.745)
        (xy 19.262 -1.766)
        (xy 19.254 -1.788)
        (xy 19.249 -1.81)
        (xy 19.245 -1.834)
        (xy 19.242 -1.856)
        (xy 19.24 -1.88)
        (xy 19.239 -1.902)
        (xy 19.684 -1.902)
        (xy 19.684 -1.906)
        (xy 19.684 -1.907)
      )

      (stroke (width 0.001) (type solid)) (fill solid) (layer "B.Paste"))
    (fp_poly
      (pts
        (xy 19.684 -0.637)
        (xy 19.239 -0.636)
        (xy 19.24 -0.659)
        (xy 19.242 -0.683)
        (xy 19.245 -0.705)
        (xy 19.249 -0.728)
        (xy 19.254 -0.75)
        (xy 19.262 -0.773)
        (xy 19.268 -0.795)
        (xy 19.277 -0.816)
        (xy 19.287 -0.837)
        (xy 19.298 -0.857)
        (xy 19.312 -0.877)
        (xy 19.324 -0.897)
        (xy 19.338 -0.916)
        (xy 19.353 -0.933)
        (xy 19.37 -0.949)
        (xy 19.387 -0.965)
        (xy 19.403 -0.98)
        (xy 19.422 -0.994)
        (xy 19.441 -1.007)
        (xy 19.461 -1.02)
        (xy 19.481 -1.032)
        (xy 19.502 -1.042)
        (xy 19.524 -1.05)
        (xy 19.547 -1.058)
        (xy 19.568 -1.064)
        (xy 19.591 -1.07)
        (xy 19.614 -1.074)
        (xy 19.637 -1.078)
        (xy 19.661 -1.078)
        (xy 19.684 -1.08)
        (xy 19.707 -1.078)
        (xy 19.731 -1.078)
        (xy 19.754 -1.074)
        (xy 19.777 -1.07)
        (xy 19.8 -1.064)
        (xy 19.822 -1.058)
        (xy 19.844 -1.05)
        (xy 19.865 -1.042)
        (xy 19.887 -1.03)
        (xy 19.906 -1.019)
        (xy 19.926 -1.007)
        (xy 19.946 -0.994)
        (xy 19.964 -0.98)
        (xy 19.983 -0.965)
        (xy 19.999 -0.949)
        (xy 20.015 -0.933)
        (xy 20.03 -0.915)
        (xy 20.045 -0.897)
        (xy 20.057 -0.876)
        (xy 20.069 -0.856)
        (xy 20.08 -0.836)
        (xy 20.091 -0.815)
        (xy 20.1 -0.794)
        (xy 20.108 -0.773)
        (xy 20.114 -0.749)
        (xy 20.12 -0.727)
        (xy 20.124 -0.704)
        (xy 20.127 -0.682)
        (xy 20.129 -0.658)
        (xy 20.129 -0.634)
        (xy 20.129 -0.611)
        (xy 20.127 -0.587)
        (xy 20.124 -0.564)
        (xy 20.12 -0.542)
        (xy 20.114 -0.52)
        (xy 20.108 -0.496)
        (xy 20.1 -0.475)
        (xy 20.091 -0.454)
        (xy 20.08 -0.432)
        (xy 20.069 -0.412)
        (xy 20.057 -0.393)
        (xy 20.045 -0.372)
        (xy 20.03 -0.354)
        (xy 20.015 -0.337)
        (xy 19.999 -0.32)
        (xy 19.983 -0.303)
        (xy 19.964 -0.288)
        (xy 19.946 -0.275)
        (xy 19.926 -0.262)
        (xy 19.906 -0.249)
        (xy 19.887 -0.238)
        (xy 19.865 -0.228)
        (xy 19.844 -0.219)
        (xy 19.822 -0.211)
        (xy 19.8 -0.204)
        (xy 19.777 -0.2)
        (xy 19.754 -0.195)
        (xy 19.731 -0.192)
        (xy 19.707 -0.19)
        (xy 19.684 -0.189)
        (xy 19.661 -0.19)
        (xy 19.637 -0.192)
        (xy 19.614 -0.195)
        (xy 19.591 -0.2)
        (xy 19.568 -0.204)
        (xy 19.547 -0.211)
        (xy 19.524 -0.218)
        (xy 19.502 -0.228)
        (xy 19.481 -0.237)
        (xy 19.461 -0.248)
        (xy 19.441 -0.262)
        (xy 19.422 -0.275)
        (xy 19.403 -0.288)
        (xy 19.387 -0.303)
        (xy 19.37 -0.32)
        (xy 19.353 -0.337)
        (xy 19.338 -0.353)
        (xy 19.324 -0.372)
        (xy 19.312 -0.392)
        (xy 19.298 -0.411)
        (xy 19.287 -0.431)
        (xy 19.277 -0.453)
        (xy 19.268 -0.474)
        (xy 19.262 -0.496)
        (xy 19.254 -0.519)
        (xy 19.249 -0.541)
        (xy 19.245 -0.563)
        (xy 19.242 -0.586)
        (xy 19.24 -0.61)
        (xy 19.239 -0.631)
        (xy 19.684 -0.631)
        (xy 19.684 -0.636)
        (xy 19.684 -0.637)
      )

      (stroke (width 0.001) (type solid)) (fill solid) (layer "B.Paste"))
    (fp_poly
      (pts
        (xy 19.684 0.633)
        (xy 19.239 0.632)
        (xy 19.24 0.611)
        (xy 19.242 0.587)
        (xy 19.245 0.564)
        (xy 19.249 0.542)
        (xy 19.254 0.52)
        (xy 19.262 0.497)
        (xy 19.268 0.475)
        (xy 19.277 0.454)
        (xy 19.287 0.432)
        (xy 19.298 0.412)
        (xy 19.312 0.393)
        (xy 19.324 0.373)
        (xy 19.338 0.354)
        (xy 19.353 0.338)
        (xy 19.37 0.32)
        (xy 19.387 0.304)
        (xy 19.403 0.289)
        (xy 19.422 0.276)
        (xy 19.441 0.263)
        (xy 19.461 0.249)
        (xy 19.481 0.238)
        (xy 19.502 0.229)
        (xy 19.524 0.219)
        (xy 19.547 0.212)
        (xy 19.568 0.205)
        (xy 19.591 0.201)
        (xy 19.614 0.196)
        (xy 19.637 0.192)
        (xy 19.661 0.191)
        (xy 19.684 0.19)
        (xy 19.707 0.191)
        (xy 19.731 0.192)
        (xy 19.754 0.196)
        (xy 19.777 0.201)
        (xy 19.8 0.205)
        (xy 19.822 0.212)
        (xy 19.844 0.22)
        (xy 19.865 0.229)
        (xy 19.887 0.239)
        (xy 19.906 0.25)
        (xy 19.926 0.263)
        (xy 19.946 0.276)
        (xy 19.964 0.289)
        (xy 19.983 0.304)
        (xy 19.999 0.32)
        (xy 20.015 0.338)
        (xy 20.03 0.355)
        (xy 20.045 0.373)
        (xy 20.057 0.394)
        (xy 20.069 0.413)
        (xy 20.08 0.433)
        (xy 20.091 0.455)
        (xy 20.1 0.476)
        (xy 20.108 0.497)
        (xy 20.114 0.521)
        (xy 20.12 0.543)
        (xy 20.124 0.565)
        (xy 20.127 0.588)
        (xy 20.129 0.612)
        (xy 20.129 0.635)
        (xy 20.129 0.659)
        (xy 20.127 0.683)
        (xy 20.124 0.705)
        (xy 20.12 0.728)
        (xy 20.114 0.75)
        (xy 20.108 0.774)
        (xy 20.1 0.795)
        (xy 20.091 0.816)
        (xy 20.08 0.837)
        (xy 20.069 0.857)
        (xy 20.057 0.877)
        (xy 20.045 0.898)
        (xy 20.03 0.916)
        (xy 20.015 0.934)
        (xy 19.999 0.95)
        (xy 19.983 0.966)
        (xy 19.964 0.981)
        (xy 19.946 0.995)
        (xy 19.926 1.008)
        (xy 19.906 1.02)
        (xy 19.887 1.031)
        (xy 19.865 1.043)
        (xy 19.844 1.051)
        (xy 19.822 1.059)
        (xy 19.8 1.065)
        (xy 19.777 1.071)
        (xy 19.754 1.075)
        (xy 19.731 1.079)
        (xy 19.707 1.079)
        (xy 19.684 1.081)
        (xy 19.661 1.079)
        (xy 19.637 1.079)
        (xy 19.614 1.075)
        (xy 19.591 1.071)
        (xy 19.568 1.065)
        (xy 19.547 1.059)
        (xy 19.524 1.051)
        (xy 19.502 1.043)
        (xy 19.481 1.033)
        (xy 19.461 1.021)
        (xy 19.441 1.008)
        (xy 19.422 0.995)
        (xy 19.403 0.981)
        (xy 19.387 0.966)
        (xy 19.37 0.95)
        (xy 19.353 0.934)
        (xy 19.338 0.917)
        (xy 19.324 0.898)
        (xy 19.312 0.878)
        (xy 19.298 0.858)
        (xy 19.287 0.838)
        (xy 19.277 0.817)
        (xy 19.268 0.796)
        (xy 19.262 0.774)
        (xy 19.254 0.751)
        (xy 19.249 0.729)
        (xy 19.245 0.706)
        (xy 19.242 0.684)
        (xy 19.24 0.66)
        (xy 19.239 0.637)
        (xy 19.684 0.637)
        (xy 19.684 0.632)
        (xy 19.684 0.633)
      )

      (stroke (width 0.001) (type solid)) (fill solid) (layer "B.Paste"))
    (fp_poly
      (pts
        (xy 20.954 -4.447)
        (xy 20.51 -4.446)
        (xy 20.51 -4.469)
        (xy 20.512 -4.493)
        (xy 20.515 -4.515)
        (xy 20.519 -4.538)
        (xy 20.524 -4.56)
        (xy 20.531 -4.583)
        (xy 20.539 -4.605)
        (xy 20.547 -4.626)
        (xy 20.557 -4.647)
        (xy 20.568 -4.668)
        (xy 20.582 -4.687)
        (xy 20.594 -4.706)
        (xy 20.609 -4.725)
        (xy 20.623 -4.743)
        (xy 20.64 -4.759)
        (xy 20.656 -4.775)
        (xy 20.673 -4.791)
        (xy 20.693 -4.804)
        (xy 20.711 -4.817)
        (xy 20.731 -4.831)
        (xy 20.751 -4.841)
        (xy 20.772 -4.852)
        (xy 20.795 -4.86)
        (xy 20.816 -4.868)
        (xy 20.838 -4.874)
        (xy 20.861 -4.879)
        (xy 20.883 -4.884)
        (xy 20.906 -4.887)
        (xy 20.931 -4.889)
        (xy 20.954 -4.889)
        (xy 20.978 -4.889)
        (xy 21.001 -4.887)
        (xy 21.024 -4.884)
        (xy 21.047 -4.879)
        (xy 21.069 -4.874)
        (xy 21.092 -4.868)
        (xy 21.114 -4.86)
        (xy 21.135 -4.852)
        (xy 21.156 -4.841)
        (xy 21.176 -4.829)
        (xy 21.196 -4.817)
        (xy 21.216 -4.804)
        (xy 21.234 -4.791)
        (xy 21.252 -4.775)
        (xy 21.269 -4.759)
        (xy 21.286 -4.743)
        (xy 21.3 -4.724)
        (xy 21.315 -4.706)
        (xy 21.327 -4.687)
        (xy 21.339 -4.668)
        (xy 21.35 -4.647)
        (xy 21.361 -4.626)
        (xy 21.37 -4.603)
        (xy 21.377 -4.583)
        (xy 21.385 -4.559)
        (xy 21.39 -4.538)
        (xy 21.394 -4.514)
        (xy 21.397 -4.491)
        (xy 21.399 -4.467)
        (xy 21.399 -4.445)
        (xy 21.399 -4.421)
        (xy 21.397 -4.397)
        (xy 21.394 -4.374)
        (xy 21.39 -4.352)
        (xy 21.385 -4.329)
        (xy 21.377 -4.307)
        (xy 21.37 -4.285)
        (xy 21.361 -4.264)
        (xy 21.35 -4.243)
        (xy 21.339 -4.222)
        (xy 21.327 -4.203)
        (xy 21.315 -4.182)
        (xy 21.3 -4.164)
        (xy 21.286 -4.147)
        (xy 21.269 -4.129)
        (xy 21.252 -4.113)
        (xy 21.234 -4.099)
        (xy 21.216 -4.084)
        (xy 21.196 -4.071)
        (xy 21.176 -4.059)
        (xy 21.156 -4.049)
        (xy 21.135 -4.038)
        (xy 21.114 -4.03)
        (xy 21.092 -4.022)
        (xy 21.069 -4.014)
        (xy 21.047 -4.009)
        (xy 21.024 -4.004)
        (xy 21.001 -4.001)
        (xy 20.978 -4.001)
        (xy 20.954 -3.999)
        (xy 20.931 -4.001)
        (xy 20.906 -4.001)
        (xy 20.883 -4.004)
        (xy 20.861 -4.009)
        (xy 20.838 -4.014)
        (xy 20.816 -4.022)
        (xy 20.795 -4.028)
        (xy 20.772 -4.038)
        (xy 20.751 -4.047)
        (xy 20.731 -4.059)
        (xy 20.711 -4.071)
        (xy 20.693 -4.084)
        (xy 20.673 -4.099)
        (xy 20.656 -4.113)
        (xy 20.64 -4.129)
        (xy 20.623 -4.147)
        (xy 20.609 -4.163)
        (xy 20.594 -4.182)
        (xy 20.582 -4.201)
        (xy 20.568 -4.222)
        (xy 20.557 -4.241)
        (xy 20.547 -4.262)
        (xy 20.539 -4.285)
        (xy 20.531 -4.307)
        (xy 20.524 -4.328)
        (xy 20.519 -4.35)
        (xy 20.515 -4.373)
        (xy 20.512 -4.397)
        (xy 20.51 -4.421)
        (xy 20.51 -4.442)
        (xy 20.954 -4.442)
        (xy 20.954 -4.446)
        (xy 20.954 -4.447)
      )

      (stroke (width 0.001) (type solid)) (fill solid) (layer "B.Paste"))
    (fp_poly
      (pts
        (xy 20.954 -1.907)
        (xy 20.51 -1.906)
        (xy 20.51 -1.929)
        (xy 20.512 -1.953)
        (xy 20.515 -1.975)
        (xy 20.519 -1.999)
        (xy 20.524 -2.02)
        (xy 20.531 -2.043)
        (xy 20.539 -2.064)
        (xy 20.547 -2.087)
        (xy 20.557 -2.108)
        (xy 20.568 -2.128)
        (xy 20.582 -2.148)
        (xy 20.594 -2.166)
        (xy 20.609 -2.185)
        (xy 20.623 -2.202)
        (xy 20.64 -2.22)
        (xy 20.656 -2.236)
        (xy 20.673 -2.25)
        (xy 20.693 -2.265)
        (xy 20.711 -2.277)
        (xy 20.731 -2.29)
        (xy 20.751 -2.301)
        (xy 20.772 -2.311)
        (xy 20.795 -2.321)
        (xy 20.816 -2.327)
        (xy 20.838 -2.334)
        (xy 20.861 -2.339)
        (xy 20.883 -2.345)
        (xy 20.906 -2.347)
        (xy 20.931 -2.349)
        (xy 20.954 -2.35)
        (xy 20.978 -2.349)
        (xy 21.001 -2.347)
        (xy 21.024 -2.345)
        (xy 21.047 -2.339)
        (xy 21.069 -2.334)
        (xy 21.092 -2.327)
        (xy 21.114 -2.319)
        (xy 21.135 -2.311)
        (xy 21.156 -2.301)
        (xy 21.176 -2.289)
        (xy 21.196 -2.277)
        (xy 21.216 -2.265)
        (xy 21.234 -2.25)
        (xy 21.252 -2.236)
        (xy 21.269 -2.22)
        (xy 21.286 -2.202)
        (xy 21.3 -2.185)
        (xy 21.315 -2.166)
        (xy 21.327 -2.146)
        (xy 21.339 -2.126)
        (xy 21.35 -2.107)
        (xy 21.361 -2.085)
        (xy 21.37 -2.064)
        (xy 21.377 -2.043)
        (xy 21.385 -2.019)
        (xy 21.39 -1.997)
        (xy 21.394 -1.975)
        (xy 21.397 -1.951)
        (xy 21.399 -1.927)
        (xy 21.399 -1.904)
        (xy 21.399 -1.881)
        (xy 21.397 -1.858)
        (xy 21.394 -1.834)
        (xy 21.39 -1.812)
        (xy 21.385 -1.789)
        (xy 21.377 -1.766)
        (xy 21.37 -1.745)
        (xy 21.361 -1.723)
        (xy 21.35 -1.703)
        (xy 21.339 -1.683)
        (xy 21.327 -1.662)
        (xy 21.315 -1.642)
        (xy 21.3 -1.624)
        (xy 21.286 -1.606)
        (xy 21.269 -1.59)
        (xy 21.252 -1.574)
        (xy 21.234 -1.558)
        (xy 21.216 -1.544)
        (xy 21.196 -1.531)
        (xy 21.176 -1.519)
        (xy 21.156 -1.508)
        (xy 21.135 -1.497)
        (xy 21.114 -1.489)
        (xy 21.092 -1.481)
        (xy 21.069 -1.475)
        (xy 21.047 -1.469)
        (xy 21.024 -1.465)
        (xy 21.001 -1.461)
        (xy 20.978 -1.461)
        (xy 20.954 -1.459)
        (xy 20.931 -1.461)
        (xy 20.906 -1.461)
        (xy 20.883 -1.465)
        (xy 20.861 -1.469)
        (xy 20.838 -1.475)
        (xy 20.816 -1.481)
        (xy 20.795 -1.489)
        (xy 20.772 -1.497)
        (xy 20.751 -1.507)
        (xy 20.731 -1.518)
        (xy 20.711 -1.531)
        (xy 20.693 -1.544)
        (xy 20.673 -1.558)
        (xy 20.656 -1.574)
        (xy 20.64 -1.59)
        (xy 20.623 -1.606)
        (xy 20.609 -1.624)
        (xy 20.594 -1.642)
        (xy 20.582 -1.661)
        (xy 20.568 -1.681)
        (xy 20.557 -1.701)
        (xy 20.547 -1.723)
        (xy 20.539 -1.745)
        (xy 20.531 -1.766)
        (xy 20.524 -1.788)
        (xy 20.519 -1.81)
        (xy 20.515 -1.834)
        (xy 20.512 -1.856)
        (xy 20.51 -1.88)
        (xy 20.51 -1.902)
        (xy 20.954 -1.902)
        (xy 20.954 -1.906)
        (xy 20.954 -1.907)
      )

      (stroke (width 0.001) (type solid)) (fill solid) (layer "B.Paste"))
    (fp_poly
      (pts
        (xy 20.954 -0.637)
        (xy 20.51 -0.636)
        (xy 20.51 -0.659)
        (xy 20.512 -0.683)
        (xy 20.515 -0.705)
        (xy 20.519 -0.728)
        (xy 20.524 -0.75)
        (xy 20.531 -0.773)
        (xy 20.539 -0.795)
        (xy 20.547 -0.816)
        (xy 20.557 -0.837)
        (xy 20.568 -0.857)
        (xy 20.582 -0.877)
        (xy 20.594 -0.897)
        (xy 20.609 -0.916)
        (xy 20.623 -0.933)
        (xy 20.64 -0.949)
        (xy 20.656 -0.965)
        (xy 20.673 -0.98)
        (xy 20.693 -0.994)
        (xy 20.711 -1.007)
        (xy 20.731 -1.02)
        (xy 20.751 -1.032)
        (xy 20.772 -1.042)
        (xy 20.795 -1.05)
        (xy 20.816 -1.058)
        (xy 20.838 -1.064)
        (xy 20.861 -1.07)
        (xy 20.883 -1.074)
        (xy 20.906 -1.078)
        (xy 20.931 -1.078)
        (xy 20.954 -1.08)
        (xy 20.978 -1.078)
        (xy 21.001 -1.078)
        (xy 21.024 -1.074)
        (xy 21.047 -1.07)
        (xy 21.069 -1.064)
        (xy 21.092 -1.058)
        (xy 21.114 -1.05)
        (xy 21.135 -1.042)
        (xy 21.156 -1.03)
        (xy 21.176 -1.019)
        (xy 21.196 -1.007)
        (xy 21.216 -0.994)
        (xy 21.234 -0.98)
        (xy 21.252 -0.965)
        (xy 21.269 -0.949)
        (xy 21.286 -0.933)
        (xy 21.3 -0.915)
        (xy 21.315 -0.897)
        (xy 21.327 -0.876)
        (xy 21.339 -0.856)
        (xy 21.35 -0.836)
        (xy 21.361 -0.815)
        (xy 21.37 -0.794)
        (xy 21.377 -0.773)
        (xy 21.385 -0.749)
        (xy 21.39 -0.727)
        (xy 21.394 -0.704)
        (xy 21.397 -0.682)
        (xy 21.399 -0.658)
        (xy 21.399 -0.634)
        (xy 21.399 -0.611)
        (xy 21.397 -0.587)
        (xy 21.394 -0.564)
        (xy 21.39 -0.542)
        (xy 21.385 -0.52)
        (xy 21.377 -0.496)
        (xy 21.37 -0.475)
        (xy 21.361 -0.454)
        (xy 21.35 -0.432)
        (xy 21.339 -0.412)
        (xy 21.327 -0.393)
        (xy 21.315 -0.372)
        (xy 21.3 -0.354)
        (xy 21.286 -0.337)
        (xy 21.269 -0.32)
        (xy 21.252 -0.303)
        (xy 21.234 -0.288)
        (xy 21.216 -0.275)
        (xy 21.196 -0.262)
        (xy 21.176 -0.249)
        (xy 21.156 -0.238)
        (xy 21.135 -0.228)
        (xy 21.114 -0.219)
        (xy 21.092 -0.211)
        (xy 21.069 -0.204)
        (xy 21.047 -0.2)
        (xy 21.024 -0.195)
        (xy 21.001 -0.192)
        (xy 20.978 -0.19)
        (xy 20.954 -0.189)
        (xy 20.931 -0.19)
        (xy 20.906 -0.192)
        (xy 20.883 -0.195)
        (xy 20.861 -0.2)
        (xy 20.838 -0.204)
        (xy 20.816 -0.211)
        (xy 20.795 -0.218)
        (xy 20.772 -0.228)
        (xy 20.751 -0.237)
        (xy 20.731 -0.248)
        (xy 20.711 -0.262)
        (xy 20.693 -0.275)
        (xy 20.673 -0.288)
        (xy 20.656 -0.303)
        (xy 20.64 -0.32)
        (xy 20.623 -0.337)
        (xy 20.609 -0.353)
        (xy 20.594 -0.372)
        (xy 20.582 -0.392)
        (xy 20.568 -0.411)
        (xy 20.557 -0.431)
        (xy 20.547 -0.453)
        (xy 20.539 -0.474)
        (xy 20.531 -0.496)
        (xy 20.524 -0.519)
        (xy 20.519 -0.541)
        (xy 20.515 -0.563)
        (xy 20.512 -0.586)
        (xy 20.51 -0.61)
        (xy 20.51 -0.631)
        (xy 20.954 -0.631)
        (xy 20.954 -0.636)
        (xy 20.954 -0.637)
      )

      (stroke (width 0.001) (type solid)) (fill solid) (layer "B.Paste"))
    (fp_poly
      (pts
        (xy 20.954 0.633)
        (xy 20.51 0.632)
        (xy 20.51 0.611)
        (xy 20.512 0.587)
        (xy 20.515 0.564)
        (xy 20.519 0.542)
        (xy 20.524 0.52)
        (xy 20.531 0.497)
        (xy 20.539 0.475)
        (xy 20.547 0.454)
        (xy 20.557 0.432)
        (xy 20.568 0.412)
        (xy 20.582 0.393)
        (xy 20.594 0.373)
        (xy 20.609 0.354)
        (xy 20.623 0.338)
        (xy 20.64 0.32)
        (xy 20.656 0.304)
        (xy 20.673 0.289)
        (xy 20.693 0.276)
        (xy 20.711 0.263)
        (xy 20.731 0.249)
        (xy 20.751 0.238)
        (xy 20.772 0.229)
        (xy 20.795 0.219)
        (xy 20.816 0.212)
        (xy 20.838 0.205)
        (xy 20.861 0.201)
        (xy 20.883 0.196)
        (xy 20.906 0.192)
        (xy 20.931 0.191)
        (xy 20.954 0.19)
        (xy 20.978 0.191)
        (xy 21.001 0.192)
        (xy 21.024 0.196)
        (xy 21.047 0.201)
        (xy 21.069 0.205)
        (xy 21.092 0.212)
        (xy 21.114 0.22)
        (xy 21.135 0.229)
        (xy 21.156 0.239)
        (xy 21.176 0.25)
        (xy 21.196 0.263)
        (xy 21.216 0.276)
        (xy 21.234 0.289)
        (xy 21.252 0.304)
        (xy 21.269 0.32)
        (xy 21.286 0.338)
        (xy 21.3 0.355)
        (xy 21.315 0.373)
        (xy 21.327 0.394)
        (xy 21.339 0.413)
        (xy 21.35 0.433)
        (xy 21.361 0.455)
        (xy 21.37 0.476)
        (xy 21.377 0.497)
        (xy 21.385 0.521)
        (xy 21.39 0.543)
        (xy 21.394 0.565)
        (xy 21.397 0.588)
        (xy 21.399 0.612)
        (xy 21.399 0.635)
        (xy 21.399 0.659)
        (xy 21.397 0.683)
        (xy 21.394 0.705)
        (xy 21.39 0.728)
        (xy 21.385 0.75)
        (xy 21.377 0.774)
        (xy 21.37 0.795)
        (xy 21.361 0.816)
        (xy 21.35 0.837)
        (xy 21.339 0.857)
        (xy 21.327 0.877)
        (xy 21.315 0.898)
        (xy 21.3 0.916)
        (xy 21.286 0.934)
        (xy 21.269 0.95)
        (xy 21.252 0.966)
        (xy 21.234 0.981)
        (xy 21.216 0.995)
        (xy 21.196 1.008)
        (xy 21.176 1.02)
        (xy 21.156 1.031)
        (xy 21.135 1.043)
        (xy 21.114 1.051)
        (xy 21.092 1.059)
        (xy 21.069 1.065)
        (xy 21.047 1.071)
        (xy 21.024 1.075)
        (xy 21.001 1.079)
        (xy 20.978 1.079)
        (xy 20.954 1.081)
        (xy 20.931 1.079)
        (xy 20.906 1.079)
        (xy 20.883 1.075)
        (xy 20.861 1.071)
        (xy 20.838 1.065)
        (xy 20.816 1.059)
        (xy 20.795 1.051)
        (xy 20.772 1.043)
        (xy 20.751 1.033)
        (xy 20.731 1.021)
        (xy 20.711 1.008)
        (xy 20.693 0.995)
        (xy 20.673 0.981)
        (xy 20.656 0.966)
        (xy 20.64 0.95)
        (xy 20.623 0.934)
        (xy 20.609 0.917)
        (xy 20.594 0.898)
        (xy 20.582 0.878)
        (xy 20.568 0.858)
        (xy 20.557 0.838)
        (xy 20.547 0.817)
        (xy 20.539 0.796)
        (xy 20.531 0.774)
        (xy 20.524 0.751)
        (xy 20.519 0.729)
        (xy 20.515 0.706)
        (xy 20.512 0.684)
        (xy 20.51 0.66)
        (xy 20.51 0.637)
        (xy 20.954 0.637)
        (xy 20.954 0.632)
        (xy 20.954 0.633)
      )

      (stroke (width 0.001) (type solid)) (fill solid) (layer "B.Paste"))
    (fp_poly
      (pts
        (xy 22.225 -4.447)
        (xy 21.78 -4.446)
        (xy 21.78 -4.469)
        (xy 21.781 -4.493)
        (xy 21.784 -4.515)
        (xy 21.789 -4.538)
        (xy 21.795 -4.56)
        (xy 21.801 -4.583)
        (xy 21.809 -4.605)
        (xy 21.818 -4.626)
        (xy 21.827 -4.647)
        (xy 21.838 -4.668)
        (xy 21.851 -4.687)
        (xy 21.864 -4.706)
        (xy 21.879 -4.725)
        (xy 21.893 -4.743)
        (xy 21.909 -4.759)
        (xy 21.926 -4.775)
        (xy 21.943 -4.791)
        (xy 21.963 -4.804)
        (xy 21.981 -4.817)
        (xy 22.001 -4.831)
        (xy 22.021 -4.841)
        (xy 22.042 -4.852)
        (xy 22.065 -4.86)
        (xy 22.086 -4.868)
        (xy 22.109 -4.874)
        (xy 22.13 -4.879)
        (xy 22.153 -4.884)
        (xy 22.176 -4.887)
        (xy 22.201 -4.889)
        (xy 22.225 -4.889)
        (xy 22.248 -4.889)
        (xy 22.271 -4.887)
        (xy 22.295 -4.884)
        (xy 22.318 -4.879)
        (xy 22.339 -4.874)
        (xy 22.362 -4.868)
        (xy 22.383 -4.86)
        (xy 22.405 -4.852)
        (xy 22.426 -4.841)
        (xy 22.447 -4.829)
        (xy 22.466 -4.817)
        (xy 22.486 -4.804)
        (xy 22.504 -4.791)
        (xy 22.522 -4.775)
        (xy 22.539 -4.759)
        (xy 22.556 -4.743)
        (xy 22.571 -4.724)
        (xy 22.585 -4.706)
        (xy 22.597 -4.687)
        (xy 22.609 -4.668)
        (xy 22.62 -4.647)
        (xy 22.632 -4.626)
        (xy 22.64 -4.603)
        (xy 22.647 -4.583)
        (xy 22.655 -4.559)
        (xy 22.659 -4.538)
        (xy 22.664 -4.514)
        (xy 22.667 -4.491)
        (xy 22.669 -4.467)
        (xy 22.67 -4.445)
        (xy 22.669 -4.421)
        (xy 22.667 -4.397)
        (xy 22.664 -4.374)
        (xy 22.659 -4.352)
        (xy 22.655 -4.329)
        (xy 22.647 -4.307)
        (xy 22.64 -4.285)
        (xy 22.632 -4.264)
        (xy 22.62 -4.243)
        (xy 22.609 -4.222)
        (xy 22.597 -4.203)
        (xy 22.585 -4.182)
        (xy 22.571 -4.164)
        (xy 22.556 -4.147)
        (xy 22.539 -4.129)
        (xy 22.522 -4.113)
        (xy 22.504 -4.099)
        (xy 22.486 -4.084)
        (xy 22.466 -4.071)
        (xy 22.447 -4.059)
        (xy 22.426 -4.049)
        (xy 22.405 -4.038)
        (xy 22.383 -4.03)
        (xy 22.362 -4.022)
        (xy 22.339 -4.014)
        (xy 22.318 -4.009)
        (xy 22.295 -4.004)
        (xy 22.271 -4.001)
        (xy 22.248 -4.001)
        (xy 22.225 -3.999)
        (xy 22.201 -4.001)
        (xy 22.176 -4.001)
        (xy 22.153 -4.004)
        (xy 22.13 -4.009)
        (xy 22.109 -4.014)
        (xy 22.086 -4.022)
        (xy 22.065 -4.028)
        (xy 22.042 -4.038)
        (xy 22.021 -4.047)
        (xy 22.001 -4.059)
        (xy 21.981 -4.071)
        (xy 21.963 -4.084)
        (xy 21.943 -4.099)
        (xy 21.926 -4.113)
        (xy 21.909 -4.129)
        (xy 21.893 -4.147)
        (xy 21.879 -4.163)
        (xy 21.864 -4.182)
        (xy 21.851 -4.201)
        (xy 21.838 -4.222)
        (xy 21.827 -4.241)
        (xy 21.818 -4.262)
        (xy 21.809 -4.285)
        (xy 21.801 -4.307)
        (xy 21.795 -4.328)
        (xy 21.789 -4.35)
        (xy 21.784 -4.373)
        (xy 21.781 -4.397)
        (xy 21.78 -4.421)
        (xy 21.78 -4.442)
        (xy 22.225 -4.442)
        (xy 22.225 -4.446)
        (xy 22.225 -4.447)
      )

      (stroke (width 0.001) (type solid)) (fill solid) (layer "B.Paste"))
    (fp_poly
      (pts
        (xy 22.225 -1.907)
        (xy 21.78 -1.906)
        (xy 21.78 -1.929)
        (xy 21.781 -1.953)
        (xy 21.784 -1.975)
        (xy 21.789 -1.999)
        (xy 21.795 -2.02)
        (xy 21.801 -2.043)
        (xy 21.809 -2.064)
        (xy 21.818 -2.087)
        (xy 21.827 -2.108)
        (xy 21.838 -2.128)
        (xy 21.851 -2.148)
        (xy 21.864 -2.166)
        (xy 21.879 -2.185)
        (xy 21.893 -2.202)
        (xy 21.909 -2.22)
        (xy 21.926 -2.236)
        (xy 21.943 -2.25)
        (xy 21.963 -2.265)
        (xy 21.981 -2.277)
        (xy 22.001 -2.29)
        (xy 22.021 -2.301)
        (xy 22.042 -2.311)
        (xy 22.065 -2.321)
        (xy 22.086 -2.327)
        (xy 22.109 -2.334)
        (xy 22.13 -2.339)
        (xy 22.153 -2.345)
        (xy 22.176 -2.347)
        (xy 22.201 -2.349)
        (xy 22.225 -2.35)
        (xy 22.248 -2.349)
        (xy 22.271 -2.347)
        (xy 22.295 -2.345)
        (xy 22.318 -2.339)
        (xy 22.339 -2.334)
        (xy 22.362 -2.327)
        (xy 22.383 -2.319)
        (xy 22.405 -2.311)
        (xy 22.426 -2.301)
        (xy 22.447 -2.289)
        (xy 22.466 -2.277)
        (xy 22.486 -2.265)
        (xy 22.504 -2.25)
        (xy 22.522 -2.236)
        (xy 22.539 -2.22)
        (xy 22.556 -2.202)
        (xy 22.571 -2.185)
        (xy 22.585 -2.166)
        (xy 22.597 -2.146)
        (xy 22.609 -2.126)
        (xy 22.62 -2.107)
        (xy 22.632 -2.085)
        (xy 22.64 -2.064)
        (xy 22.647 -2.043)
        (xy 22.655 -2.019)
        (xy 22.659 -1.997)
        (xy 22.664 -1.975)
        (xy 22.667 -1.951)
        (xy 22.669 -1.927)
        (xy 22.67 -1.904)
        (xy 22.669 -1.881)
        (xy 22.667 -1.858)
        (xy 22.664 -1.834)
        (xy 22.659 -1.812)
        (xy 22.655 -1.789)
        (xy 22.647 -1.766)
        (xy 22.64 -1.745)
        (xy 22.632 -1.723)
        (xy 22.62 -1.703)
        (xy 22.609 -1.683)
        (xy 22.597 -1.662)
        (xy 22.585 -1.642)
        (xy 22.571 -1.624)
        (xy 22.556 -1.606)
        (xy 22.539 -1.59)
        (xy 22.522 -1.574)
        (xy 22.504 -1.558)
        (xy 22.486 -1.544)
        (xy 22.466 -1.531)
        (xy 22.447 -1.519)
        (xy 22.426 -1.508)
        (xy 22.405 -1.497)
        (xy 22.383 -1.489)
        (xy 22.362 -1.481)
        (xy 22.339 -1.475)
        (xy 22.318 -1.469)
        (xy 22.295 -1.465)
        (xy 22.271 -1.461)
        (xy 22.248 -1.461)
        (xy 22.225 -1.459)
        (xy 22.201 -1.461)
        (xy 22.176 -1.461)
        (xy 22.153 -1.465)
        (xy 22.13 -1.469)
        (xy 22.109 -1.475)
        (xy 22.086 -1.481)
        (xy 22.065 -1.489)
        (xy 22.042 -1.497)
        (xy 22.021 -1.507)
        (xy 22.001 -1.518)
        (xy 21.981 -1.531)
        (xy 21.963 -1.544)
        (xy 21.943 -1.558)
        (xy 21.926 -1.574)
        (xy 21.909 -1.59)
        (xy 21.893 -1.606)
        (xy 21.879 -1.624)
        (xy 21.864 -1.642)
        (xy 21.851 -1.661)
        (xy 21.838 -1.681)
        (xy 21.827 -1.701)
        (xy 21.818 -1.723)
        (xy 21.809 -1.745)
        (xy 21.801 -1.766)
        (xy 21.795 -1.788)
        (xy 21.789 -1.81)
        (xy 21.784 -1.834)
        (xy 21.781 -1.856)
        (xy 21.78 -1.88)
        (xy 21.78 -1.902)
        (xy 22.225 -1.902)
        (xy 22.225 -1.906)
        (xy 22.225 -1.907)
      )

      (stroke (width 0.001) (type solid)) (fill solid) (layer "B.Paste"))
    (fp_poly
      (pts
        (xy 22.225 -0.637)
        (xy 21.78 -0.636)
        (xy 21.78 -0.659)
        (xy 21.781 -0.683)
        (xy 21.784 -0.705)
        (xy 21.789 -0.728)
        (xy 21.795 -0.75)
        (xy 21.801 -0.773)
        (xy 21.809 -0.795)
        (xy 21.818 -0.816)
        (xy 21.827 -0.837)
        (xy 21.838 -0.857)
        (xy 21.851 -0.877)
        (xy 21.864 -0.897)
        (xy 21.879 -0.916)
        (xy 21.893 -0.933)
        (xy 21.909 -0.949)
        (xy 21.926 -0.965)
        (xy 21.943 -0.98)
        (xy 21.963 -0.994)
        (xy 21.981 -1.007)
        (xy 22.001 -1.02)
        (xy 22.021 -1.032)
        (xy 22.042 -1.042)
        (xy 22.065 -1.05)
        (xy 22.086 -1.058)
        (xy 22.109 -1.064)
        (xy 22.13 -1.07)
        (xy 22.153 -1.074)
        (xy 22.176 -1.078)
        (xy 22.201 -1.078)
        (xy 22.225 -1.08)
        (xy 22.248 -1.078)
        (xy 22.271 -1.078)
        (xy 22.295 -1.074)
        (xy 22.318 -1.07)
        (xy 22.339 -1.064)
        (xy 22.362 -1.058)
        (xy 22.383 -1.05)
        (xy 22.405 -1.042)
        (xy 22.426 -1.03)
        (xy 22.447 -1.019)
        (xy 22.466 -1.007)
        (xy 22.486 -0.994)
        (xy 22.504 -0.98)
        (xy 22.522 -0.965)
        (xy 22.539 -0.949)
        (xy 22.556 -0.933)
        (xy 22.571 -0.915)
        (xy 22.585 -0.897)
        (xy 22.597 -0.876)
        (xy 22.609 -0.856)
        (xy 22.62 -0.836)
        (xy 22.632 -0.815)
        (xy 22.64 -0.794)
        (xy 22.647 -0.773)
        (xy 22.655 -0.749)
        (xy 22.659 -0.727)
        (xy 22.664 -0.704)
        (xy 22.667 -0.682)
        (xy 22.669 -0.658)
        (xy 22.67 -0.634)
        (xy 22.669 -0.611)
        (xy 22.667 -0.587)
        (xy 22.664 -0.564)
        (xy 22.659 -0.542)
        (xy 22.655 -0.52)
        (xy 22.647 -0.496)
        (xy 22.64 -0.475)
        (xy 22.632 -0.454)
        (xy 22.62 -0.432)
        (xy 22.609 -0.412)
        (xy 22.597 -0.393)
        (xy 22.585 -0.372)
        (xy 22.571 -0.354)
        (xy 22.556 -0.337)
        (xy 22.539 -0.32)
        (xy 22.522 -0.303)
        (xy 22.504 -0.288)
        (xy 22.486 -0.275)
        (xy 22.466 -0.262)
        (xy 22.447 -0.249)
        (xy 22.426 -0.238)
        (xy 22.405 -0.228)
        (xy 22.383 -0.219)
        (xy 22.362 -0.211)
        (xy 22.339 -0.204)
        (xy 22.318 -0.2)
        (xy 22.295 -0.195)
        (xy 22.271 -0.192)
        (xy 22.248 -0.19)
        (xy 22.225 -0.189)
        (xy 22.201 -0.19)
        (xy 22.176 -0.192)
        (xy 22.153 -0.195)
        (xy 22.13 -0.2)
        (xy 22.109 -0.204)
        (xy 22.086 -0.211)
        (xy 22.065 -0.218)
        (xy 22.042 -0.228)
        (xy 22.021 -0.237)
        (xy 22.001 -0.248)
        (xy 21.981 -0.262)
        (xy 21.963 -0.275)
        (xy 21.943 -0.288)
        (xy 21.926 -0.303)
        (xy 21.909 -0.32)
        (xy 21.893 -0.337)
        (xy 21.879 -0.353)
        (xy 21.864 -0.372)
        (xy 21.851 -0.392)
        (xy 21.838 -0.411)
        (xy 21.827 -0.431)
        (xy 21.818 -0.453)
        (xy 21.809 -0.474)
        (xy 21.801 -0.496)
        (xy 21.795 -0.519)
        (xy 21.789 -0.541)
        (xy 21.784 -0.563)
        (xy 21.781 -0.586)
        (xy 21.78 -0.61)
        (xy 21.78 -0.631)
        (xy 22.225 -0.631)
        (xy 22.225 -0.636)
        (xy 22.225 -0.637)
      )

      (stroke (width 0.001) (type solid)) (fill solid) (layer "B.Paste"))
    (fp_poly
      (pts
        (xy 22.225 0.633)
        (xy 21.78 0.632)
        (xy 21.78 0.611)
        (xy 21.781 0.587)
        (xy 21.784 0.564)
        (xy 21.789 0.542)
        (xy 21.795 0.52)
        (xy 21.801 0.497)
        (xy 21.809 0.475)
        (xy 21.818 0.454)
        (xy 21.827 0.432)
        (xy 21.838 0.412)
        (xy 21.851 0.393)
        (xy 21.864 0.373)
        (xy 21.879 0.354)
        (xy 21.893 0.338)
        (xy 21.909 0.32)
        (xy 21.926 0.304)
        (xy 21.943 0.289)
        (xy 21.963 0.276)
        (xy 21.981 0.263)
        (xy 22.001 0.249)
        (xy 22.021 0.238)
        (xy 22.042 0.229)
        (xy 22.065 0.219)
        (xy 22.086 0.212)
        (xy 22.109 0.205)
        (xy 22.13 0.201)
        (xy 22.153 0.196)
        (xy 22.176 0.192)
        (xy 22.201 0.191)
        (xy 22.225 0.19)
        (xy 22.248 0.191)
        (xy 22.271 0.192)
        (xy 22.295 0.196)
        (xy 22.318 0.201)
        (xy 22.339 0.205)
        (xy 22.362 0.212)
        (xy 22.383 0.22)
        (xy 22.405 0.229)
        (xy 22.426 0.239)
        (xy 22.447 0.25)
        (xy 22.466 0.263)
        (xy 22.486 0.276)
        (xy 22.504 0.289)
        (xy 22.522 0.304)
        (xy 22.539 0.32)
        (xy 22.556 0.338)
        (xy 22.571 0.355)
        (xy 22.585 0.373)
        (xy 22.597 0.394)
        (xy 22.609 0.413)
        (xy 22.62 0.433)
        (xy 22.632 0.455)
        (xy 22.64 0.476)
        (xy 22.647 0.497)
        (xy 22.655 0.521)
        (xy 22.659 0.543)
        (xy 22.664 0.565)
        (xy 22.667 0.588)
        (xy 22.669 0.612)
        (xy 22.67 0.635)
        (xy 22.669 0.659)
        (xy 22.667 0.683)
        (xy 22.664 0.705)
        (xy 22.659 0.728)
        (xy 22.655 0.75)
        (xy 22.647 0.774)
        (xy 22.64 0.795)
        (xy 22.632 0.816)
        (xy 22.62 0.837)
        (xy 22.609 0.857)
        (xy 22.597 0.877)
        (xy 22.585 0.898)
        (xy 22.571 0.916)
        (xy 22.556 0.934)
        (xy 22.539 0.95)
        (xy 22.522 0.966)
        (xy 22.504 0.981)
        (xy 22.486 0.995)
        (xy 22.466 1.008)
        (xy 22.447 1.02)
        (xy 22.426 1.031)
        (xy 22.405 1.043)
        (xy 22.383 1.051)
        (xy 22.362 1.059)
        (xy 22.339 1.065)
        (xy 22.318 1.071)
        (xy 22.295 1.075)
        (xy 22.271 1.079)
        (xy 22.248 1.079)
        (xy 22.225 1.081)
        (xy 22.201 1.079)
        (xy 22.176 1.079)
        (xy 22.153 1.075)
        (xy 22.13 1.071)
        (xy 22.109 1.065)
        (xy 22.086 1.059)
        (xy 22.065 1.051)
        (xy 22.042 1.043)
        (xy 22.021 1.033)
        (xy 22.001 1.021)
        (xy 21.981 1.008)
        (xy 21.963 0.995)
        (xy 21.943 0.981)
        (xy 21.926 0.966)
        (xy 21.909 0.95)
        (xy 21.893 0.934)
        (xy 21.879 0.917)
        (xy 21.864 0.898)
        (xy 21.851 0.878)
        (xy 21.838 0.858)
        (xy 21.827 0.838)
        (xy 21.818 0.817)
        (xy 21.809 0.796)
        (xy 21.801 0.774)
        (xy 21.795 0.751)
        (xy 21.789 0.729)
        (xy 21.784 0.706)
        (xy 21.781 0.684)
        (xy 21.78 0.66)
        (xy 21.78 0.637)
        (xy 22.225 0.637)
        (xy 22.225 0.632)
        (xy 22.225 0.633)
      )

      (stroke (width 0.001) (type solid)) (fill solid) (layer "B.Paste"))
    (fp_poly
      (pts
        (xy 23.495 -4.447)
        (xy 23.05 -4.446)
        (xy 23.05 -4.469)
        (xy 23.051 -4.493)
        (xy 23.054 -4.515)
        (xy 23.059 -4.538)
        (xy 23.065 -4.56)
        (xy 23.071 -4.583)
        (xy 23.079 -4.605)
        (xy 23.088 -4.626)
        (xy 23.097 -4.647)
        (xy 23.109 -4.668)
        (xy 23.121 -4.687)
        (xy 23.135 -4.706)
        (xy 23.149 -4.725)
        (xy 23.164 -4.743)
        (xy 23.179 -4.759)
        (xy 23.196 -4.775)
        (xy 23.213 -4.791)
        (xy 23.233 -4.804)
        (xy 23.251 -4.817)
        (xy 23.271 -4.831)
        (xy 23.292 -4.841)
        (xy 23.312 -4.852)
        (xy 23.335 -4.86)
        (xy 23.356 -4.868)
        (xy 23.379 -4.874)
        (xy 23.4 -4.879)
        (xy 23.423 -4.884)
        (xy 23.446 -4.887)
        (xy 23.47 -4.889)
        (xy 23.495 -4.889)
        (xy 23.518 -4.889)
        (xy 23.542 -4.887)
        (xy 23.565 -4.884)
        (xy 23.588 -4.879)
        (xy 23.609 -4.874)
        (xy 23.632 -4.868)
        (xy 23.653 -4.86)
        (xy 23.675 -4.852)
        (xy 23.696 -4.841)
        (xy 23.717 -4.829)
        (xy 23.736 -4.817)
        (xy 23.757 -4.804)
        (xy 23.774 -4.791)
        (xy 23.792 -4.775)
        (xy 23.809 -4.759)
        (xy 23.826 -4.743)
        (xy 23.841 -4.724)
        (xy 23.854 -4.706)
        (xy 23.867 -4.687)
        (xy 23.879 -4.668)
        (xy 23.89 -4.647)
        (xy 23.902 -4.626)
        (xy 23.909 -4.603)
        (xy 23.917 -4.583)
        (xy 23.925 -4.559)
        (xy 23.929 -4.538)
        (xy 23.934 -4.514)
        (xy 23.937 -4.491)
        (xy 23.938 -4.467)
        (xy 23.94 -4.445)
        (xy 23.938 -4.421)
        (xy 23.937 -4.397)
        (xy 23.934 -4.374)
        (xy 23.929 -4.352)
        (xy 23.925 -4.329)
        (xy 23.917 -4.307)
        (xy 23.909 -4.285)
        (xy 23.902 -4.264)
        (xy 23.89 -4.243)
        (xy 23.879 -4.222)
        (xy 23.867 -4.203)
        (xy 23.854 -4.182)
        (xy 23.841 -4.164)
        (xy 23.826 -4.147)
        (xy 23.809 -4.129)
        (xy 23.792 -4.113)
        (xy 23.774 -4.099)
        (xy 23.757 -4.084)
        (xy 23.736 -4.071)
        (xy 23.717 -4.059)
        (xy 23.696 -4.049)
        (xy 23.675 -4.038)
        (xy 23.653 -4.03)
        (xy 23.632 -4.022)
        (xy 23.609 -4.014)
        (xy 23.588 -4.009)
        (xy 23.565 -4.004)
        (xy 23.542 -4.001)
        (xy 23.518 -4.001)
        (xy 23.495 -3.999)
        (xy 23.47 -4.001)
        (xy 23.446 -4.001)
        (xy 23.423 -4.004)
        (xy 23.4 -4.009)
        (xy 23.379 -4.014)
        (xy 23.356 -4.022)
        (xy 23.335 -4.028)
        (xy 23.312 -4.038)
        (xy 23.292 -4.047)
        (xy 23.271 -4.059)
        (xy 23.251 -4.071)
        (xy 23.233 -4.084)
        (xy 23.213 -4.099)
        (xy 23.196 -4.113)
        (xy 23.179 -4.129)
        (xy 23.164 -4.147)
        (xy 23.149 -4.163)
        (xy 23.135 -4.182)
        (xy 23.121 -4.201)
        (xy 23.109 -4.222)
        (xy 23.097 -4.241)
        (xy 23.088 -4.262)
        (xy 23.079 -4.285)
        (xy 23.071 -4.307)
        (xy 23.065 -4.328)
        (xy 23.059 -4.35)
        (xy 23.054 -4.373)
        (xy 23.051 -4.397)
        (xy 23.05 -4.421)
        (xy 23.05 -4.442)
        (xy 23.495 -4.442)
        (xy 23.495 -4.446)
        (xy 23.495 -4.447)
      )

      (stroke (width 0.001) (type solid)) (fill solid) (layer "B.Paste"))
    (fp_poly
      (pts
        (xy 23.495 -1.907)
        (xy 23.05 -1.906)
        (xy 23.05 -1.929)
        (xy 23.051 -1.953)
        (xy 23.054 -1.975)
        (xy 23.059 -1.999)
        (xy 23.065 -2.02)
        (xy 23.071 -2.043)
        (xy 23.079 -2.064)
        (xy 23.088 -2.087)
        (xy 23.097 -2.108)
        (xy 23.109 -2.128)
        (xy 23.121 -2.148)
        (xy 23.135 -2.166)
        (xy 23.149 -2.185)
        (xy 23.164 -2.202)
        (xy 23.179 -2.22)
        (xy 23.196 -2.236)
        (xy 23.213 -2.25)
        (xy 23.233 -2.265)
        (xy 23.251 -2.277)
        (xy 23.271 -2.29)
        (xy 23.292 -2.301)
        (xy 23.312 -2.311)
        (xy 23.335 -2.321)
        (xy 23.356 -2.327)
        (xy 23.379 -2.334)
        (xy 23.4 -2.339)
        (xy 23.423 -2.345)
        (xy 23.446 -2.347)
        (xy 23.47 -2.349)
        (xy 23.495 -2.35)
        (xy 23.518 -2.349)
        (xy 23.542 -2.347)
        (xy 23.565 -2.345)
        (xy 23.588 -2.339)
        (xy 23.609 -2.334)
        (xy 23.632 -2.327)
        (xy 23.653 -2.319)
        (xy 23.675 -2.311)
        (xy 23.696 -2.301)
        (xy 23.717 -2.289)
        (xy 23.736 -2.277)
        (xy 23.757 -2.265)
        (xy 23.774 -2.25)
        (xy 23.792 -2.236)
        (xy 23.809 -2.22)
        (xy 23.826 -2.202)
        (xy 23.841 -2.185)
        (xy 23.854 -2.166)
        (xy 23.867 -2.146)
        (xy 23.879 -2.126)
        (xy 23.89 -2.107)
        (xy 23.902 -2.085)
        (xy 23.909 -2.064)
        (xy 23.917 -2.043)
        (xy 23.925 -2.019)
        (xy 23.929 -1.997)
        (xy 23.934 -1.975)
        (xy 23.937 -1.951)
        (xy 23.938 -1.927)
        (xy 23.94 -1.904)
        (xy 23.938 -1.881)
        (xy 23.937 -1.858)
        (xy 23.934 -1.834)
        (xy 23.929 -1.812)
        (xy 23.925 -1.789)
        (xy 23.917 -1.766)
        (xy 23.909 -1.745)
        (xy 23.902 -1.723)
        (xy 23.89 -1.703)
        (xy 23.879 -1.683)
        (xy 23.867 -1.662)
        (xy 23.854 -1.642)
        (xy 23.841 -1.624)
        (xy 23.826 -1.606)
        (xy 23.809 -1.59)
        (xy 23.792 -1.574)
        (xy 23.774 -1.558)
        (xy 23.757 -1.544)
        (xy 23.736 -1.531)
        (xy 23.717 -1.519)
        (xy 23.696 -1.508)
        (xy 23.675 -1.497)
        (xy 23.653 -1.489)
        (xy 23.632 -1.481)
        (xy 23.609 -1.475)
        (xy 23.588 -1.469)
        (xy 23.565 -1.465)
        (xy 23.542 -1.461)
        (xy 23.518 -1.461)
        (xy 23.495 -1.459)
        (xy 23.47 -1.461)
        (xy 23.446 -1.461)
        (xy 23.423 -1.465)
        (xy 23.4 -1.469)
        (xy 23.379 -1.475)
        (xy 23.356 -1.481)
        (xy 23.335 -1.489)
        (xy 23.312 -1.497)
        (xy 23.292 -1.507)
        (xy 23.271 -1.518)
        (xy 23.251 -1.531)
        (xy 23.233 -1.544)
        (xy 23.213 -1.558)
        (xy 23.196 -1.574)
        (xy 23.179 -1.59)
        (xy 23.164 -1.606)
        (xy 23.149 -1.624)
        (xy 23.135 -1.642)
        (xy 23.121 -1.661)
        (xy 23.109 -1.681)
        (xy 23.097 -1.701)
        (xy 23.088 -1.723)
        (xy 23.079 -1.745)
        (xy 23.071 -1.766)
        (xy 23.065 -1.788)
        (xy 23.059 -1.81)
        (xy 23.054 -1.834)
        (xy 23.051 -1.856)
        (xy 23.05 -1.88)
        (xy 23.05 -1.902)
        (xy 23.495 -1.902)
        (xy 23.495 -1.906)
        (xy 23.495 -1.907)
      )

      (stroke (width 0.001) (type solid)) (fill solid) (layer "B.Paste"))
    (fp_poly
      (pts
        (xy 23.495 -0.637)
        (xy 23.05 -0.636)
        (xy 23.05 -0.659)
        (xy 23.051 -0.683)
        (xy 23.054 -0.705)
        (xy 23.059 -0.728)
        (xy 23.065 -0.75)
        (xy 23.071 -0.773)
        (xy 23.079 -0.795)
        (xy 23.088 -0.816)
        (xy 23.097 -0.837)
        (xy 23.109 -0.857)
        (xy 23.121 -0.877)
        (xy 23.135 -0.897)
        (xy 23.149 -0.916)
        (xy 23.164 -0.933)
        (xy 23.179 -0.949)
        (xy 23.196 -0.965)
        (xy 23.213 -0.98)
        (xy 23.233 -0.994)
        (xy 23.251 -1.007)
        (xy 23.271 -1.02)
        (xy 23.292 -1.032)
        (xy 23.312 -1.042)
        (xy 23.335 -1.05)
        (xy 23.356 -1.058)
        (xy 23.379 -1.064)
        (xy 23.4 -1.07)
        (xy 23.423 -1.074)
        (xy 23.446 -1.078)
        (xy 23.47 -1.078)
        (xy 23.495 -1.08)
        (xy 23.518 -1.078)
        (xy 23.542 -1.078)
        (xy 23.565 -1.074)
        (xy 23.588 -1.07)
        (xy 23.609 -1.064)
        (xy 23.632 -1.058)
        (xy 23.653 -1.05)
        (xy 23.675 -1.042)
        (xy 23.696 -1.03)
        (xy 23.717 -1.019)
        (xy 23.736 -1.007)
        (xy 23.757 -0.994)
        (xy 23.774 -0.98)
        (xy 23.792 -0.965)
        (xy 23.809 -0.949)
        (xy 23.826 -0.933)
        (xy 23.841 -0.915)
        (xy 23.854 -0.897)
        (xy 23.867 -0.876)
        (xy 23.879 -0.856)
        (xy 23.89 -0.836)
        (xy 23.902 -0.815)
        (xy 23.909 -0.794)
        (xy 23.917 -0.773)
        (xy 23.925 -0.749)
        (xy 23.929 -0.727)
        (xy 23.934 -0.704)
        (xy 23.937 -0.682)
        (xy 23.938 -0.658)
        (xy 23.94 -0.634)
        (xy 23.938 -0.611)
        (xy 23.937 -0.587)
        (xy 23.934 -0.564)
        (xy 23.929 -0.542)
        (xy 23.925 -0.52)
        (xy 23.917 -0.496)
        (xy 23.909 -0.475)
        (xy 23.902 -0.454)
        (xy 23.89 -0.432)
        (xy 23.879 -0.412)
        (xy 23.867 -0.393)
        (xy 23.854 -0.372)
        (xy 23.841 -0.354)
        (xy 23.826 -0.337)
        (xy 23.809 -0.32)
        (xy 23.792 -0.303)
        (xy 23.774 -0.288)
        (xy 23.757 -0.275)
        (xy 23.736 -0.262)
        (xy 23.717 -0.249)
        (xy 23.696 -0.238)
        (xy 23.675 -0.228)
        (xy 23.653 -0.219)
        (xy 23.632 -0.211)
        (xy 23.609 -0.204)
        (xy 23.588 -0.2)
        (xy 23.565 -0.195)
        (xy 23.542 -0.192)
        (xy 23.518 -0.19)
        (xy 23.495 -0.189)
        (xy 23.47 -0.19)
        (xy 23.446 -0.192)
        (xy 23.423 -0.195)
        (xy 23.4 -0.2)
        (xy 23.379 -0.204)
        (xy 23.356 -0.211)
        (xy 23.335 -0.218)
        (xy 23.312 -0.228)
        (xy 23.292 -0.237)
        (xy 23.271 -0.248)
        (xy 23.251 -0.262)
        (xy 23.233 -0.275)
        (xy 23.213 -0.288)
        (xy 23.196 -0.303)
        (xy 23.179 -0.32)
        (xy 23.164 -0.337)
        (xy 23.149 -0.353)
        (xy 23.135 -0.372)
        (xy 23.121 -0.392)
        (xy 23.109 -0.411)
        (xy 23.097 -0.431)
        (xy 23.088 -0.453)
        (xy 23.079 -0.474)
        (xy 23.071 -0.496)
        (xy 23.065 -0.519)
        (xy 23.059 -0.541)
        (xy 23.054 -0.563)
        (xy 23.051 -0.586)
        (xy 23.05 -0.61)
        (xy 23.05 -0.631)
        (xy 23.495 -0.631)
        (xy 23.495 -0.636)
        (xy 23.495 -0.637)
      )

      (stroke (width 0.001) (type solid)) (fill solid) (layer "B.Paste"))
    (fp_poly
      (pts
        (xy 23.495 0.633)
        (xy 23.05 0.632)
        (xy 23.05 0.611)
        (xy 23.051 0.587)
        (xy 23.054 0.564)
        (xy 23.059 0.542)
        (xy 23.065 0.52)
        (xy 23.071 0.497)
        (xy 23.079 0.475)
        (xy 23.088 0.454)
        (xy 23.097 0.432)
        (xy 23.109 0.412)
        (xy 23.121 0.393)
        (xy 23.135 0.373)
        (xy 23.149 0.354)
        (xy 23.164 0.338)
        (xy 23.179 0.32)
        (xy 23.196 0.304)
        (xy 23.213 0.289)
        (xy 23.233 0.276)
        (xy 23.251 0.263)
        (xy 23.271 0.249)
        (xy 23.292 0.238)
        (xy 23.312 0.229)
        (xy 23.335 0.219)
        (xy 23.356 0.212)
        (xy 23.379 0.205)
        (xy 23.4 0.201)
        (xy 23.423 0.196)
        (xy 23.446 0.192)
        (xy 23.47 0.191)
        (xy 23.495 0.19)
        (xy 23.518 0.191)
        (xy 23.542 0.192)
        (xy 23.565 0.196)
        (xy 23.588 0.201)
        (xy 23.609 0.205)
        (xy 23.632 0.212)
        (xy 23.653 0.22)
        (xy 23.675 0.229)
        (xy 23.696 0.239)
        (xy 23.717 0.25)
        (xy 23.736 0.263)
        (xy 23.757 0.276)
        (xy 23.774 0.289)
        (xy 23.792 0.304)
        (xy 23.809 0.32)
        (xy 23.826 0.338)
        (xy 23.841 0.355)
        (xy 23.854 0.373)
        (xy 23.867 0.394)
        (xy 23.879 0.413)
        (xy 23.89 0.433)
        (xy 23.902 0.455)
        (xy 23.909 0.476)
        (xy 23.917 0.497)
        (xy 23.925 0.521)
        (xy 23.929 0.543)
        (xy 23.934 0.565)
        (xy 23.937 0.588)
        (xy 23.938 0.612)
        (xy 23.94 0.635)
        (xy 23.938 0.659)
        (xy 23.937 0.683)
        (xy 23.934 0.705)
        (xy 23.929 0.728)
        (xy 23.925 0.75)
        (xy 23.917 0.774)
        (xy 23.909 0.795)
        (xy 23.902 0.816)
        (xy 23.89 0.837)
        (xy 23.879 0.857)
        (xy 23.867 0.877)
        (xy 23.854 0.898)
        (xy 23.841 0.916)
        (xy 23.826 0.934)
        (xy 23.809 0.95)
        (xy 23.792 0.966)
        (xy 23.774 0.981)
        (xy 23.757 0.995)
        (xy 23.736 1.008)
        (xy 23.717 1.02)
        (xy 23.696 1.031)
        (xy 23.675 1.043)
        (xy 23.653 1.051)
        (xy 23.632 1.059)
        (xy 23.609 1.065)
        (xy 23.588 1.071)
        (xy 23.565 1.075)
        (xy 23.542 1.079)
        (xy 23.518 1.079)
        (xy 23.495 1.081)
        (xy 23.47 1.079)
        (xy 23.446 1.079)
        (xy 23.423 1.075)
        (xy 23.4 1.071)
        (xy 23.379 1.065)
        (xy 23.356 1.059)
        (xy 23.335 1.051)
        (xy 23.312 1.043)
        (xy 23.292 1.033)
        (xy 23.271 1.021)
        (xy 23.251 1.008)
        (xy 23.233 0.995)
        (xy 23.213 0.981)
        (xy 23.196 0.966)
        (xy 23.179 0.95)
        (xy 23.164 0.934)
        (xy 23.149 0.917)
        (xy 23.135 0.898)
        (xy 23.121 0.878)
        (xy 23.109 0.858)
        (xy 23.097 0.838)
        (xy 23.088 0.817)
        (xy 23.079 0.796)
        (xy 23.071 0.774)
        (xy 23.065 0.751)
        (xy 23.059 0.729)
        (xy 23.054 0.706)
        (xy 23.051 0.684)
        (xy 23.05 0.66)
        (xy 23.05 0.637)
        (xy 23.495 0.637)
        (xy 23.495 0.632)
        (xy 23.495 0.633)
      )

      (stroke (width 0.001) (type solid)) (fill solid) (layer "B.Paste"))
    (fp_poly
      (pts
        (xy 24.765 -4.447)
        (xy 24.319 -4.446)
        (xy 24.321 -4.469)
        (xy 24.321 -4.493)
        (xy 24.324 -4.515)
        (xy 24.329 -4.538)
        (xy 24.335 -4.56)
        (xy 24.341 -4.583)
        (xy 24.348 -4.605)
        (xy 24.358 -4.626)
        (xy 24.367 -4.647)
        (xy 24.379 -4.668)
        (xy 24.391 -4.687)
        (xy 24.405 -4.706)
        (xy 24.418 -4.725)
        (xy 24.434 -4.743)
        (xy 24.449 -4.759)
        (xy 24.466 -4.775)
        (xy 24.484 -4.791)
        (xy 24.502 -4.804)
        (xy 24.521 -4.817)
        (xy 24.542 -4.831)
        (xy 24.562 -4.841)
        (xy 24.582 -4.852)
        (xy 24.604 -4.86)
        (xy 24.626 -4.868)
        (xy 24.649 -4.874)
        (xy 24.67 -4.879)
        (xy 24.693 -4.884)
        (xy 24.716 -4.887)
        (xy 24.74 -4.889)
        (xy 24.765 -4.889)
        (xy 24.787 -4.889)
        (xy 24.812 -4.887)
        (xy 24.835 -4.884)
        (xy 24.858 -4.879)
        (xy 24.879 -4.874)
        (xy 24.902 -4.868)
        (xy 24.923 -4.86)
        (xy 24.946 -4.852)
        (xy 24.966 -4.841)
        (xy 24.987 -4.829)
        (xy 25.007 -4.817)
        (xy 25.027 -4.804)
        (xy 25.045 -4.791)
        (xy 25.062 -4.775)
        (xy 25.079 -4.759)
        (xy 25.095 -4.743)
        (xy 25.111 -4.724)
        (xy 25.124 -4.706)
        (xy 25.138 -4.687)
        (xy 25.149 -4.668)
        (xy 25.161 -4.647)
        (xy 25.172 -4.626)
        (xy 25.179 -4.603)
        (xy 25.187 -4.583)
        (xy 25.194 -4.559)
        (xy 25.199 -4.538)
        (xy 25.204 -4.514)
        (xy 25.207 -4.491)
        (xy 25.208 -4.467)
        (xy 25.21 -4.445)
        (xy 25.208 -4.421)
        (xy 25.207 -4.397)
        (xy 25.204 -4.374)
        (xy 25.199 -4.352)
        (xy 25.194 -4.329)
        (xy 25.187 -4.307)
        (xy 25.179 -4.285)
        (xy 25.172 -4.264)
        (xy 25.161 -4.243)
        (xy 25.149 -4.222)
        (xy 25.138 -4.203)
        (xy 25.124 -4.182)
        (xy 25.111 -4.164)
        (xy 25.095 -4.147)
        (xy 25.079 -4.129)
        (xy 25.062 -4.113)
        (xy 25.045 -4.099)
        (xy 25.027 -4.084)
        (xy 25.007 -4.071)
        (xy 24.987 -4.059)
        (xy 24.966 -4.049)
        (xy 24.946 -4.038)
        (xy 24.923 -4.03)
        (xy 24.902 -4.022)
        (xy 24.879 -4.014)
        (xy 24.858 -4.009)
        (xy 24.835 -4.004)
        (xy 24.812 -4.001)
        (xy 24.787 -4.001)
        (xy 24.765 -3.999)
        (xy 24.74 -4.001)
        (xy 24.716 -4.001)
        (xy 24.693 -4.004)
        (xy 24.67 -4.009)
        (xy 24.649 -4.014)
        (xy 24.626 -4.022)
        (xy 24.604 -4.028)
        (xy 24.582 -4.038)
        (xy 24.562 -4.047)
        (xy 24.542 -4.059)
        (xy 24.521 -4.071)
        (xy 24.502 -4.084)
        (xy 24.484 -4.099)
        (xy 24.466 -4.113)
        (xy 24.449 -4.129)
        (xy 24.434 -4.147)
        (xy 24.418 -4.163)
        (xy 24.405 -4.182)
        (xy 24.391 -4.201)
        (xy 24.379 -4.222)
        (xy 24.367 -4.241)
        (xy 24.358 -4.262)
        (xy 24.348 -4.285)
        (xy 24.341 -4.307)
        (xy 24.335 -4.328)
        (xy 24.329 -4.35)
        (xy 24.324 -4.373)
        (xy 24.321 -4.397)
        (xy 24.321 -4.421)
        (xy 24.319 -4.442)
        (xy 24.765 -4.442)
        (xy 24.765 -4.446)
        (xy 24.765 -4.447)
      )

      (stroke (width 0.001) (type solid)) (fill solid) (layer "B.Paste"))
    (fp_poly
      (pts
        (xy 24.765 -1.907)
        (xy 24.319 -1.906)
        (xy 24.321 -1.929)
        (xy 24.321 -1.953)
        (xy 24.324 -1.975)
        (xy 24.329 -1.999)
        (xy 24.335 -2.02)
        (xy 24.341 -2.043)
        (xy 24.348 -2.064)
        (xy 24.358 -2.087)
        (xy 24.367 -2.108)
        (xy 24.379 -2.128)
        (xy 24.391 -2.148)
        (xy 24.405 -2.166)
        (xy 24.418 -2.185)
        (xy 24.434 -2.202)
        (xy 24.449 -2.22)
        (xy 24.466 -2.236)
        (xy 24.484 -2.25)
        (xy 24.502 -2.265)
        (xy 24.521 -2.277)
        (xy 24.542 -2.29)
        (xy 24.562 -2.301)
        (xy 24.582 -2.311)
        (xy 24.604 -2.321)
        (xy 24.626 -2.327)
        (xy 24.649 -2.334)
        (xy 24.67 -2.339)
        (xy 24.693 -2.345)
        (xy 24.716 -2.347)
        (xy 24.74 -2.349)
        (xy 24.765 -2.35)
        (xy 24.787 -2.349)
        (xy 24.812 -2.347)
        (xy 24.835 -2.345)
        (xy 24.858 -2.339)
        (xy 24.879 -2.334)
        (xy 24.902 -2.327)
        (xy 24.923 -2.319)
        (xy 24.946 -2.311)
        (xy 24.966 -2.301)
        (xy 24.987 -2.289)
        (xy 25.007 -2.277)
        (xy 25.027 -2.265)
        (xy 25.045 -2.25)
        (xy 25.062 -2.236)
        (xy 25.079 -2.22)
        (xy 25.095 -2.202)
        (xy 25.111 -2.185)
        (xy 25.124 -2.166)
        (xy 25.138 -2.146)
        (xy 25.149 -2.126)
        (xy 25.161 -2.107)
        (xy 25.172 -2.085)
        (xy 25.179 -2.064)
        (xy 25.187 -2.043)
        (xy 25.194 -2.019)
        (xy 25.199 -1.997)
        (xy 25.204 -1.975)
        (xy 25.207 -1.951)
        (xy 25.208 -1.927)
        (xy 25.21 -1.904)
        (xy 25.208 -1.881)
        (xy 25.207 -1.858)
        (xy 25.204 -1.834)
        (xy 25.199 -1.812)
        (xy 25.194 -1.789)
        (xy 25.187 -1.766)
        (xy 25.179 -1.745)
        (xy 25.172 -1.723)
        (xy 25.161 -1.703)
        (xy 25.149 -1.683)
        (xy 25.138 -1.662)
        (xy 25.124 -1.642)
        (xy 25.111 -1.624)
        (xy 25.095 -1.606)
        (xy 25.079 -1.59)
        (xy 25.062 -1.574)
        (xy 25.045 -1.558)
        (xy 25.027 -1.544)
        (xy 25.007 -1.531)
        (xy 24.987 -1.519)
        (xy 24.966 -1.508)
        (xy 24.946 -1.497)
        (xy 24.923 -1.489)
        (xy 24.902 -1.481)
        (xy 24.879 -1.475)
        (xy 24.858 -1.469)
        (xy 24.835 -1.465)
        (xy 24.812 -1.461)
        (xy 24.787 -1.461)
        (xy 24.765 -1.459)
        (xy 24.74 -1.461)
        (xy 24.716 -1.461)
        (xy 24.693 -1.465)
        (xy 24.67 -1.469)
        (xy 24.649 -1.475)
        (xy 24.626 -1.481)
        (xy 24.604 -1.489)
        (xy 24.582 -1.497)
        (xy 24.562 -1.507)
        (xy 24.542 -1.518)
        (xy 24.521 -1.531)
        (xy 24.502 -1.544)
        (xy 24.484 -1.558)
        (xy 24.466 -1.574)
        (xy 24.449 -1.59)
        (xy 24.434 -1.606)
        (xy 24.418 -1.624)
        (xy 24.405 -1.642)
        (xy 24.391 -1.661)
        (xy 24.379 -1.681)
        (xy 24.367 -1.701)
        (xy 24.358 -1.723)
        (xy 24.348 -1.745)
        (xy 24.341 -1.766)
        (xy 24.335 -1.788)
        (xy 24.329 -1.81)
        (xy 24.324 -1.834)
        (xy 24.321 -1.856)
        (xy 24.321 -1.88)
        (xy 24.319 -1.902)
        (xy 24.765 -1.902)
        (xy 24.765 -1.906)
        (xy 24.765 -1.907)
      )

      (stroke (width 0.001) (type solid)) (fill solid) (layer "B.Paste"))
    (fp_poly
      (pts
        (xy 24.765 -0.637)
        (xy 24.319 -0.636)
        (xy 24.321 -0.659)
        (xy 24.321 -0.683)
        (xy 24.324 -0.705)
        (xy 24.329 -0.728)
        (xy 24.335 -0.75)
        (xy 24.341 -0.773)
        (xy 24.348 -0.795)
        (xy 24.358 -0.816)
        (xy 24.367 -0.837)
        (xy 24.379 -0.857)
        (xy 24.391 -0.877)
        (xy 24.405 -0.897)
        (xy 24.418 -0.916)
        (xy 24.434 -0.933)
        (xy 24.449 -0.949)
        (xy 24.466 -0.965)
        (xy 24.484 -0.98)
        (xy 24.502 -0.994)
        (xy 24.521 -1.007)
        (xy 24.542 -1.02)
        (xy 24.562 -1.032)
        (xy 24.582 -1.042)
        (xy 24.604 -1.05)
        (xy 24.626 -1.058)
        (xy 24.649 -1.064)
        (xy 24.67 -1.07)
        (xy 24.693 -1.074)
        (xy 24.716 -1.078)
        (xy 24.74 -1.078)
        (xy 24.765 -1.08)
        (xy 24.787 -1.078)
        (xy 24.812 -1.078)
        (xy 24.835 -1.074)
        (xy 24.858 -1.07)
        (xy 24.879 -1.064)
        (xy 24.902 -1.058)
        (xy 24.923 -1.05)
        (xy 24.946 -1.042)
        (xy 24.966 -1.03)
        (xy 24.987 -1.019)
        (xy 25.007 -1.007)
        (xy 25.027 -0.994)
        (xy 25.045 -0.98)
        (xy 25.062 -0.965)
        (xy 25.079 -0.949)
        (xy 25.095 -0.933)
        (xy 25.111 -0.915)
        (xy 25.124 -0.897)
        (xy 25.138 -0.876)
        (xy 25.149 -0.856)
        (xy 25.161 -0.836)
        (xy 25.172 -0.815)
        (xy 25.179 -0.794)
        (xy 25.187 -0.773)
        (xy 25.194 -0.749)
        (xy 25.199 -0.727)
        (xy 25.204 -0.704)
        (xy 25.207 -0.682)
        (xy 25.208 -0.658)
        (xy 25.21 -0.634)
        (xy 25.208 -0.611)
        (xy 25.207 -0.587)
        (xy 25.204 -0.564)
        (xy 25.199 -0.542)
        (xy 25.194 -0.52)
        (xy 25.187 -0.496)
        (xy 25.179 -0.475)
        (xy 25.172 -0.454)
        (xy 25.161 -0.432)
        (xy 25.149 -0.412)
        (xy 25.138 -0.393)
        (xy 25.124 -0.372)
        (xy 25.111 -0.354)
        (xy 25.095 -0.337)
        (xy 25.079 -0.32)
        (xy 25.062 -0.303)
        (xy 25.045 -0.288)
        (xy 25.027 -0.275)
        (xy 25.007 -0.262)
        (xy 24.987 -0.249)
        (xy 24.966 -0.238)
        (xy 24.946 -0.228)
        (xy 24.923 -0.219)
        (xy 24.902 -0.211)
        (xy 24.879 -0.204)
        (xy 24.858 -0.2)
        (xy 24.835 -0.195)
        (xy 24.812 -0.192)
        (xy 24.787 -0.19)
        (xy 24.765 -0.189)
        (xy 24.74 -0.19)
        (xy 24.716 -0.192)
        (xy 24.693 -0.195)
        (xy 24.67 -0.2)
        (xy 24.649 -0.204)
        (xy 24.626 -0.211)
        (xy 24.604 -0.218)
        (xy 24.582 -0.228)
        (xy 24.562 -0.237)
        (xy 24.542 -0.248)
        (xy 24.521 -0.262)
        (xy 24.502 -0.275)
        (xy 24.484 -0.288)
        (xy 24.466 -0.303)
        (xy 24.449 -0.32)
        (xy 24.434 -0.337)
        (xy 24.418 -0.353)
        (xy 24.405 -0.372)
        (xy 24.391 -0.392)
        (xy 24.379 -0.411)
        (xy 24.367 -0.431)
        (xy 24.358 -0.453)
        (xy 24.348 -0.474)
        (xy 24.341 -0.496)
        (xy 24.335 -0.519)
        (xy 24.329 -0.541)
        (xy 24.324 -0.563)
        (xy 24.321 -0.586)
        (xy 24.321 -0.61)
        (xy 24.319 -0.631)
        (xy 24.765 -0.631)
        (xy 24.765 -0.636)
        (xy 24.765 -0.637)
      )

      (stroke (width 0.001) (type solid)) (fill solid) (layer "B.Paste"))
    (fp_poly
      (pts
        (xy 24.765 0.633)
        (xy 24.319 0.632)
        (xy 24.321 0.611)
        (xy 24.321 0.587)
        (xy 24.324 0.564)
        (xy 24.329 0.542)
        (xy 24.335 0.52)
        (xy 24.341 0.497)
        (xy 24.348 0.475)
        (xy 24.358 0.454)
        (xy 24.367 0.432)
        (xy 24.379 0.412)
        (xy 24.391 0.393)
        (xy 24.405 0.373)
        (xy 24.418 0.354)
        (xy 24.434 0.338)
        (xy 24.449 0.32)
        (xy 24.466 0.304)
        (xy 24.484 0.289)
        (xy 24.502 0.276)
        (xy 24.521 0.263)
        (xy 24.542 0.249)
        (xy 24.562 0.238)
        (xy 24.582 0.229)
        (xy 24.604 0.219)
        (xy 24.626 0.212)
        (xy 24.649 0.205)
        (xy 24.67 0.201)
        (xy 24.693 0.196)
        (xy 24.716 0.192)
        (xy 24.74 0.191)
        (xy 24.765 0.19)
        (xy 24.787 0.191)
        (xy 24.812 0.192)
        (xy 24.835 0.196)
        (xy 24.858 0.201)
        (xy 24.879 0.205)
        (xy 24.902 0.212)
        (xy 24.923 0.22)
        (xy 24.946 0.229)
        (xy 24.966 0.239)
        (xy 24.987 0.25)
        (xy 25.007 0.263)
        (xy 25.027 0.276)
        (xy 25.045 0.289)
        (xy 25.062 0.304)
        (xy 25.079 0.32)
        (xy 25.095 0.338)
        (xy 25.111 0.355)
        (xy 25.124 0.373)
        (xy 25.138 0.394)
        (xy 25.149 0.413)
        (xy 25.161 0.433)
        (xy 25.172 0.455)
        (xy 25.179 0.476)
        (xy 25.187 0.497)
        (xy 25.194 0.521)
        (xy 25.199 0.543)
        (xy 25.204 0.565)
        (xy 25.207 0.588)
        (xy 25.208 0.612)
        (xy 25.21 0.635)
        (xy 25.208 0.659)
        (xy 25.207 0.683)
        (xy 25.204 0.705)
        (xy 25.199 0.728)
        (xy 25.194 0.75)
        (xy 25.187 0.774)
        (xy 25.179 0.795)
        (xy 25.172 0.816)
        (xy 25.161 0.837)
        (xy 25.149 0.857)
        (xy 25.138 0.877)
        (xy 25.124 0.898)
        (xy 25.111 0.916)
        (xy 25.095 0.934)
        (xy 25.079 0.95)
        (xy 25.062 0.966)
        (xy 25.045 0.981)
        (xy 25.027 0.995)
        (xy 25.007 1.008)
        (xy 24.987 1.02)
        (xy 24.966 1.031)
        (xy 24.946 1.043)
        (xy 24.923 1.051)
        (xy 24.902 1.059)
        (xy 24.879 1.065)
        (xy 24.858 1.071)
        (xy 24.835 1.075)
        (xy 24.812 1.079)
        (xy 24.787 1.079)
        (xy 24.765 1.081)
        (xy 24.74 1.079)
        (xy 24.716 1.079)
        (xy 24.693 1.075)
        (xy 24.67 1.071)
        (xy 24.649 1.065)
        (xy 24.626 1.059)
        (xy 24.604 1.051)
        (xy 24.582 1.043)
        (xy 24.562 1.033)
        (xy 24.542 1.021)
        (xy 24.521 1.008)
        (xy 24.502 0.995)
        (xy 24.484 0.981)
        (xy 24.466 0.966)
        (xy 24.449 0.95)
        (xy 24.434 0.934)
        (xy 24.418 0.917)
        (xy 24.405 0.898)
        (xy 24.391 0.878)
        (xy 24.379 0.858)
        (xy 24.367 0.838)
        (xy 24.358 0.817)
        (xy 24.348 0.796)
        (xy 24.341 0.774)
        (xy 24.335 0.751)
        (xy 24.329 0.729)
        (xy 24.324 0.706)
        (xy 24.321 0.684)
        (xy 24.321 0.66)
        (xy 24.319 0.637)
        (xy 24.765 0.637)
        (xy 24.765 0.632)
        (xy 24.765 0.633)
      )

      (stroke (width 0.001) (type solid)) (fill solid) (layer "B.Paste"))
    (fp_line (start -28.665 -2.85) (end -27.9 -2.85)
      (stroke (width 0.15) (type solid)) (layer "B.SilkS"))
    (fp_line (start -28.665 0.65) (end -28.665 -0.65)
      (stroke (width 0.15) (type solid)) (layer "B.SilkS"))
    (fp_line (start -28.665 2.851) (end -27.9 2.85)
      (stroke (width 0.15) (type solid)) (layer "B.SilkS"))
    (fp_line (start -27.9 -6.615) (end 28.7 -6.615)
      (stroke (width 0.15) (type solid)) (layer "B.SilkS"))
    (fp_line (start -27.9 -2.85) (end -27.9 -6.615)
      (stroke (width 0.15) (type solid)) (layer "B.SilkS"))
    (fp_line (start -27.9 6.616) (end -27.9 2.85)
      (stroke (width 0.15) (type solid)) (layer "B.SilkS"))
    (fp_line (start 28.7 -6.615) (end 28.7 -3.25)
      (stroke (width 0.15) (type solid)) (layer "B.SilkS"))
    (fp_line (start 28.7 -0.55) (end 28.7 6.616)
      (stroke (width 0.15) (type solid)) (layer "B.SilkS"))
    (fp_line (start 28.7 6.616) (end -27.9 6.616)
      (stroke (width 0.15) (type solid)) (layer "B.SilkS"))
    (fp_circle (center -24.77 7.17071) (end -24.72 7.12071)
      (stroke (width 0.15) (type solid)) (fill solid) (layer "B.SilkS"))
    (fp_line (start -29 -6.9) (end 29 -6.9)
      (stroke (width 0.05) (type solid)) (layer "B.CrtYd"))
    (fp_line (start -29 -5.5) (end -31.5 -5.5)
      (stroke (width 0.05) (type solid)) (layer "B.CrtYd"))
    (fp_line (start -29 -5.5) (end -29 -6.9)
      (stroke (width 0.05) (type solid)) (layer "B.CrtYd"))
    (fp_line (start -29 1.5) (end -31.5 1.5)
      (stroke (width 0.05) (type solid)) (layer "B.CrtYd"))
    (fp_line (start -29 6.9) (end -29 1.5)
      (stroke (width 0.05) (type solid)) (layer "B.CrtYd"))
    (fp_line (start 29 -5.5) (end 29 -6.9)
      (stroke (width 0.05) (type solid)) (layer "B.CrtYd"))
    (fp_line (start 29 -5.5) (end 31.5 -5.5)
      (stroke (width 0.05) (type solid)) (layer "B.CrtYd"))
    (fp_line (start 29 1.5) (end 29 6.9)
      (stroke (width 0.05) (type solid)) (layer "B.CrtYd"))
    (fp_line (start 29 1.5) (end 31.5 1.5)
      (stroke (width 0.05) (type solid)) (layer "B.CrtYd"))
    (fp_line (start 29 6.9) (end -29 6.9)
      (stroke (width 0.05) (type solid)) (layer "B.CrtYd"))
    (fp_arc (start -31.5 1.5) (mid -35 -2) (end -31.5 -5.5)
      (stroke (width 0.05) (type solid)) (layer "B.CrtYd"))
    (fp_arc (start 31.5 -5.5) (mid 35 -2) (end 31.5 1.5)
      (stroke (width 0.05) (type solid)) (layer "B.CrtYd"))
    (fp_line (start -28.665 -2.85) (end -27.865 -2.85)
      (stroke (width 0.15) (type solid)) (layer "B.Fab"))
    (fp_line (start -28.665 2.851) (end -28.665 -2.85)
      (stroke (width 0.15) (type solid)) (layer "B.Fab"))
    (fp_line (start -27.865 -6.615) (end 28.764 -6.615)
      (stroke (width 0.15) (type solid)) (layer "B.Fab"))
    (fp_line (start -27.865 -2.85) (end -27.865 -6.615)
      (stroke (width 0.15) (type solid)) (layer "B.Fab"))
    (fp_line (start -27.865 2.851) (end -28.665 2.851)
      (stroke (width 0.15) (type solid)) (layer "B.Fab"))
    (fp_line (start -27.865 6.616) (end -27.865 2.851)
      (stroke (width 0.15) (type solid)) (layer "B.Fab"))
    (fp_line (start 28.764 -6.615) (end 28.764 6.616)
      (stroke (width 0.15) (type solid)) (layer "B.Fab"))
    (fp_line (start 28.764 6.616) (end -27.865 6.616)
      (stroke (width 0.15) (type solid)) (layer "B.Fab"))
    (fp_circle (center -28.4 5.8) (end -28.301 5.8)
      (stroke (width 0.15) (type solid)) (fill none) (layer "B.Fab"))
    (pad "" np_thru_hole circle (at -31.499 -1.999 270) (size 6 6) (drill 3.2) (layers "*.Cu" "*.Mask"))
    (pad "" np_thru_hole circle (at -27.189 3.05 270) (size 1.27 1.27) (drill 1.27) (layers "F&B.Cu" "*.Mask"))
    (pad "" np_thru_hole circle (at 27.19 0 90) (size 1.27 1.27) (drill 1.27) (layers "*.Cu" "*.Mask"))
    (pad "" np_thru_hole circle (at 31.501 -1.999 270) (size 6 6) (drill 3.2) (layers "*.Cu" "*.Mask"))
    (pad "A1" smd circle (at -24.766 5.715 270) (size 0.64 0.64) (layers "B.Cu" "B.Mask")
      (net 9 "GND") (pinfunction "GND") (pintype "passive"))
    (pad "A2" smd circle (at -23.496 5.715 270) (size 0.64 0.64) (layers "B.Cu" "B.Mask")
      (net 632 "GTX_RX1_P") (pinfunction "DP1_{M2C}+") (pintype "passive"))
    (pad "A3" smd circle (at -22.226 5.715 270) (size 0.64 0.64) (layers "B.Cu" "B.Mask")
      (net 633 "GTX_RX1_N") (pinfunction "DP1_{M2C}-") (pintype "passive"))
    (pad "A4" smd circle (at -20.955 5.715 270) (size 0.64 0.64) (layers "B.Cu" "B.Mask")
      (net 9 "GND") (pinfunction "GND") (pintype "passive"))
    (pad "A5" smd circle (at -19.685 5.715 270) (size 0.64 0.64) (layers "B.Cu" "B.Mask")
      (net 9 "GND") (pinfunction "GND") (pintype "passive"))
    (pad "A6" smd circle (at -18.415 5.715 270) (size 0.64 0.64) (layers "B.Cu" "B.Mask")
      (net 634 "GTX_RX2_P") (pinfunction "DP2_{M2C}+") (pintype "passive"))
    (pad "A7" smd circle (at -17.145 5.715 270) (size 0.64 0.64) (layers "B.Cu" "B.Mask")
      (net 635 "GTX_RX2_N") (pinfunction "DP2_{M2C}-") (pintype "passive"))
    (pad "A8" smd circle (at -15.875 5.715 270) (size 0.64 0.64) (layers "B.Cu" "B.Mask")
      (net 9 "GND") (pinfunction "GND") (pintype "passive"))
    (pad "A9" smd circle (at -14.606 5.715 270) (size 0.64 0.64) (layers "B.Cu" "B.Mask")
      (net 9 "GND") (pinfunction "GND") (pintype "passive"))
    (pad "A10" smd circle (at -13.336 5.715 270) (size 0.64 0.64) (layers "B.Cu" "B.Mask")
      (net 636 "GTX_RX3_P") (pinfunction "DP3_{M2C}+") (pintype "passive"))
    (pad "A11" smd circle (at -12.065 5.715 270) (size 0.64 0.64) (layers "B.Cu" "B.Mask")
      (net 637 "GTX_RX3_N") (pinfunction "DP3_{M2C}-") (pintype "passive"))
    (pad "A12" smd circle (at -10.795 5.715 270) (size 0.64 0.64) (layers "B.Cu" "B.Mask")
      (net 9 "GND") (pinfunction "GND") (pintype "passive"))
    (pad "A13" smd circle (at -9.526 5.715 270) (size 0.64 0.64) (layers "B.Cu" "B.Mask")
      (net 9 "GND") (pinfunction "GND") (pintype "passive"))
    (pad "A14" smd circle (at -8.256 5.715 270) (size 0.64 0.64) (layers "B.Cu" "B.Mask")
      (net 638 "GTX_RX4_P") (pinfunction "DP4_{M2C}+") (pintype "passive"))
    (pad "A15" smd circle (at -6.986 5.715 270) (size 0.64 0.64) (layers "B.Cu" "B.Mask")
      (net 639 "GTX_RX4_N") (pinfunction "DP4_{M2C}-") (pintype "passive"))
    (pad "A16" smd circle (at -5.715 5.715 270) (size 0.64 0.64) (layers "B.Cu" "B.Mask")
      (net 9 "GND") (pinfunction "GND") (pintype "passive"))
    (pad "A17" smd circle (at -4.446 5.715 270) (size 0.64 0.64) (layers "B.Cu" "B.Mask")
      (net 9 "GND") (pinfunction "GND") (pintype "passive"))
    (pad "A18" smd circle (at -3.175 5.715 270) (size 0.64 0.64) (layers "B.Cu" "B.Mask")
      (net 640 "GTX_RX5_P") (pinfunction "DP5_{M2C}+") (pintype "passive"))
    (pad "A19" smd circle (at -1.905 5.715 270) (size 0.64 0.64) (layers "B.Cu" "B.Mask")
      (net 641 "GTX_RX5_N") (pinfunction "DP5_{M2C}-") (pintype "passive"))
    (pad "A20" smd circle (at -0.635 5.715 270) (size 0.64 0.64) (layers "B.Cu" "B.Mask")
      (net 9 "GND") (pinfunction "GND") (pintype "passive"))
    (pad "A21" smd circle (at 0.634 5.715 270) (size 0.64 0.64) (layers "B.Cu" "B.Mask")
      (net 9 "GND") (pinfunction "GND") (pintype "passive"))
    (pad "A22" smd circle (at 1.904 5.715 270) (size 0.64 0.64) (layers "B.Cu" "B.Mask")
      (net 419 "/FMC HPC/GTX_TX1_C_P") (pinfunction "DP1_{C2M}+") (pintype "passive"))
    (pad "A23" smd circle (at 3.174 5.715 270) (size 0.64 0.64) (layers "B.Cu" "B.Mask")
      (net 421 "/FMC HPC/GTX_TX1_C_N") (pinfunction "DP1_{C2M}-") (pintype "passive"))
    (pad "A24" smd circle (at 4.445 5.715 270) (size 0.64 0.64) (layers "B.Cu" "B.Mask")
      (net 9 "GND") (pinfunction "GND") (pintype "passive"))
    (pad "A25" smd circle (at 5.714 5.715 270) (size 0.64 0.64) (layers "B.Cu" "B.Mask")
      (net 9 "GND") (pinfunction "GND") (pintype "passive"))
    (pad "A26" smd circle (at 6.985 5.715 270) (size 0.64 0.64) (layers "B.Cu" "B.Mask")
      (net 430 "/FMC HPC/GTX_TX2_C_P") (pinfunction "DP2_{C2M}+") (pintype "passive"))
    (pad "A27" smd circle (at 8.255 5.715 270) (size 0.64 0.64) (layers "B.Cu" "B.Mask")
      (net 438 "/FMC HPC/GTX_TX2_C_N") (pinfunction "DP2_{C2M}-") (pintype "passive"))
    (pad "A28" smd circle (at 9.525 5.715 270) (size 0.64 0.64) (layers "B.Cu" "B.Mask")
      (net 9 "GND") (pinfunction "GND") (pintype "passive"))
    (pad "A29" smd circle (at 10.794 5.715 270) (size 0.64 0.64) (layers "B.Cu" "B.Mask")
      (net 9 "GND") (pinfunction "GND") (pintype "passive"))
    (pad "A30" smd circle (at 12.064 5.715 270) (size 0.64 0.64) (layers "B.Cu" "B.Mask")
      (net 440 "/FMC HPC/GTX_TX3_C_P") (pinfunction "DP3_{C2M}+") (pintype "passive"))
    (pad "A31" smd circle (at 13.335 5.715 270) (size 0.64 0.64) (layers "B.Cu" "B.Mask")
      (net 451 "/FMC HPC/GTX_TX3_C_N") (pinfunction "DP3_{C2M}-") (pintype "passive"))
    (pad "A32" smd circle (at 14.605 5.715 270) (size 0.64 0.64) (layers "B.Cu" "B.Mask")
      (net 9 "GND") (pinfunction "GND") (pintype "passive"))
    (pad "A33" smd circle (at 15.874 5.715 270) (size 0.64 0.64) (layers "B.Cu" "B.Mask")
      (net 9 "GND") (pinfunction "GND") (pintype "passive"))
    (pad "A34" smd circle (at 17.144 5.715 270) (size 0.64 0.64) (layers "B.Cu" "B.Mask")
      (net 464 "/FMC HPC/GTX_TX4_C_P") (pinfunction "DP4_{C2M}+") (pintype "passive"))
    (pad "A35" smd circle (at 18.414 5.715 270) (size 0.64 0.64) (layers "B.Cu" "B.Mask")
      (net 466 "/FMC HPC/GTX_TX4_C_N") (pinfunction "DP4_{C2M}-") (pintype "passive"))
    (pad "A36" smd circle (at 19.684 5.715 270) (size 0.64 0.64) (layers "B.Cu" "B.Mask")
      (net 9 "GND") (pinfunction "GND") (pintype "passive"))
    (pad "A37" smd circle (at 20.954 5.715 270) (size 0.64 0.64) (layers "B.Cu" "B.Mask")
      (net 9 "GND") (pinfunction "GND") (pintype "passive"))
    (pad "A38" smd circle (at 22.225 5.715 270) (size 0.64 0.64) (layers "B.Cu" "B.Mask")
      (net 480 "/FMC HPC/GTX_TX5_C_P") (pinfunction "DP5_{C2M}+") (pintype "passive"))
    (pad "A39" smd circle (at 23.495 5.715 270) (size 0.64 0.64) (layers "B.Cu" "B.Mask")
      (net 482 "/FMC HPC/GTX_TX5_C_N") (pinfunction "DP5_{C2M}-") (pintype "passive"))
    (pad "A40" smd circle (at 24.765 5.715 270) (size 0.64 0.64) (layers "B.Cu" "B.Mask")
      (net 9 "GND") (pinfunction "GND") (pintype "passive"))
    (pad "B1" smd circle (at -24.766 4.446 270) (size 0.64 0.64) (layers "B.Cu" "B.Mask")
      (net 449 "CLK_DIR") (pinfunction "CLK_{DIR}") (pintype "passive"))
    (pad "B2" smd circle (at -23.496 4.446 270) (size 0.64 0.64) (layers "B.Cu" "B.Mask")
      (net 9 "GND") (pinfunction "GND") (pintype "passive"))
    (pad "B3" smd circle (at -22.226 4.446 270) (size 0.64 0.64) (layers "B.Cu" "B.Mask")
      (net 9 "GND") (pinfunction "GND") (pintype "passive"))
    (pad "B4" smd circle (at -20.955 4.446 270) (size 0.64 0.64) (layers "B.Cu" "B.Mask")
      (net 114 "unconnected-(J5E-DP9_{M2C}+-PadB4)") (pinfunction "DP9_{M2C}+") (pintype "passive+no_connect"))
    (pad "B5" smd circle (at -19.685 4.446 270) (size 0.64 0.64) (layers "B.Cu" "B.Mask")
      (net 116 "unconnected-(J5E-DP9_{M2C}--PadB5)") (pinfunction "DP9_{M2C}-") (pintype "passive+no_connect"))
    (pad "B6" smd circle (at -18.415 4.446 270) (size 0.64 0.64) (layers "B.Cu" "B.Mask")
      (net 9 "GND") (pinfunction "GND") (pintype "passive"))
    (pad "B7" smd circle (at -17.145 4.446 270) (size 0.64 0.64) (layers "B.Cu" "B.Mask")
      (net 9 "GND") (pinfunction "GND") (pintype "passive"))
    (pad "B8" smd circle (at -15.875 4.446 270) (size 0.64 0.64) (layers "B.Cu" "B.Mask")
      (net 117 "unconnected-(J5E-DP8_{M2C}+-PadB8)") (pinfunction "DP8_{M2C}+") (pintype "passive+no_connect"))
    (pad "B9" smd circle (at -14.606 4.446 270) (size 0.64 0.64) (layers "B.Cu" "B.Mask")
      (net 121 "unconnected-(J5E-DP8_{M2C}--PadB9)") (pinfunction "DP8_{M2C}-") (pintype "passive+no_connect"))
    (pad "B10" smd circle (at -13.336 4.446 270) (size 0.64 0.64) (layers "B.Cu" "B.Mask")
      (net 9 "GND") (pinfunction "GND") (pintype "passive"))
    (pad "B11" smd circle (at -12.065 4.446 270) (size 0.64 0.64) (layers "B.Cu" "B.Mask")
      (net 9 "GND") (pinfunction "GND") (pintype "passive"))
    (pad "B12" smd circle (at -10.795 4.446 270) (size 0.64 0.64) (layers "B.Cu" "B.Mask")
      (net 645 "GTX_RX7_P") (pinfunction "DP7_{M2C}+") (pintype "passive"))
    (pad "B13" smd circle (at -9.526 4.446 270) (size 0.64 0.64) (layers "B.Cu" "B.Mask")
      (net 646 "GTX_RX7_N") (pinfunction "DP7_{M2C}-") (pintype "passive"))
    (pad "B14" smd circle (at -8.256 4.446 270) (size 0.64 0.64) (layers "B.Cu" "B.Mask")
      (net 9 "GND") (pinfunction "GND") (pintype "passive"))
    (pad "B15" smd circle (at -6.986 4.446 270) (size 0.64 0.64) (layers "B.Cu" "B.Mask")
      (net 9 "GND") (pinfunction "GND") (pintype "passive"))
    (pad "B16" smd circle (at -5.715 4.446 270) (size 0.64 0.64) (layers "B.Cu" "B.Mask")
      (net 647 "GTX_RX6_P") (pinfunction "DP6_{M2C}+") (pintype "passive"))
    (pad "B17" smd circle (at -4.446 4.446 270) (size 0.64 0.64) (layers "B.Cu" "B.Mask")
      (net 648 "GTX_RX6_N") (pinfunction "DP6_{M2C}-") (pintype "passive"))
    (pad "B18" smd circle (at -3.175 4.446 270) (size 0.64 0.64) (layers "B.Cu" "B.Mask")
      (net 9 "GND") (pinfunction "GND") (pintype "passive"))
    (pad "B19" smd circle (at -1.905 4.446 270) (size 0.64 0.64) (layers "B.Cu" "B.Mask")
      (net 9 "GND") (pinfunction "GND") (pintype "passive"))
    (pad "B20" smd circle (at -0.635 4.446 270) (size 0.64 0.64) (layers "B.Cu" "B.Mask")
      (net 897 "/FMC HPC/GTR_REFCLK1_R_P") (pinfunction "GBTCLK1_{M2C}+") (pintype "passive"))
    (pad "B21" smd circle (at 0.634 4.446 270) (size 0.64 0.64) (layers "B.Cu" "B.Mask")
      (net 898 "/FMC HPC/GTR_REFCLK1_R_N") (pinfunction "GBTCLK1_{M2C}-") (pintype "passive"))
    (pad "B22" smd circle (at 1.904 4.446 270) (size 0.64 0.64) (layers "B.Cu" "B.Mask")
      (net 9 "GND") (pinfunction "GND") (pintype "passive"))
    (pad "B23" smd circle (at 3.174 4.446 270) (size 0.64 0.64) (layers "B.Cu" "B.Mask")
      (net 9 "GND") (pinfunction "GND") (pintype "passive"))
    (pad "B24" smd circle (at 4.445 4.446 270) (size 0.64 0.64) (layers "B.Cu" "B.Mask")
      (net 122 "unconnected-(J5E-DP9_{C2M}+-PadB24)") (pinfunction "DP9_{C2M}+") (pintype "passive+no_connect"))
    (pad "B25" smd circle (at 5.714 4.446 270) (size 0.64 0.64) (layers "B.Cu" "B.Mask")
      (net 123 "unconnected-(J5E-DP9_{C2M}--PadB25)") (pinfunction "DP9_{C2M}-") (pintype "passive+no_connect"))
    (pad "B26" smd circle (at 6.985 4.446 270) (size 0.64 0.64) (layers "B.Cu" "B.Mask")
      (net 9 "GND") (pinfunction "GND") (pintype "passive"))
    (pad "B27" smd circle (at 8.255 4.446 270) (size 0.64 0.64) (layers "B.Cu" "B.Mask")
      (net 9 "GND") (pinfunction "GND") (pintype "passive"))
    (pad "B28" smd circle (at 9.525 4.446 270) (size 0.64 0.64) (layers "B.Cu" "B.Mask")
      (net 124 "unconnected-(J5E-DP8_{C2M}+-PadB28)") (pinfunction "DP8_{C2M}+") (pintype "passive+no_connect"))
    (pad "B29" smd circle (at 10.794 4.446 270) (size 0.64 0.64) (layers "B.Cu" "B.Mask")
      (net 125 "unconnected-(J5E-DP8_{C2M}--PadB29)") (pinfunction "DP8_{C2M}-") (pintype "passive+no_connect"))
    (pad "B30" smd circle (at 12.064 4.446 270) (size 0.64 0.64) (layers "B.Cu" "B.Mask")
      (net 9 "GND") (pinfunction "GND") (pintype "passive"))
    (pad "B31" smd circle (at 13.335 4.446 270) (size 0.64 0.64) (layers "B.Cu" "B.Mask")
      (net 9 "GND") (pinfunction "GND") (pintype "passive"))
    (pad "B32" smd circle (at 14.605 4.446 270) (size 0.64 0.64) (layers "B.Cu" "B.Mask")
      (net 513 "/FMC HPC/GTX_TX7_C_P") (pinfunction "DP7_{C2M}+") (pintype "passive"))
    (pad "B33" smd circle (at 15.874 4.446 270) (size 0.64 0.64) (layers "B.Cu" "B.Mask")
      (net 525 "/FMC HPC/GTX_TX7_C_N") (pinfunction "DP7_{C2M}-") (pintype "passive"))
    (pad "B34" smd circle (at 17.144 4.446 270) (size 0.64 0.64) (layers "B.Cu" "B.Mask")
      (net 9 "GND") (pinfunction "GND") (pintype "passive"))
    (pad "B35" smd circle (at 18.414 4.446 270) (size 0.64 0.64) (layers "B.Cu" "B.Mask")
      (net 9 "GND") (pinfunction "GND") (pintype "passive"))
    (pad "B36" smd circle (at 19.684 4.446 270) (size 0.64 0.64) (layers "B.Cu" "B.Mask")
      (net 497 "/FMC HPC/GTX_TX6_C_P") (pinfunction "DP6_{C2M}+") (pintype "passive"))
    (pad "B37" smd circle (at 20.954 4.446 270) (size 0.64 0.64) (layers "B.Cu" "B.Mask")
      (net 499 "/FMC HPC/GTX_TX6_C_N") (pinfunction "DP6_{C2M}-") (pintype "passive"))
    (pad "B38" smd circle (at 22.225 4.446 270) (size 0.64 0.64) (layers "B.Cu" "B.Mask")
      (net 9 "GND") (pinfunction "GND") (pintype "passive"))
    (pad "B39" smd circle (at 23.495 4.446 270) (size 0.64 0.64) (layers "B.Cu" "B.Mask")
      (net 9 "GND") (pinfunction "GND") (pintype "passive"))
    (pad "B40" smd circle (at 24.765 4.446 270) (size 0.64 0.64) (layers "B.Cu" "B.Mask")
      (net 127 "unconnected-(J5E-RES0-PadB40)") (pinfunction "RES0") (pintype "passive+no_connect"))
    (pad "C1" smd circle (at -24.766 3.175 270) (size 0.64 0.64) (layers "B.Cu" "B.Mask")
      (net 9 "GND") (pinfunction "GND") (pintype "passive"))
    (pad "C2" smd circle (at -23.496 3.175 270) (size 0.64 0.64) (layers "B.Cu" "B.Mask")
      (net 410 "/FMC HPC/GTX_TX0_C_P") (pinfunction "DP0_{C2M}+") (pintype "passive"))
    (pad "C3" smd circle (at -22.226 3.175 270) (size 0.64 0.64) (layers "B.Cu" "B.Mask")
      (net 412 "/FMC HPC/GTX_TX0_C_N") (pinfunction "DP0_{C2M}-") (pintype "passive"))
    (pad "C4" smd circle (at -20.955 3.175 270) (size 0.64 0.64) (layers "B.Cu" "B.Mask")
      (net 9 "GND") (pinfunction "GND") (pintype "passive"))
    (pad "C5" smd circle (at -19.685 3.175 270) (size 0.64 0.64) (layers "B.Cu" "B.Mask")
      (net 9 "GND") (pinfunction "GND") (pintype "passive"))
    (pad "C6" smd circle (at -18.415 3.175 270) (size 0.64 0.64) (layers "B.Cu" "B.Mask")
      (net 655 "GTX_RX0_P") (pinfunction "DP0_{M2C}+") (pintype "passive"))
    (pad "C7" smd circle (at -17.145 3.175 270) (size 0.64 0.64) (layers "B.Cu" "B.Mask")
      (net 656 "GTX_RX0_N") (pinfunction "DP0_{M2C}-") (pintype "passive"))
    (pad "C8" smd circle (at -15.875 3.175 270) (size 0.64 0.64) (layers "B.Cu" "B.Mask")
      (net 9 "GND") (pinfunction "GND") (pintype "passive"))
    (pad "C9" smd circle (at -14.606 3.175 270) (size 0.64 0.64) (layers "B.Cu" "B.Mask")
      (net 9 "GND") (pinfunction "GND") (pintype "passive"))
    (pad "C10" smd circle (at -13.336 3.175 270) (size 0.64 0.64) (layers "B.Cu" "B.Mask")
      (net 129 "unconnected-(J5D-LA06+-PadC10)") (pinfunction "LA06+") (pintype "passive+no_connect"))
    (pad "C11" smd circle (at -12.065 3.175 270) (size 0.64 0.64) (layers "B.Cu" "B.Mask")
      (net 130 "unconnected-(J5D-LA06--PadC11)") (pinfunction "LA06-") (pintype "passive+no_connect"))
    (pad "C12" smd circle (at -10.795 3.175 270) (size 0.64 0.64) (layers "B.Cu" "B.Mask")
      (net 9 "GND") (pinfunction "GND") (pintype "passive"))
    (pad "C13" smd circle (at -9.526 3.175 270) (size 0.64 0.64) (layers "B.Cu" "B.Mask")
      (net 9 "GND") (pinfunction "GND") (pintype "passive"))
    (pad "C14" smd circle (at -8.256 3.175 270) (size 0.64 0.64) (layers "B.Cu" "B.Mask")
      (net 132 "unconnected-(J5D-LA10+-PadC14)") (pinfunction "LA10+") (pintype "passive+no_connect"))
    (pad "C15" smd circle (at -6.986 3.175 270) (size 0.64 0.64) (layers "B.Cu" "B.Mask")
      (net 134 "unconnected-(J5D-LA10--PadC15)") (pinfunction "LA10-") (pintype "passive+no_connect"))
    (pad "C16" smd circle (at -5.715 3.175 270) (size 0.64 0.64) (layers "B.Cu" "B.Mask")
      (net 9 "GND") (pinfunction "GND") (pintype "passive"))
    (pad "C17" smd circle (at -4.446 3.175 270) (size 0.64 0.64) (layers "B.Cu" "B.Mask")
      (net 9 "GND") (pinfunction "GND") (pintype "passive"))
    (pad "C18" smd circle (at -3.175 3.175 270) (size 0.64 0.64) (layers "B.Cu" "B.Mask")
      (net 136 "unconnected-(J5D-LA14+-PadC18)") (pinfunction "LA14+") (pintype "passive+no_connect"))
    (pad "C19" smd circle (at -1.905 3.175 270) (size 0.64 0.64) (layers "B.Cu" "B.Mask")
      (net 138 "unconnected-(J5D-LA14--PadC19)") (pinfunction "LA14-") (pintype "passive+no_connect"))
    (pad "C20" smd circle (at -0.635 3.175 270) (size 0.64 0.64) (layers "B.Cu" "B.Mask")
      (net 9 "GND") (pinfunction "GND") (pintype "passive"))
    (pad "C21" smd circle (at 0.634 3.175 270) (size 0.64 0.64) (layers "B.Cu" "B.Mask")
      (net 9 "GND") (pinfunction "GND") (pintype "passive"))
    (pad "C22" smd circle (at 1.904 3.175 270) (size 0.64 0.64) (layers "B.Cu" "B.Mask")
      (net 140 "unconnected-(J5D-LA18_{CC}+-PadC22)") (pinfunction "LA18_{CC}+") (pintype "passive+no_connect"))
    (pad "C23" smd circle (at 3.174 3.175 270) (size 0.64 0.64) (layers "B.Cu" "B.Mask")
      (net 142 "unconnected-(J5D-LA18_{CC}--PadC23)") (pinfunction "LA18_{CC}-") (pintype "passive+no_connect"))
    (pad "C24" smd circle (at 4.445 3.175 270) (size 0.64 0.64) (layers "B.Cu" "B.Mask")
      (net 9 "GND") (pinfunction "GND") (pintype "passive"))
    (pad "C25" smd circle (at 5.714 3.175 270) (size 0.64 0.64) (layers "B.Cu" "B.Mask")
      (net 9 "GND") (pinfunction "GND") (pintype "passive"))
    (pad "C26" smd circle (at 6.985 3.175 270) (size 0.64 0.64) (layers "B.Cu" "B.Mask")
      (net 148 "unconnected-(J5D-LA27+-PadC26)") (pinfunction "LA27+") (pintype "passive+no_connect"))
    (pad "C27" smd circle (at 8.255 3.175 270) (size 0.64 0.64) (layers "B.Cu" "B.Mask")
      (net 150 "unconnected-(J5D-LA27--PadC27)") (pinfunction "LA27-") (pintype "passive+no_connect"))
    (pad "C28" smd circle (at 9.525 3.175 270) (size 0.64 0.64) (layers "B.Cu" "B.Mask")
      (net 9 "GND") (pinfunction "GND") (pintype "passive"))
    (pad "C29" smd circle (at 10.794 3.175 270) (size 0.64 0.64) (layers "B.Cu" "B.Mask")
      (net 9 "GND") (pinfunction "GND") (pintype "passive"))
    (pad "C30" smd circle (at 12.064 3.175 270) (size 0.64 0.64) (layers "B.Cu" "B.Mask")
      (net 907 "FMC_SCL_3V3") (pinfunction "SCL") (pintype "passive"))
    (pad "C31" smd circle (at 13.335 3.175 270) (size 0.64 0.64) (layers "B.Cu" "B.Mask")
      (net 908 "FMC_SDA_3V3") (pinfunction "SDA") (pintype "passive"))
    (pad "C32" smd circle (at 14.605 3.175 270) (size 0.64 0.64) (layers "B.Cu" "B.Mask")
      (net 9 "GND") (pinfunction "GND") (pintype "passive"))
    (pad "C33" smd circle (at 15.874 3.175 270) (size 0.64 0.64) (layers "B.Cu" "B.Mask")
      (net 9 "GND") (pinfunction "GND") (pintype "passive"))
    (pad "C34" smd circle (at 17.144 3.175 270) (size 0.64 0.64) (layers "B.Cu" "B.Mask")
      (net 180 "unconnected-(J5D-GA0-PadC34)") (pinfunction "GA0") (pintype "passive+no_connect"))
    (pad "C35" smd circle (at 18.414 3.175 270) (size 0.64 0.64) (layers "B.Cu" "B.Mask")
      (net 535 "12P0V") (pinfunction "12P0V") (pintype "passive"))
    (pad "C36" smd circle (at 19.684 3.175 270) (size 0.64 0.64) (layers "B.Cu" "B.Mask")
      (net 9 "GND") (pinfunction "GND") (pintype "passive"))
    (pad "C37" smd circle (at 20.954 3.175 270) (size 0.64 0.64) (layers "B.Cu" "B.Mask")
      (net 535 "12P0V") (pinfunction "12P0V") (pintype "passive"))
    (pad "C38" smd circle (at 22.225 3.175 270) (size 0.64 0.64) (layers "B.Cu" "B.Mask")
      (net 9 "GND") (pinfunction "GND") (pintype "passive"))
    (pad "C39" smd circle (at 23.495 3.175 270) (size 0.64 0.64) (layers "B.Cu" "B.Mask")
      (net 143 "3V3_SYS") (pinfunction "3P3V") (pintype "passive"))
    (pad "C40" smd circle (at 24.765 3.175 270) (size 0.64 0.64) (layers "B.Cu" "B.Mask")
      (net 9 "GND") (pinfunction "GND") (pintype "passive"))
    (pad "D1" smd circle (at -24.766 1.905 270) (size 0.64 0.64) (layers "B.Cu" "B.Mask")
      (net 181 "Net-(J5D-PG_{C2M})") (pinfunction "PG_{C2M}") (pintype "passive"))
    (pad "D2" smd circle (at -23.496 1.905 270) (size 0.64 0.64) (layers "B.Cu" "B.Mask")
      (net 9 "GND") (pinfunction "GND") (pintype "passive"))
    (pad "D3" smd circle (at -22.226 1.905 270) (size 0.64 0.64) (layers "B.Cu" "B.Mask")
      (net 9 "GND") (pinfunction "GND") (pintype "passive"))
    (pad "D4" smd circle (at -20.955 1.905 270) (size 0.64 0.64) (layers "B.Cu" "B.Mask")
      (net 668 "/FMC HPC/GTR_REFCLK0_R_P") (pinfunction "GBTCLK0_{M2C}+") (pintype "passive"))
    (pad "D5" smd circle (at -19.685 1.905 270) (size 0.64 0.64) (layers "B.Cu" "B.Mask")
      (net 669 "/FMC HPC/GTR_REFCLK0_R_N") (pinfunction "GBTCLK0_{M2C}-") (pintype "passive"))
    (pad "D6" smd circle (at -18.415 1.905 270) (size 0.64 0.64) (layers "B.Cu" "B.Mask")
      (net 9 "GND") (pinfunction "GND") (pintype "passive"))
    (pad "D7" smd circle (at -17.145 1.905 270) (size 0.64 0.64) (layers "B.Cu" "B.Mask")
      (net 9 "GND") (pinfunction "GND") (pintype "passive"))
    (pad "D8" smd circle (at -15.875 1.905 270) (size 0.64 0.64) (layers "B.Cu" "B.Mask")
      (net 120 "~{PERST}") (pinfunction "LA01_{CC}+") (pintype "passive"))
    (pad "D9" smd circle (at -14.606 1.905 270) (size 0.64 0.64) (layers "B.Cu" "B.Mask")
      (net 182 "unconnected-(J5D-LA01_{CC}--PadD9)") (pinfunction "LA01_{CC}-") (pintype "passive+no_connect"))
    (pad "D10" smd circle (at -13.336 1.905 270) (size 0.64 0.64) (layers "B.Cu" "B.Mask")
      (net 9 "GND") (pinfunction "GND") (pintype "passive"))
    (pad "D11" smd circle (at -12.065 1.905 270) (size 0.64 0.64) (layers "B.Cu" "B.Mask")
      (net 313 "unconnected-(J5D-LA05+-PadD11)") (pinfunction "LA05+") (pintype "passive+no_connect"))
    (pad "D12" smd circle (at -10.795 1.905 270) (size 0.64 0.64) (layers "B.Cu" "B.Mask")
      (net 352 "unconnected-(J5D-LA05--PadD12)") (pinfunction "LA05-") (pintype "passive+no_connect"))
    (pad "D13" smd circle (at -9.526 1.905 270) (size 0.64 0.64) (layers "B.Cu" "B.Mask")
      (net 9 "GND") (pinfunction "GND") (pintype "passive"))
    (pad "D14" smd circle (at -8.256 1.905 270) (size 0.64 0.64) (layers "B.Cu" "B.Mask")
      (net 359 "unconnected-(J5D-LA09+-PadD14)") (pinfunction "LA09+") (pintype "passive+no_connect"))
    (pad "D15" smd circle (at -6.986 1.905 270) (size 0.64 0.64) (layers "B.Cu" "B.Mask")
      (net 361 "unconnected-(J5D-LA09--PadD15)") (pinfunction "LA09-") (pintype "passive+no_connect"))
    (pad "D16" smd circle (at -5.715 1.905 270) (size 0.64 0.64) (layers "B.Cu" "B.Mask")
      (net 9 "GND") (pinfunction "GND") (pintype "passive"))
    (pad "D17" smd circle (at -4.446 1.905 270) (size 0.64 0.64) (layers "B.Cu" "B.Mask")
      (net 362 "unconnected-(J5D-LA13+-PadD17)") (pinfunction "LA13+") (pintype "passive+no_connect"))
    (pad "D18" smd circle (at -3.175 1.905 270) (size 0.64 0.64) (layers "B.Cu" "B.Mask")
      (net 363 "unconnected-(J5D-LA13--PadD18)") (pinfunction "LA13-") (pintype "passive+no_connect"))
    (pad "D19" smd circle (at -1.905 1.905 270) (size 0.64 0.64) (layers "B.Cu" "B.Mask")
      (net 9 "GND") (pinfunction "GND") (pintype "passive"))
    (pad "D20" smd circle (at -0.635 1.905 270) (size 0.64 0.64) (layers "B.Cu" "B.Mask")
      (net 364 "unconnected-(J5D-LA17_{CC}+-PadD20)") (pinfunction "LA17_{CC}+") (pintype "passive+no_connect"))
    (pad "D21" smd circle (at 0.634 1.905 270) (size 0.64 0.64) (layers "B.Cu" "B.Mask")
      (net 365 "unconnected-(J5D-LA17_{CC}--PadD21)") (pinfunction "LA17_{CC}-") (pintype "passive+no_connect"))
    (pad "D22" smd circle (at 1.904 1.905 270) (size 0.64 0.64) (layers "B.Cu" "B.Mask")
      (net 9 "GND") (pinfunction "GND") (pintype "passive"))
    (pad "D23" smd circle (at 3.174 1.905 270) (size 0.64 0.64) (layers "B.Cu" "B.Mask")
      (net 366 "unconnected-(J5D-LA23+-PadD23)") (pinfunction "LA23+") (pintype "passive+no_connect"))
    (pad "D24" smd circle (at 4.445 1.905 270) (size 0.64 0.64) (layers "B.Cu" "B.Mask")
      (net 367 "unconnected-(J5D-LA23--PadD24)") (pinfunction "LA23-") (pintype "passive+no_connect"))
    (pad "D25" smd circle (at 5.714 1.905 270) (size 0.64 0.64) (layers "B.Cu" "B.Mask")
      (net 9 "GND") (pinfunction "GND") (pintype "passive"))
    (pad "D26" smd circle (at 6.985 1.905 270) (size 0.64 0.64) (layers "B.Cu" "B.Mask")
      (net 368 "unconnected-(J5D-LA26+-PadD26)") (pinfunction "LA26+") (pintype "passive+no_connect"))
    (pad "D27" smd circle (at 8.255 1.905 270) (size 0.64 0.64) (layers "B.Cu" "B.Mask")
      (net 369 "unconnected-(J5D-LA26--PadD27)") (pinfunction "LA26-") (pintype "passive+no_connect"))
    (pad "D28" smd circle (at 9.525 1.905 270) (size 0.64 0.64) (layers "B.Cu" "B.Mask")
      (net 9 "GND") (pinfunction "GND") (pintype "passive"))
    (pad "D29" smd circle (at 10.794 1.905 270) (size 0.64 0.64) (layers "B.Cu" "B.Mask")
      (net 126 "AUX_JTAG_TCK") (pinfunction "TCK") (pintype "passive"))
    (pad "D30" smd circle (at 12.064 1.905 270) (size 0.64 0.64) (layers "B.Cu" "B.Mask")
      (net 128 "AUX_JTAG_TDI") (pinfunction "TDI") (pintype "passive"))
    (pad "D31" smd circle (at 13.335 1.905 270) (size 0.64 0.64) (layers "B.Cu" "B.Mask")
      (net 146 "AUX_JTAG_TDO") (pinfunction "TDO") (pintype "passive"))
    (pad "D32" smd circle (at 14.605 1.905 270) (size 0.64 0.64) (layers "B.Cu" "B.Mask")
      (net 371 "unconnected-(J5D-3P3VAUX-PadD32)") (pinfunction "3P3VAUX") (pintype "passive+no_connect"))
    (pad "D33" smd circle (at 15.874 1.905 270) (size 0.64 0.64) (layers "B.Cu" "B.Mask")
      (net 131 "AUX_JTAG_TMS") (pinfunction "TMS") (pintype "passive"))
    (pad "D34" smd circle (at 17.144 1.905 270) (size 0.64 0.64) (layers "B.Cu" "B.Mask")
      (net 133 "AUX_JTAG_RST") (pinfunction "TRST_L") (pintype "passive"))
    (pad "D35" smd circle (at 18.414 1.905 270) (size 0.64 0.64) (layers "B.Cu" "B.Mask")
      (net 372 "unconnected-(J5D-GA1-PadD35)") (pinfunction "GA1") (pintype "passive+no_connect"))
    (pad "D36" smd circle (at 19.684 1.905 270) (size 0.64 0.64) (layers "B.Cu" "B.Mask")
      (net 143 "3V3_SYS") (pinfunction "3P3V") (pintype "passive"))
    (pad "D37" smd circle (at 20.954 1.905 270) (size 0.64 0.64) (layers "B.Cu" "B.Mask")
      (net 9 "GND") (pinfunction "GND") (pintype "passive"))
    (pad "D38" smd circle (at 22.225 1.905 270) (size 0.64 0.64) (layers "B.Cu" "B.Mask")
      (net 143 "3V3_SYS") (pinfunction "3P3V") (pintype "passive"))
    (pad "D39" smd circle (at 23.495 1.905 270) (size 0.64 0.64) (layers "B.Cu" "B.Mask")
      (net 9 "GND") (pinfunction "GND") (pintype "passive"))
    (pad "D40" smd circle (at 24.765 1.905 270) (size 0.64 0.64) (layers "B.Cu" "B.Mask")
      (net 143 "3V3_SYS") (pinfunction "3P3V") (pintype "passive"))
    (pad "E1" smd circle (at -24.766 0.635 270) (size 0.64 0.64) (layers "B.Cu" "B.Mask")
      (net 9 "GND") (pinfunction "GND") (pintype "passive"))
    (pad "E2" smd circle (at -23.496 0.635 270) (size 0.64 0.64) (layers "B.Cu" "B.Mask")
      (net 373 "unconnected-(J5C-HA01_{CC}+-PadE2)") (pinfunction "HA01_{CC}+") (pintype "passive+no_connect"))
    (pad "E3" smd circle (at -22.226 0.635 270) (size 0.64 0.64) (layers "B.Cu" "B.Mask")
      (net 374 "unconnected-(J5C-HA01_{CC}--PadE3)") (pinfunction "HA01_{CC}-") (pintype "passive+no_connect"))
    (pad "E4" smd circle (at -20.955 0.635 270) (size 0.64 0.64) (layers "B.Cu" "B.Mask")
      (net 9 "GND") (pinfunction "GND") (pintype "passive"))
    (pad "E5" smd circle (at -19.685 0.635 270) (size 0.64 0.64) (layers "B.Cu" "B.Mask")
      (net 9 "GND") (pinfunction "GND") (pintype "passive"))
    (pad "E6" smd circle (at -18.415 0.635 270) (size 0.64 0.64) (layers "B.Cu" "B.Mask")
      (net 375 "unconnected-(J5C-HA05+-PadE6)") (pinfunction "HA05+") (pintype "passive+no_connect"))
    (pad "E7" smd circle (at -17.145 0.635 270) (size 0.64 0.64) (layers "B.Cu" "B.Mask")
      (net 376 "unconnected-(J5C-HA05--PadE7)") (pinfunction "HA05-") (pintype "passive+no_connect"))
    (pad "E8" smd circle (at -15.875 0.635 270) (size 0.64 0.64) (layers "B.Cu" "B.Mask")
      (net 9 "GND") (pinfunction "GND") (pintype "passive"))
    (pad "E9" smd circle (at -14.606 0.635 270) (size 0.64 0.64) (layers "B.Cu" "B.Mask")
      (net 377 "unconnected-(J5C-HA09+-PadE9)") (pinfunction "HA09+") (pintype "passive+no_connect"))
    (pad "E10" smd circle (at -13.336 0.635 270) (size 0.64 0.64) (layers "B.Cu" "B.Mask")
      (net 378 "unconnected-(J5C-HA09--PadE10)") (pinfunction "HA09-") (pintype "passive+no_connect"))
    (pad "E11" smd circle (at -12.065 0.635 270) (size 0.64 0.64) (layers "B.Cu" "B.Mask")
      (net 9 "GND") (pinfunction "GND") (pintype "passive"))
    (pad "E12" smd circle (at -10.795 0.635 270) (size 0.64 0.64) (layers "B.Cu" "B.Mask")
      (net 382 "unconnected-(J5C-HA13+-PadE12)") (pinfunction "HA13+") (pintype "passive+no_connect"))
    (pad "E13" smd circle (at -9.526 0.635 270) (size 0.64 0.64) (layers "B.Cu" "B.Mask")
      (net 384 "unconnected-(J5C-HA13--PadE13)") (pinfunction "HA13-") (pintype "passive+no_connect"))
    (pad "E14" smd circle (at -8.256 0.635 270) (size 0.64 0.64) (layers "B.Cu" "B.Mask")
      (net 9 "GND") (pinfunction "GND") (pintype "passive"))
    (pad "E15" smd circle (at -6.986 0.635 270) (size 0.64 0.64) (layers "B.Cu" "B.Mask")
      (net 385 "unconnected-(J5C-HA16+-PadE15)") (pinfunction "HA16+") (pintype "passive+no_connect"))
    (pad "E16" smd circle (at -5.715 0.635 270) (size 0.64 0.64) (layers "B.Cu" "B.Mask")
      (net 386 "unconnected-(J5C-HA16--PadE16)") (pinfunction "HA16-") (pintype "passive+no_connect"))
    (pad "E17" smd circle (at -4.446 0.635 270) (size 0.64 0.64) (layers "B.Cu" "B.Mask")
      (net 9 "GND") (pinfunction "GND") (pintype "passive"))
    (pad "E18" smd circle (at -3.175 0.635 270) (size 0.64 0.64) (layers "B.Cu" "B.Mask")
      (net 387 "unconnected-(J5C-HA20+-PadE18)") (pinfunction "HA20+") (pintype "passive+no_connect"))
    (pad "E19" smd circle (at -1.905 0.635 270) (size 0.64 0.64) (layers "B.Cu" "B.Mask")
      (net 388 "unconnected-(J5C-HA20--PadE19)") (pinfunction "HA20-") (pintype "passive+no_connect"))
    (pad "E20" smd circle (at -0.635 0.635 270) (size 0.64 0.64) (layers "B.Cu" "B.Mask")
      (net 9 "GND") (pinfunction "GND") (pintype "passive"))
    (pad "E21" smd circle (at 0.634 0.635 270) (size 0.64 0.64) (layers "B.Cu" "B.Mask")
      (net 389 "unconnected-(J5C-HB03+-PadE21)") (pinfunction "HB03+") (pintype "passive+no_connect"))
    (pad "E22" smd circle (at 1.904 0.635 270) (size 0.64 0.64) (layers "B.Cu" "B.Mask")
      (net 390 "unconnected-(J5C-HB03--PadE22)") (pinfunction "HB03-") (pintype "passive+no_connect"))
    (pad "E23" smd circle (at 3.174 0.635 270) (size 0.64 0.64) (layers "B.Cu" "B.Mask")
      (net 9 "GND") (pinfunction "GND") (pintype "passive"))
    (pad "E24" smd circle (at 4.445 0.635 270) (size 0.64 0.64) (layers "B.Cu" "B.Mask")
      (net 391 "unconnected-(J5C-HB05+-PadE24)") (pinfunction "HB05+") (pintype "passive+no_connect"))
    (pad "E25" smd circle (at 5.714 0.635 270) (size 0.64 0.64) (layers "B.Cu" "B.Mask")
      (net 392 "unconnected-(J5C-HB05--PadE25)") (pinfunction "HB05-") (pintype "passive+no_connect"))
    (pad "E26" smd circle (at 6.985 0.635 270) (size 0.64 0.64) (layers "B.Cu" "B.Mask")
      (net 9 "GND") (pinfunction "GND") (pintype "passive"))
    (pad "E27" smd circle (at 8.255 0.635 270) (size 0.64 0.64) (layers "B.Cu" "B.Mask")
      (net 393 "unconnected-(J5C-HB09+-PadE27)") (pinfunction "HB09+") (pintype "passive+no_connect"))
    (pad "E28" smd circle (at 9.525 0.635 270) (size 0.64 0.64) (layers "B.Cu" "B.Mask")
      (net 394 "unconnected-(J5C-HB09--PadE28)") (pinfunction "HB09-") (pintype "passive+no_connect"))
    (pad "E29" smd circle (at 10.794 0.635 270) (size 0.64 0.64) (layers "B.Cu" "B.Mask")
      (net 9 "GND") (pinfunction "GND") (pintype "passive"))
    (pad "E30" smd circle (at 12.064 0.635 270) (size 0.64 0.64) (layers "B.Cu" "B.Mask")
      (net 395 "unconnected-(J5C-HB13+-PadE30)") (pinfunction "HB13+") (pintype "passive+no_connect"))
    (pad "E31" smd circle (at 13.335 0.635 270) (size 0.64 0.64) (layers "B.Cu" "B.Mask")
      (net 396 "unconnected-(J5C-HB13--PadE31)") (pinfunction "HB13-") (pintype "passive+no_connect"))
    (pad "E32" smd circle (at 14.605 0.635 270) (size 0.64 0.64) (layers "B.Cu" "B.Mask")
      (net 9 "GND") (pinfunction "GND") (pintype "passive"))
    (pad "E33" smd circle (at 15.874 0.635 270) (size 0.64 0.64) (layers "B.Cu" "B.Mask")
      (net 397 "unconnected-(J5C-HB19+-PadE33)") (pinfunction "HB19+") (pintype "passive+no_connect"))
    (pad "E34" smd circle (at 17.144 0.635 270) (size 0.64 0.64) (layers "B.Cu" "B.Mask")
      (net 398 "unconnected-(J5C-HB19--PadE34)") (pinfunction "HB19-") (pintype "passive+no_connect"))
    (pad "E35" smd circle (at 18.414 0.635 270) (size 0.64 0.64) (layers "B.Cu" "B.Mask")
      (net 9 "GND") (pinfunction "GND") (pintype "passive"))
    (pad "E36" smd circle (at 19.684 0.635 270) (size 0.64 0.64) (layers "B.Cu" "B.Mask")
      (net 399 "unconnected-(J5C-HB21+-PadE36)") (pinfunction "HB21+") (pintype "passive+no_connect"))
    (pad "E37" smd circle (at 20.954 0.635 270) (size 0.64 0.64) (layers "B.Cu" "B.Mask")
      (net 401 "unconnected-(J5C-HB21--PadE37)") (pinfunction "HB21-") (pintype "passive+no_connect"))
    (pad "E38" smd circle (at 22.225 0.635 270) (size 0.64 0.64) (layers "B.Cu" "B.Mask")
      (net 9 "GND") (pinfunction "GND") (pintype "passive"))
    (pad "E39" smd circle (at 23.495 0.635 270) (size 0.64 0.64) (layers "B.Cu" "B.Mask")
      (net 402 "unconnected-(J5C-VADJ-PadE39)") (pinfunction "VADJ") (pintype "passive+no_connect"))
    (pad "E40" smd circle (at 24.765 0.635 270) (size 0.64 0.64) (layers "B.Cu" "B.Mask")
      (net 9 "GND") (pinfunction "GND") (pintype "passive"))
    (pad "F1" smd circle (at -24.766 -0.634 270) (size 0.64 0.64) (layers "B.Cu" "B.Mask")
      (net 405 "Net-(J5C-PG_{M2C})") (pinfunction "PG_{M2C}") (pintype "passive"))
    (pad "F2" smd circle (at -23.496 -0.634 270) (size 0.64 0.64) (layers "B.Cu" "B.Mask")
      (net 9 "GND") (pinfunction "GND") (pintype "passive"))
    (pad "F3" smd circle (at -22.226 -0.634 270) (size 0.64 0.64) (layers "B.Cu" "B.Mask")
      (net 9 "GND") (pinfunction "GND") (pintype "passive"))
    (pad "F4" smd circle (at -20.955 -0.634 270) (size 0.64 0.64) (layers "B.Cu" "B.Mask")
      (net 413 "unconnected-(J5C-HA00_{CC}+-PadF4)") (pinfunction "HA00_{CC}+") (pintype "passive+no_connect"))
    (pad "F5" smd circle (at -19.685 -0.634 270) (size 0.64 0.64) (layers "B.Cu" "B.Mask")
      (net 414 "unconnected-(J5C-HA00_{CC}--PadF5)") (pinfunction "HA00_{CC}-") (pintype "passive+no_connect"))
    (pad "F6" smd circle (at -18.415 -0.634 270) (size 0.64 0.64) (layers "B.Cu" "B.Mask")
      (net 9 "GND") (pinfunction "GND") (pintype "passive"))
    (pad "F7" smd circle (at -17.145 -0.634 270) (size 0.64 0.64) (layers "B.Cu" "B.Mask")
      (net 415 "unconnected-(J5C-HA04+-PadF7)") (pinfunction "HA04+") (pintype "passive+no_connect"))
    (pad "F8" smd circle (at -15.875 -0.634 270) (size 0.64 0.64) (layers "B.Cu" "B.Mask")
      (net 422 "unconnected-(J5C-HA04--PadF8)") (pinfunction "HA04-") (pintype "passive+no_connect"))
    (pad "F9" smd circle (at -14.606 -0.634 270) (size 0.64 0.64) (layers "B.Cu" "B.Mask")
      (net 9 "GND") (pinfunction "GND") (pintype "passive"))
    (pad "F10" smd circle (at -13.336 -0.634 270) (size 0.64 0.64) (layers "B.Cu" "B.Mask")
      (net 423 "unconnected-(J5C-HA08+-PadF10)") (pinfunction "HA08+") (pintype "passive+no_connect"))
    (pad "F11" smd circle (at -12.065 -0.634 270) (size 0.64 0.64) (layers "B.Cu" "B.Mask")
      (net 424 "unconnected-(J5C-HA08--PadF11)") (pinfunction "HA08-") (pintype "passive+no_connect"))
    (pad "F12" smd circle (at -10.795 -0.634 270) (size 0.64 0.64) (layers "B.Cu" "B.Mask")
      (net 9 "GND") (pinfunction "GND") (pintype "passive"))
    (pad "F13" smd circle (at -9.526 -0.634 270) (size 0.64 0.64) (layers "B.Cu" "B.Mask")
      (net 432 "unconnected-(J5C-HA12+-PadF13)") (pinfunction "HA12+") (pintype "passive+no_connect"))
    (pad "F14" smd circle (at -8.256 -0.634 270) (size 0.64 0.64) (layers "B.Cu" "B.Mask")
      (net 433 "unconnected-(J5C-HA12--PadF14)") (pinfunction "HA12-") (pintype "passive+no_connect"))
    (pad "F15" smd circle (at -6.986 -0.634 270) (size 0.64 0.64) (layers "B.Cu" "B.Mask")
      (net 9 "GND") (pinfunction "GND") (pintype "passive"))
    (pad "F16" smd circle (at -5.715 -0.634 270) (size 0.64 0.64) (layers "B.Cu" "B.Mask")
      (net 434 "unconnected-(J5C-HA15+-PadF16)") (pinfunction "HA15+") (pintype "passive+no_connect"))
    (pad "F17" smd circle (at -4.446 -0.634 270) (size 0.64 0.64) (layers "B.Cu" "B.Mask")
      (net 441 "unconnected-(J5C-HA15--PadF17)") (pinfunction "HA15-") (pintype "passive+no_connect"))
    (pad "F18" smd circle (at -3.175 -0.634 270) (size 0.64 0.64) (layers "B.Cu" "B.Mask")
      (net 9 "GND") (pinfunction "GND") (pintype "passive"))
    (pad "F19" smd circle (at -1.905 -0.634 270) (size 0.64 0.64) (layers "B.Cu" "B.Mask")
      (net 442 "unconnected-(J5C-HA19+-PadF19)") (pinfunction "HA19+") (pintype "passive+no_connect"))
    (pad "F20" smd circle (at -0.635 -0.634 270) (size 0.64 0.64) (layers "B.Cu" "B.Mask")
      (net 443 "unconnected-(J5C-HA19--PadF20)") (pinfunction "HA19-") (pintype "passive+no_connect"))
    (pad "F21" smd circle (at 0.634 -0.634 270) (size 0.64 0.64) (layers "B.Cu" "B.Mask")
      (net 9 "GND") (pinfunction "GND") (pintype "passive"))
    (pad "F22" smd circle (at 1.904 -0.634 270) (size 0.64 0.64) (layers "B.Cu" "B.Mask")
      (net 452 "unconnected-(J5C-HB02+-PadF22)") (pinfunction "HB02+") (pintype "passive+no_connect"))
    (pad "F23" smd circle (at 3.174 -0.634 270) (size 0.64 0.64) (layers "B.Cu" "B.Mask")
      (net 453 "unconnected-(J5C-HB02--PadF23)") (pinfunction "HB02-") (pintype "passive+no_connect"))
    (pad "F24" smd circle (at 4.445 -0.634 270) (size 0.64 0.64) (layers "B.Cu" "B.Mask")
      (net 9 "GND") (pinfunction "GND") (pintype "passive"))
    (pad "F25" smd circle (at 5.714 -0.634 270) (size 0.64 0.64) (layers "B.Cu" "B.Mask")
      (net 454 "unconnected-(J5C-HB04+-PadF25)") (pinfunction "HB04+") (pintype "passive+no_connect"))
    (pad "F26" smd circle (at 6.985 -0.634 270) (size 0.64 0.64) (layers "B.Cu" "B.Mask")
      (net 455 "unconnected-(J5C-HB04--PadF26)") (pinfunction "HB04-") (pintype "passive+no_connect"))
    (pad "F27" smd circle (at 8.255 -0.634 270) (size 0.64 0.64) (layers "B.Cu" "B.Mask")
      (net 9 "GND") (pinfunction "GND") (pintype "passive"))
    (pad "F28" smd circle (at 9.525 -0.634 270) (size 0.64 0.64) (layers "B.Cu" "B.Mask")
      (net 461 "unconnected-(J5C-HB08+-PadF28)") (pinfunction "HB08+") (pintype "passive+no_connect"))
    (pad "F29" smd circle (at 10.794 -0.634 270) (size 0.64 0.64) (layers "B.Cu" "B.Mask")
      (net 462 "unconnected-(J5C-HB08--PadF29)") (pinfunction "HB08-") (pintype "passive+no_connect"))
    (pad "F30" smd circle (at 12.064 -0.634 270) (size 0.64 0.64) (layers "B.Cu" "B.Mask")
      (net 9 "GND") (pinfunction "GND") (pintype "passive"))
    (pad "F31" smd circle (at 13.335 -0.634 270) (size 0.64 0.64) (layers "B.Cu" "B.Mask")
      (net 467 "unconnected-(J5C-HB12+-PadF31)") (pinfunction "HB12+") (pintype "passive+no_connect"))
    (pad "F32" smd circle (at 14.605 -0.634 270) (size 0.64 0.64) (layers "B.Cu" "B.Mask")
      (net 468 "unconnected-(J5C-HB12--PadF32)") (pinfunction "HB12-") (pintype "passive+no_connect"))
    (pad "F33" smd circle (at 15.874 -0.634 270) (size 0.64 0.64) (layers "B.Cu" "B.Mask")
      (net 9 "GND") (pinfunction "GND") (pintype "passive"))
    (pad "F34" smd circle (at 17.144 -0.634 270) (size 0.64 0.64) (layers "B.Cu" "B.Mask")
      (net 469 "unconnected-(J5C-HB16+-PadF34)") (pinfunction "HB16+") (pintype "passive+no_connect"))
    (pad "F35" smd circle (at 18.414 -0.634 270) (size 0.64 0.64) (layers "B.Cu" "B.Mask")
      (net 470 "unconnected-(J5C-HB16--PadF35)") (pinfunction "HB16-") (pintype "passive+no_connect"))
    (pad "F36" smd circle (at 19.684 -0.634 270) (size 0.64 0.64) (layers "B.Cu" "B.Mask")
      (net 9 "GND") (pinfunction "GND") (pintype "passive"))
    (pad "F37" smd circle (at 20.954 -0.634 270) (size 0.64 0.64) (layers "B.Cu" "B.Mask")
      (net 471 "unconnected-(J5C-HB20+-PadF37)") (pinfunction "HB20+") (pintype "passive+no_connect"))
    (pad "F38" smd circle (at 22.225 -0.634 270) (size 0.64 0.64) (layers "B.Cu" "B.Mask")
      (net 477 "unconnected-(J5C-HB20--PadF38)") (pinfunction "HB20-") (pintype "passive+no_connect"))
    (pad "F39" smd circle (at 23.495 -0.634 270) (size 0.64 0.64) (layers "B.Cu" "B.Mask")
      (net 9 "GND") (pinfunction "GND") (pintype "passive"))
    (pad "F40" smd circle (at 24.765 -0.634 270) (size 0.64 0.64) (layers "B.Cu" "B.Mask")
      (net 478 "unconnected-(J5C-VADJ-PadF40)") (pinfunction "VADJ") (pintype "passive+no_connect"))
    (pad "G1" smd circle (at -24.766 -1.904 270) (size 0.64 0.64) (layers "B.Cu" "B.Mask")
      (net 9 "GND") (pinfunction "GND") (pintype "passive"))
    (pad "G2" smd circle (at -23.496 -1.904 270) (size 0.64 0.64) (layers "B.Cu" "B.Mask")
      (net 484 "unconnected-(J5B-CLK1_{M2C}+-PadG2)") (pinfunction "CLK1_{M2C}+") (pintype "passive+no_connect"))
    (pad "G3" smd circle (at -22.226 -1.904 270) (size 0.64 0.64) (layers "B.Cu" "B.Mask")
      (net 485 "unconnected-(J5B-CLK1_{M2C}--PadG3)") (pinfunction "CLK1_{M2C}-") (pintype "passive+no_connect"))
    (pad "G4" smd circle (at -20.955 -1.904 270) (size 0.64 0.64) (layers "B.Cu" "B.Mask")
      (net 9 "GND") (pinfunction "GND") (pintype "passive"))
    (pad "G5" smd circle (at -19.685 -1.904 270) (size 0.64 0.64) (layers "B.Cu" "B.Mask")
      (net 9 "GND") (pinfunction "GND") (pintype "passive"))
    (pad "G6" smd circle (at -18.415 -1.904 270) (size 0.64 0.64) (layers "B.Cu" "B.Mask")
      (net 736 "EXT_LED_LINK") (pinfunction "LA00_{CC}+") (pintype "passive"))
    (pad "G7" smd circle (at -17.145 -1.904 270) (size 0.64 0.64) (layers "B.Cu" "B.Mask")
      (net 737 "EXT_LED_SPD") (pinfunction "LA00_{CC}-") (pintype "passive"))
    (pad "G8" smd circle (at -15.875 -1.904 270) (size 0.64 0.64) (layers "B.Cu" "B.Mask")
      (net 9 "GND") (pinfunction "GND") (pintype "passive"))
    (pad "G9" smd circle (at -14.606 -1.904 270) (size 0.64 0.64) (layers "B.Cu" "B.Mask")
      (net 738 "EXT_ETH2_P") (pinfunction "LA03+") (pintype "passive"))
    (pad "G10" smd circle (at -13.336 -1.904 270) (size 0.64 0.64) (layers "B.Cu" "B.Mask")
      (net 739 "EXT_ETH2_N") (pinfunction "LA03-") (pintype "passive"))
    (pad "G11" smd circle (at -12.065 -1.904 270) (size 0.64 0.64) (layers "B.Cu" "B.Mask")
      (net 9 "GND") (pinfunction "GND") (pintype "passive"))
    (pad "G12" smd circle (at -10.795 -1.904 270) (size 0.64 0.64) (layers "B.Cu" "B.Mask")
      (net 740 "EXT_ETH4_P") (pinfunction "LA08+") (pintype "passive"))
    (pad "G13" smd circle (at -9.526 -1.904 270) (size 0.64 0.64) (layers "B.Cu" "B.Mask")
      (net 741 "EXT_ETH4_N") (pinfunction "LA08-") (pintype "passive"))
    (pad "G14" smd circle (at -8.256 -1.904 270) (size 0.64 0.64) (layers "B.Cu" "B.Mask")
      (net 9 "GND") (pinfunction "GND") (pintype "passive"))
    (pad "G15" smd circle (at -6.986 -1.904 270) (size 0.64 0.64) (layers "B.Cu" "B.Mask")
      (net 486 "unconnected-(J5B-LA12+-PadG15)") (pinfunction "LA12+") (pintype "passive+no_connect"))
    (pad "G16" smd circle (at -5.715 -1.904 270) (size 0.64 0.64) (layers "B.Cu" "B.Mask")
      (net 487 "unconnected-(J5B-LA12--PadG16)") (pinfunction "LA12-") (pintype "passive+no_connect"))
    (pad "G17" smd circle (at -4.446 -1.904 270) (size 0.64 0.64) (layers "B.Cu" "B.Mask")
      (net 9 "GND") (pinfunction "GND") (pintype "passive"))
    (pad "G18" smd circle (at -3.175 -1.904 270) (size 0.64 0.64) (layers "B.Cu" "B.Mask")
      (net 407 "FMC_IO_2_P") (pinfunction "LA16+") (pintype "passive"))
    (pad "G19" smd circle (at -1.905 -1.904 270) (size 0.64 0.64) (layers "B.Cu" "B.Mask")
      (net 416 "FMC_IO_2_N") (pinfunction "LA16-") (pintype "passive"))
    (pad "G20" smd circle (at -0.635 -1.904 270) (size 0.64 0.64) (layers "B.Cu" "B.Mask")
      (net 9 "GND") (pinfunction "GND") (pintype "passive"))
    (pad "G21" smd circle (at 0.634 -1.904 270) (size 0.64 0.64) (layers "B.Cu" "B.Mask")
      (net 427 "FMC_IO_1_P") (pinfunction "LA20+") (pintype "passive"))
    (pad "G22" smd circle (at 1.904 -1.904 270) (size 0.64 0.64) (layers "B.Cu" "B.Mask")
      (net 417 "FMC_IO_1_N") (pinfunction "LA20-") (pintype "passive"))
    (pad "G23" smd circle (at 3.174 -1.904 270) (size 0.64 0.64) (layers "B.Cu" "B.Mask")
      (net 9 "GND") (pinfunction "GND") (pintype "passive"))
    (pad "G24" smd circle (at 4.445 -1.904 270) (size 0.64 0.64) (layers "B.Cu" "B.Mask")
      (net 437 "FMC_IO_6_P") (pinfunction "LA22+") (pintype "passive"))
    (pad "G25" smd circle (at 5.714 -1.904 270) (size 0.64 0.64) (layers "B.Cu" "B.Mask")
      (net 444 "FMC_IO_6_N") (pinfunction "LA22-") (pintype "passive"))
    (pad "G26" smd circle (at 6.985 -1.904 270) (size 0.64 0.64) (layers "B.Cu" "B.Mask")
      (net 9 "GND") (pinfunction "GND") (pintype "passive"))
    (pad "G27" smd circle (at 8.255 -1.904 270) (size 0.64 0.64) (layers "B.Cu" "B.Mask")
      (net 476 "FMC_IO_8_P") (pinfunction "LA25+") (pintype "passive"))
    (pad "G28" smd circle (at 9.525 -1.904 270) (size 0.64 0.64) (layers "B.Cu" "B.Mask")
      (net 460 "FMC_IO_8_N") (pinfunction "LA25-") (pintype "passive"))
    (pad "G29" smd circle (at 10.794 -1.904 270) (size 0.64 0.64) (layers "B.Cu" "B.Mask")
      (net 9 "GND") (pinfunction "GND") (pintype "passive"))
    (pad "G30" smd circle (at 12.064 -1.904 270) (size 0.64 0.64) (layers "B.Cu" "B.Mask")
      (net 515 "FMC_IO_9_P") (pinfunction "LA29+") (pintype "passive"))
    (pad "G31" smd circle (at 13.335 -1.904 270) (size 0.64 0.64) (layers "B.Cu" "B.Mask")
      (net 516 "FMC_IO_9_N") (pinfunction "LA29-") (pintype "passive"))
    (pad "G32" smd circle (at 14.605 -1.904 270) (size 0.64 0.64) (layers "B.Cu" "B.Mask")
      (net 9 "GND") (pinfunction "GND") (pintype "passive"))
    (pad "G33" smd circle (at 15.874 -1.904 270) (size 0.64 0.64) (layers "B.Cu" "B.Mask")
      (net 529 "FMC_IO_0") (pinfunction "LA31+") (pintype "passive"))
    (pad "G34" smd circle (at 17.144 -1.904 270) (size 0.64 0.64) (layers "B.Cu" "B.Mask")
      (net 488 "unconnected-(J5B-LA31--PadG34)") (pinfunction "LA31-") (pintype "passive+no_connect"))
    (pad "G35" smd circle (at 18.414 -1.904 270) (size 0.64 0.64) (layers "B.Cu" "B.Mask")
      (net 9 "GND") (pinfunction "GND") (pintype "passive"))
    (pad "G36" smd circle (at 19.684 -1.904 270) (size 0.64 0.64) (layers "B.Cu" "B.Mask")
      (net 489 "unconnected-(J5B-LA33+-PadG36)") (pinfunction "LA33+") (pintype "passive+no_connect"))
    (pad "G37" smd circle (at 20.954 -1.904 270) (size 0.64 0.64) (layers "B.Cu" "B.Mask")
      (net 494 "unconnected-(J5B-LA33--PadG37)") (pinfunction "LA33-") (pintype "passive+no_connect"))
    (pad "G38" smd circle (at 22.225 -1.904 270) (size 0.64 0.64) (layers "B.Cu" "B.Mask")
      (net 9 "GND") (pinfunction "GND") (pintype "passive"))
    (pad "G39" smd circle (at 23.495 -1.904 270) (size 0.64 0.64) (layers "B.Cu" "B.Mask")
      (net 495 "unconnected-(J5B-VADJ-PadG39)") (pinfunction "VADJ") (pintype "passive+no_connect"))
    (pad "G40" smd circle (at 24.765 -1.904 270) (size 0.64 0.64) (layers "B.Cu" "B.Mask")
      (net 9 "GND") (pinfunction "GND") (pintype "passive"))
    (pad "H1" smd circle (at -24.766 -3.174 270) (size 0.64 0.64) (layers "B.Cu" "B.Mask")
      (net 496 "Net-(J5B-VREF_{A_M2C})") (pinfunction "VREF_{A_M2C}") (pintype "passive"))
    (pad "H2" smd circle (at -23.496 -3.174 270) (size 0.64 0.64) (layers "B.Cu" "B.Mask")
      (net 751 "PRSNT_M2C") (pinfunction "~{PRSNT_{M2C}}") (pintype "passive"))
    (pad "H3" smd circle (at -22.226 -3.174 270) (size 0.64 0.64) (layers "B.Cu" "B.Mask")
      (net 9 "GND") (pinfunction "GND") (pintype "passive"))
    (pad "H4" smd circle (at -20.955 -3.174 270) (size 0.64 0.64) (layers "B.Cu" "B.Mask")
      (net 500 "unconnected-(J5B-CLK0_{M2C}+-PadH4)") (pinfunction "CLK0_{M2C}+") (pintype "passive+no_connect"))
    (pad "H5" smd circle (at -19.685 -3.174 270) (size 0.64 0.64) (layers "B.Cu" "B.Mask")
      (net 501 "unconnected-(J5B-CLK0_{M2C}--PadH5)") (pinfunction "CLK0_{M2C}-") (pintype "passive+no_connect"))
    (pad "H6" smd circle (at -18.415 -3.174 270) (size 0.64 0.64) (layers "B.Cu" "B.Mask")
      (net 9 "GND") (pinfunction "GND") (pintype "passive"))
    (pad "H7" smd circle (at -17.145 -3.174 270) (size 0.64 0.64) (layers "B.Cu" "B.Mask")
      (net 754 "EXT_ETH1_P") (pinfunction "LA02+") (pintype "passive"))
    (pad "H8" smd circle (at -15.875 -3.174 270) (size 0.64 0.64) (layers "B.Cu" "B.Mask")
      (net 755 "EXT_ETH1_N") (pinfunction "LA02-") (pintype "passive"))
    (pad "H9" smd circle (at -14.606 -3.174 270) (size 0.64 0.64) (layers "B.Cu" "B.Mask")
      (net 9 "GND") (pinfunction "GND") (pintype "passive"))
    (pad "H10" smd circle (at -13.336 -3.174 270) (size 0.64 0.64) (layers "B.Cu" "B.Mask")
      (net 756 "EXT_ETH3_P") (pinfunction "LA04+") (pintype "passive"))
    (pad "H11" smd circle (at -12.065 -3.174 270) (size 0.64 0.64) (layers "B.Cu" "B.Mask")
      (net 757 "EXT_ETH3_N") (pinfunction "LA04-") (pintype "passive"))
    (pad "H12" smd circle (at -10.795 -3.174 270) (size 0.64 0.64) (layers "B.Cu" "B.Mask")
      (net 9 "GND") (pinfunction "GND") (pintype "passive"))
    (pad "H13" smd circle (at -9.526 -3.174 270) (size 0.64 0.64) (layers "B.Cu" "B.Mask")
      (net 502 "unconnected-(J5B-LA07+-PadH13)") (pinfunction "LA07+") (pintype "passive+no_connect"))
    (pad "H14" smd circle (at -8.256 -3.174 270) (size 0.64 0.64) (layers "B.Cu" "B.Mask")
      (net 503 "unconnected-(J5B-LA07--PadH14)") (pinfunction "LA07-") (pintype "passive+no_connect"))
    (pad "H15" smd circle (at -6.986 -3.174 270) (size 0.64 0.64) (layers "B.Cu" "B.Mask")
      (net 9 "GND") (pinfunction "GND") (pintype "passive"))
    (pad "H16" smd circle (at -5.715 -3.174 270) (size 0.64 0.64) (layers "B.Cu" "B.Mask")
      (net 436 "FMC_IO_4_P") (pinfunction "LA11+") (pintype "passive"))
    (pad "H17" smd circle (at -4.446 -3.174 270) (size 0.64 0.64) (layers "B.Cu" "B.Mask")
      (net 426 "FMC_IO_4_N") (pinfunction "LA11-") (pintype "passive"))
    (pad "H18" smd circle (at -3.175 -3.174 270) (size 0.64 0.64) (layers "B.Cu" "B.Mask")
      (net 9 "GND") (pinfunction "GND") (pintype "passive"))
    (pad "H19" smd circle (at -1.905 -3.174 270) (size 0.64 0.64) (layers "B.Cu" "B.Mask")
      (net 425 "FMC_IO_3_P") (pinfunction "LA15+") (pintype "passive"))
    (pad "H20" smd circle (at -0.635 -3.174 270) (size 0.64 0.64) (layers "B.Cu" "B.Mask")
      (net 406 "FMC_IO_3_N") (pinfunction "LA15-") (pintype "passive"))
    (pad "H21" smd circle (at 0.634 -3.174 270) (size 0.64 0.64) (layers "B.Cu" "B.Mask")
      (net 9 "GND") (pinfunction "GND") (pintype "passive"))
    (pad "H22" smd circle (at 1.904 -3.174 270) (size 0.64 0.64) (layers "B.Cu" "B.Mask")
      (net 810 "FMC_IO_19_P") (pinfunction "LA19+") (pintype "passive"))
    (pad "H23" smd circle (at 3.174 -3.174 270) (size 0.64 0.64) (layers "B.Cu" "B.Mask")
      (net 528 "FMC_IO_19_N") (pinfunction "LA19-") (pintype "passive"))
    (pad "H24" smd circle (at 4.445 -3.174 270) (size 0.64 0.64) (layers "B.Cu" "B.Mask")
      (net 9 "GND") (pinfunction "GND") (pintype "passive"))
    (pad "H25" smd circle (at 5.714 -3.174 270) (size 0.64 0.64) (layers "B.Cu" "B.Mask")
      (net 448 "FMC_IO_10_P") (pinfunction "LA21+") (pintype "passive"))
    (pad "H26" smd circle (at 6.985 -3.174 270) (size 0.64 0.64) (layers "B.Cu" "B.Mask")
      (net 456 "FMC_IO_10_N") (pinfunction "LA21-") (pintype "passive"))
    (pad "H27" smd circle (at 8.255 -3.174 270) (size 0.64 0.64) (layers "B.Cu" "B.Mask")
      (net 9 "GND") (pinfunction "GND") (pintype "passive"))
    (pad "H28" smd circle (at 9.525 -3.174 270) (size 0.64 0.64) (layers "B.Cu" "B.Mask")
      (net 505 "FMC_IO_7_P") (pinfunction "LA24+") (pintype "passive"))
    (pad "H29" smd circle (at 10.794 -3.174 270) (size 0.64 0.64) (layers "B.Cu" "B.Mask")
      (net 490 "FMC_IO_7_N") (pinfunction "LA24-") (pintype "passive"))
    (pad "H30" smd circle (at 12.064 -3.174 270) (size 0.64 0.64) (layers "B.Cu" "B.Mask")
      (net 9 "GND") (pinfunction "GND") (pintype "passive"))
    (pad "H31" smd circle (at 13.335 -3.174 270) (size 0.64 0.64) (layers "B.Cu" "B.Mask")
      (net 504 "unconnected-(J5B-LA28+-PadH31)") (pinfunction "LA28+") (pintype "passive+no_connect"))
    (pad "H32" smd circle (at 14.605 -3.174 270) (size 0.64 0.64) (layers "B.Cu" "B.Mask")
      (net 508 "unconnected-(J5B-LA28--PadH32)") (pinfunction "LA28-") (pintype "passive+no_connect"))
    (pad "H33" smd circle (at 15.874 -3.174 270) (size 0.64 0.64) (layers "B.Cu" "B.Mask")
      (net 9 "GND") (pinfunction "GND") (pintype "passive"))
    (pad "H34" smd circle (at 17.144 -3.174 270) (size 0.64 0.64) (layers "B.Cu" "B.Mask")
      (net 509 "unconnected-(J5B-LA30+-PadH34)") (pinfunction "LA30+") (pintype "passive+no_connect"))
    (pad "H35" smd circle (at 18.414 -3.174 270) (size 0.64 0.64) (layers "B.Cu" "B.Mask")
      (net 510 "unconnected-(J5B-LA30--PadH35)") (pinfunction "LA30-") (pintype "passive+no_connect"))
    (pad "H36" smd circle (at 19.684 -3.174 270) (size 0.64 0.64) (layers "B.Cu" "B.Mask")
      (net 9 "GND") (pinfunction "GND") (pintype "passive"))
    (pad "H37" smd circle (at 20.954 -3.174 270) (size 0.64 0.64) (layers "B.Cu" "B.Mask")
      (net 511 "unconnected-(J5B-LA32+-PadH37)") (pinfunction "LA32+") (pintype "passive+no_connect"))
    (pad "H38" smd circle (at 22.225 -3.174 270) (size 0.64 0.64) (layers "B.Cu" "B.Mask")
      (net 519 "unconnected-(J5B-LA32--PadH38)") (pinfunction "LA32-") (pintype "passive+no_connect"))
    (pad "H39" smd circle (at 23.495 -3.174 270) (size 0.64 0.64) (layers "B.Cu" "B.Mask")
      (net 9 "GND") (pinfunction "GND") (pintype "passive"))
    (pad "H40" smd circle (at 24.765 -3.174 270) (size 0.64 0.64) (layers "B.Cu" "B.Mask")
      (net 520 "unconnected-(J5B-VADJ-PadH40)") (pinfunction "VADJ") (pintype "passive+no_connect"))
    (pad "J1" smd circle (at -24.766 -4.445 270) (size 0.64 0.64) (layers "B.Cu" "B.Mask")
      (net 9 "GND") (pinfunction "GND") (pintype "passive"))
    (pad "J2" smd circle (at -23.496 -4.445 270) (size 0.64 0.64) (layers "B.Cu" "B.Mask")
      (net 899 "/FMC HPC/GTR_REFCLK3_R_P") (pinfunction "CLK3_{BIDIR}+") (pintype "passive"))
    (pad "J3" smd circle (at -22.226 -4.445 270) (size 0.64 0.64) (layers "B.Cu" "B.Mask")
      (net 900 "/FMC HPC/GTR_REFCLK3_R_N") (pinfunction "CLK3_{BIDIR}-") (pintype "passive"))
    (pad "J4" smd circle (at -20.955 -4.445 270) (size 0.64 0.64) (layers "B.Cu" "B.Mask")
      (net 9 "GND") (pinfunction "GND") (pintype "passive"))
    (pad "J5" smd circle (at -19.685 -4.445 270) (size 0.64 0.64) (layers "B.Cu" "B.Mask")
      (net 9 "GND") (pinfunction "GND") (pintype "passive"))
    (pad "J6" smd circle (at -18.415 -4.445 270) (size 0.64 0.64) (layers "B.Cu" "B.Mask")
      (net 521 "unconnected-(J5A-HA03+-PadJ6)") (pinfunction "HA03+") (pintype "passive+no_connect"))
    (pad "J7" smd circle (at -17.145 -4.445 270) (size 0.64 0.64) (layers "B.Cu" "B.Mask")
      (net 522 "unconnected-(J5A-HA03--PadJ7)") (pinfunction "HA03-") (pintype "passive+no_connect"))
    (pad "J8" smd circle (at -15.875 -4.445 270) (size 0.64 0.64) (layers "B.Cu" "B.Mask")
      (net 9 "GND") (pinfunction "GND") (pintype "passive"))
    (pad "J9" smd circle (at -14.606 -4.445 270) (size 0.64 0.64) (layers "B.Cu" "B.Mask")
      (net 514 "FMC_IO_18_P") (pinfunction "HA07+") (pintype "passive"))
    (pad "J10" smd circle (at -13.336 -4.445 270) (size 0.64 0.64) (layers "B.Cu" "B.Mask")
      (net 493 "FMC_IO_18_N") (pinfunction "HA07-") (pintype "passive"))
    (pad "J11" smd circle (at -12.065 -4.445 270) (size 0.64 0.64) (layers "B.Cu" "B.Mask")
      (net 9 "GND") (pinfunction "GND") (pintype "passive"))
    (pad "J12" smd circle (at -10.795 -4.445 270) (size 0.64 0.64) (layers "B.Cu" "B.Mask")
      (net 816 "FMC_IO_23_P") (pinfunction "HA11+") (pintype "passive"))
    (pad "J13" smd circle (at -9.526 -4.445 270) (size 0.64 0.64) (layers "B.Cu" "B.Mask")
      (net 812 "FMC_IO_23_N") (pinfunction "HA11-") (pintype "passive"))
    (pad "J14" smd circle (at -8.256 -4.445 270) (size 0.64 0.64) (layers "B.Cu" "B.Mask")
      (net 9 "GND") (pinfunction "GND") (pintype "passive"))
    (pad "J15" smd circle (at -6.986 -4.445 270) (size 0.64 0.64) (layers "B.Cu" "B.Mask")
      (net 523 "unconnected-(J5A-HA14+-PadJ15)") (pinfunction "HA14+") (pintype "passive+no_connect"))
    (pad "J16" smd circle (at -5.715 -4.445 270) (size 0.64 0.64) (layers "B.Cu" "B.Mask")
      (net 527 "unconnected-(J5A-HA14--PadJ16)") (pinfunction "HA14-") (pintype "passive+no_connect"))
    (pad "J17" smd circle (at -4.446 -4.445 270) (size 0.64 0.64) (layers "B.Cu" "B.Mask")
      (net 9 "GND") (pinfunction "GND") (pintype "passive"))
    (pad "J18" smd circle (at -3.175 -4.445 270) (size 0.64 0.64) (layers "B.Cu" "B.Mask")
      (net 428 "FMC_IO_5_P") (pinfunction "HA18+") (pintype "passive"))
    (pad "J19" smd circle (at -1.905 -4.445 270) (size 0.64 0.64) (layers "B.Cu" "B.Mask")
      (net 435 "FMC_IO_5_N") (pinfunction "HA18-") (pintype "passive"))
    (pad "J20" smd circle (at -0.635 -4.445 270) (size 0.64 0.64) (layers "B.Cu" "B.Mask")
      (net 9 "GND") (pinfunction "GND") (pintype "passive"))
    (pad "J21" smd circle (at 0.634 -4.445 270) (size 0.64 0.64) (layers "B.Cu" "B.Mask")
      (net 472 "FMC_IO_12_P") (pinfunction "HA22+") (pintype "passive"))
    (pad "J22" smd circle (at 1.904 -4.445 270) (size 0.64 0.64) (layers "B.Cu" "B.Mask")
      (net 457 "FMC_IO_12_N") (pinfunction "HA22-") (pintype "passive"))
    (pad "J23" smd circle (at 3.174 -4.445 270) (size 0.64 0.64) (layers "B.Cu" "B.Mask")
      (net 9 "GND") (pinfunction "GND") (pintype "passive"))
    (pad "J24" smd circle (at 4.445 -4.445 270) (size 0.64 0.64) (layers "B.Cu" "B.Mask")
      (net 506 "FMC_IO_14_P") (pinfunction "HB01+") (pintype "passive"))
    (pad "J25" smd circle (at 5.714 -4.445 270) (size 0.64 0.64) (layers "B.Cu" "B.Mask")
      (net 507 "FMC_IO_14_N") (pinfunction "HB01-") (pintype "passive"))
    (pad "J26" smd circle (at 6.985 -4.445 270) (size 0.64 0.64) (layers "B.Cu" "B.Mask")
      (net 9 "GND") (pinfunction "GND") (pintype "passive"))
    (pad "J27" smd circle (at 8.255 -4.445 270) (size 0.64 0.64) (layers "B.Cu" "B.Mask")
      (net 811 "FMC_IO_24_P") (pinfunction "HB07+") (pintype "passive"))
    (pad "J28" smd circle (at 9.525 -4.445 270) (size 0.64 0.64) (layers "B.Cu" "B.Mask")
      (net 809 "FMC_IO_24_N") (pinfunction "HB07-") (pintype "passive"))
    (pad "J29" smd circle (at 10.794 -4.445 270) (size 0.64 0.64) (layers "B.Cu" "B.Mask")
      (net 9 "GND") (pinfunction "GND") (pintype "passive"))
    (pad "J30" smd circle (at 12.064 -4.445 270) (size 0.64 0.64) (layers "B.Cu" "B.Mask")
      (net 530 "unconnected-(J5A-HB11+-PadJ30)") (pinfunction "HB11+") (pintype "passive+no_connect"))
    (pad "J31" smd circle (at 13.335 -4.445 270) (size 0.64 0.64) (layers "B.Cu" "B.Mask")
      (net 531 "unconnected-(J5A-HB11--PadJ31)") (pinfunction "HB11-") (pintype "passive+no_connect"))
    (pad "J32" smd circle (at 14.605 -4.445 270) (size 0.64 0.64) (layers "B.Cu" "B.Mask")
      (net 9 "GND") (pinfunction "GND") (pintype "passive"))
    (pad "J33" smd circle (at 15.874 -4.445 270) (size 0.64 0.64) (layers "B.Cu" "B.Mask")
      (net 532 "unconnected-(J5A-HB15+-PadJ33)") (pinfunction "HB15+") (pintype "passive+no_connect"))
    (pad "J34" smd circle (at 17.144 -4.445 270) (size 0.64 0.64) (layers "B.Cu" "B.Mask")
      (net 533 "unconnected-(J5A-HB15--PadJ34)") (pinfunction "HB15-") (pintype "passive+no_connect"))
    (pad "J35" smd circle (at 18.414 -4.445 270) (size 0.64 0.64) (layers "B.Cu" "B.Mask")
      (net 9 "GND") (pinfunction "GND") (pintype "passive"))
    (pad "J36" smd circle (at 19.684 -4.445 270) (size 0.64 0.64) (layers "B.Cu" "B.Mask")
      (net 534 "unconnected-(J5A-HB18+-PadJ36)") (pinfunction "HB18+") (pintype "passive+no_connect"))
    (pad "J37" smd circle (at 20.954 -4.445 270) (size 0.64 0.64) (layers "B.Cu" "B.Mask")
      (net 540 "unconnected-(J5A-HB18--PadJ37)") (pinfunction "HB18-") (pintype "passive+no_connect"))
    (pad "J38" smd circle (at 22.225 -4.445 270) (size 0.64 0.64) (layers "B.Cu" "B.Mask")
      (net 9 "GND") (pinfunction "GND") (pintype "passive"))
    (pad "J39" smd circle (at 23.495 -4.445 270) (size 0.64 0.64) (layers "B.Cu" "B.Mask")
      (net 541 "unconnected-(J5A-VIO_{B_M2C}-PadJ39)") (pinfunction "VIO_{B_M2C}") (pintype "passive+no_connect"))
    (pad "J40" smd circle (at 24.765 -4.445 270) (size 0.64 0.64) (layers "B.Cu" "B.Mask")
      (net 9 "GND") (pinfunction "GND") (pintype "passive"))
    (pad "K1" smd circle (at -24.766 -5.714 270) (size 0.64 0.64) (layers "B.Cu" "B.Mask")
      (net 542 "Net-(J5A-VREF_{B_M2C})") (pinfunction "VREF_{B_M2C}") (pintype "passive"))
    (pad "K2" smd circle (at -23.496 -5.714 270) (size 0.64 0.64) (layers "B.Cu" "B.Mask")
      (net 9 "GND") (pinfunction "GND") (pintype "passive"))
    (pad "K3" smd circle (at -22.226 -5.714 270) (size 0.64 0.64) (layers "B.Cu" "B.Mask")
      (net 9 "GND") (pinfunction "GND") (pintype "passive"))
    (pad "K4" smd circle (at -20.955 -5.714 270) (size 0.64 0.64) (layers "B.Cu" "B.Mask")
      (net 903 "/FMC HPC/GTR_REFCLK2_R_P") (pinfunction "CLK2_{BIDIR}+") (pintype "passive"))
    (pad "K5" smd circle (at -19.685 -5.714 270) (size 0.64 0.64) (layers "B.Cu" "B.Mask")
      (net 904 "/FMC HPC/GTR_REFCLK2_R_N") (pinfunction "CLK2_{BIDIR}-") (pintype "passive"))
    (pad "K6" smd circle (at -18.415 -5.714 270) (size 0.64 0.64) (layers "B.Cu" "B.Mask")
      (net 9 "GND") (pinfunction "GND") (pintype "passive"))
    (pad "K7" smd circle (at -17.145 -5.714 270) (size 0.64 0.64) (layers "B.Cu" "B.Mask")
      (net 492 "FMC_IO_16_P") (pinfunction "HA02+") (pintype "passive"))
    (pad "K8" smd circle (at -15.875 -5.714 270) (size 0.64 0.64) (layers "B.Cu" "B.Mask")
      (net 475 "FMC_IO_16_N") (pinfunction "HA02-") (pintype "passive"))
    (pad "K9" smd circle (at -14.606 -5.714 270) (size 0.64 0.64) (layers "B.Cu" "B.Mask")
      (net 9 "GND") (pinfunction "GND") (pintype "passive"))
    (pad "K10" smd circle (at -13.336 -5.714 270) (size 0.64 0.64) (layers "B.Cu" "B.Mask")
      (net 813 "FMC_IO_21_P") (pinfunction "HA06+") (pintype "passive"))
    (pad "K11" smd circle (at -12.065 -5.714 270) (size 0.64 0.64) (layers "B.Cu" "B.Mask")
      (net 814 "FMC_IO_21_N") (pinfunction "HA06-") (pintype "passive"))
    (pad "K12" smd circle (at -10.795 -5.714 270) (size 0.64 0.64) (layers "B.Cu" "B.Mask")
      (net 9 "GND") (pinfunction "GND") (pintype "passive"))
    (pad "K13" smd circle (at -9.526 -5.714 270) (size 0.64 0.64) (layers "B.Cu" "B.Mask")
      (net 543 "unconnected-(J5A-HA10+-PadK13)") (pinfunction "HA10+") (pintype "passive+no_connect"))
    (pad "K14" smd circle (at -8.256 -5.714 270) (size 0.64 0.64) (layers "B.Cu" "B.Mask")
      (net 544 "unconnected-(J5A-HA10--PadK14)") (pinfunction "HA10-") (pintype "passive+no_connect"))
    (pad "K15" smd circle (at -6.986 -5.714 270) (size 0.64 0.64) (layers "B.Cu" "B.Mask")
      (net 9 "GND") (pinfunction "GND") (pintype "passive"))
    (pad "K16" smd circle (at -5.715 -5.714 270) (size 0.64 0.64) (layers "B.Cu" "B.Mask")
      (net 474 "FMC_IO_17_P") (pinfunction "HA17_{CC}+") (pintype "passive"))
    (pad "K17" smd circle (at -4.446 -5.714 270) (size 0.64 0.64) (layers "B.Cu" "B.Mask")
      (net 459 "FMC_IO_17_N") (pinfunction "HA17_{CC}-") (pintype "passive"))
    (pad "K18" smd circle (at -3.175 -5.714 270) (size 0.64 0.64) (layers "B.Cu" "B.Mask")
      (net 9 "GND") (pinfunction "GND") (pintype "passive"))
    (pad "K19" smd circle (at -1.905 -5.714 270) (size 0.64 0.64) (layers "B.Cu" "B.Mask")
      (net 458 "FMC_IO_13_P") (pinfunction "HA21+") (pintype "passive"))
    (pad "K20" smd circle (at -0.635 -5.714 270) (size 0.64 0.64) (layers "B.Cu" "B.Mask")
      (net 445 "FMC_IO_13_N") (pinfunction "HA21-") (pintype "passive"))
    (pad "K21" smd circle (at 0.634 -5.714 270) (size 0.64 0.64) (layers "B.Cu" "B.Mask")
      (net 9 "GND") (pinfunction "GND") (pintype "passive"))
    (pad "K22" smd circle (at 1.904 -5.714 270) (size 0.64 0.64) (layers "B.Cu" "B.Mask")
      (net 491 "FMC_IO_11_P") (pinfunction "HA23+") (pintype "passive"))
    (pad "K23" smd circle (at 3.174 -5.714 270) (size 0.64 0.64) (layers "B.Cu" "B.Mask")
      (net 473 "FMC_IO_11_N") (pinfunction "HA23-") (pintype "passive"))
    (pad "K24" smd circle (at 4.445 -5.714 270) (size 0.64 0.64) (layers "B.Cu" "B.Mask")
      (net 9 "GND") (pinfunction "GND") (pintype "passive"))
    (pad "K25" smd circle (at 5.714 -5.714 270) (size 0.64 0.64) (layers "B.Cu" "B.Mask")
      (net 517 "FMC_IO_20_P") (pinfunction "HB00_{CC}+") (pintype "passive"))
    (pad "K26" smd circle (at 6.985 -5.714 270) (size 0.64 0.64) (layers "B.Cu" "B.Mask")
      (net 518 "FMC_IO_20_N") (pinfunction "HB00_{CC}-") (pintype "passive"))
    (pad "K27" smd circle (at 8.255 -5.714 270) (size 0.64 0.64) (layers "B.Cu" "B.Mask")
      (net 9 "GND") (pinfunction "GND") (pintype "passive"))
    (pad "K28" smd circle (at 9.525 -5.714 270) (size 0.64 0.64) (layers "B.Cu" "B.Mask")
      (net 815 "FMC_IO_25") (pinfunction "HB06_{CC}+") (pintype "passive"))
    (pad "K29" smd circle (at 10.794 -5.714 270) (size 0.64 0.64) (layers "B.Cu" "B.Mask")
      (net 545 "unconnected-(J5A-HB06_{CC}--PadK29)") (pinfunction "HB06_{CC}-") (pintype "passive+no_connect"))
    (pad "K30" smd circle (at 12.064 -5.714 270) (size 0.64 0.64) (layers "B.Cu" "B.Mask")
      (net 9 "GND") (pinfunction "GND") (pintype "passive"))
    (pad "K31" smd circle (at 13.335 -5.714 270) (size 0.64 0.64) (layers "B.Cu" "B.Mask")
      (net 549 "unconnected-(J5A-HB10+-PadK31)") (pinfunction "HB10+") (pintype "passive+no_connect"))
    (pad "K32" smd circle (at 14.605 -5.714 270) (size 0.64 0.64) (layers "B.Cu" "B.Mask")
      (net 550 "unconnected-(J5A-HB10--PadK32)") (pinfunction "HB10-") (pintype "passive+no_connect"))
    (pad "K33" smd circle (at 15.874 -5.714 270) (size 0.64 0.64) (layers "B.Cu" "B.Mask")
      (net 9 "GND") (pinfunction "GND") (pintype "passive"))
    (pad "K34" smd circle (at 17.144 -5.714 270) (size 0.64 0.64) (layers "B.Cu" "B.Mask")
      (net 551 "unconnected-(J5A-HB14+-PadK34)") (pinfunction "HB14+") (pintype "passive+no_connect"))
    (pad "K35" smd circle (at 18.414 -5.714 270) (size 0.64 0.64) (layers "B.Cu" "B.Mask")
      (net 552 "unconnected-(J5A-HB14--PadK35)") (pinfunction "HB14-") (pintype "passive+no_connect"))
    (pad "K36" smd circle (at 19.684 -5.714 270) (size 0.64 0.64) (layers "B.Cu" "B.Mask")
      (net 9 "GND") (pinfunction "GND") (pintype "passive"))
    (pad "K37" smd circle (at 20.954 -5.714 270) (size 0.64 0.64) (layers "B.Cu" "B.Mask")
      (net 553 "unconnected-(J5A-HB17_{CC}+-PadK37)") (pinfunction "HB17_{CC}+") (pintype "passive+no_connect"))
    (pad "K38" smd circle (at 22.225 -5.714 270) (size 0.64 0.64) (layers "B.Cu" "B.Mask")
      (net 554 "unconnected-(J5A-HB17_{CC}--PadK38)") (pinfunction "HB17_{CC}-") (pintype "passive+no_connect"))
    (pad "K39" smd circle (at 23.495 -5.714 270) (size 0.64 0.64) (layers "B.Cu" "B.Mask")
      (net 9 "GND") (pinfunction "GND") (pintype "passive"))
    (pad "K40" smd circle (at 24.765 -5.714 270) (size 0.64 0.64) (layers "B.Cu" "B.Mask")
      (net 555 "unconnected-(J5A-VIO_{B_M2C}-PadK40)") (pinfunction "VIO_{B_M2C}") (pintype "passive+no_connect"))
  )

  (footprint "data-center-rdimm-ddr4-tester-footprints:R_0402_1005Metric" (layer "B.Cu")
    (at 192.725 92.675)
    (descr "Resistor SMD 0402")
    (tags "resistor SMD 0402")
    (property "Author" "Antmicro")
    (property "License" "Apache-2.0")
    (property "MPN" "CR0402-FX-1000GLF")
    (property "Manufacturer" "Bourns")
    (property "Sheetfile" "fpga-power.kicad_sch")
    (property "Sheetname" "FPGA power")
    (property "Tolerance" "1%")
    (property "Val" "100R")
    (property "ki_description" "100R resistor in 0402 package with 1% tolerance")
    (attr smd)
    (fp_text reference "R207" (at -0.825 -0.045 45) (layer "B.SilkS")
        (effects (font (size 0.7 0.7) (thickness 0.15)) (justify left bottom mirror))
    )
    (fp_text value "R_100R_0402" (at 0 -1.4 180) (layer "B.Fab") hide
        (effects (font (size 0.7 0.7) (thickness 0.15)) (justify left bottom mirror))
    )
    (fp_text user "License: Apache-2.0" (at -0.95 -5.169 180) (layer "B.Fab") hide
        (effects (font (size 0.7 0.7) (thickness 0.15)) (justify left bottom mirror))
    )
    (fp_text user "Author: Antmicro" (at -0.95 -4.169 180) (layer "B.Fab") hide
        (effects (font (size 0.7 0.7) (thickness 0.15)) (justify left bottom mirror))
    )
    (fp_text user "${REFERENCE}" (at -0.95 -3.168 180) (layer "B.Fab") hide
        (effects (font (size 0.7 0.7) (thickness 0.15)) (justify left bottom mirror))
    )
    (fp_rect (start -0.93 0.47) (end 0.93 -0.47)
      (stroke (width 0.05) (type solid)) (fill none) (layer "B.CrtYd"))
    (fp_rect (start -0.5 0.25) (end 0.5 -0.25)
      (stroke (width 0.15) (type solid)) (fill none) (layer "B.Fab"))
    (pad "1" smd roundrect (at -0.485 0) (size 0.59 0.64) (layers "B.Cu" "B.Paste" "B.Mask") (roundrect_rratio 0.25)
      (net 663 "Net-(U15J-MGTRREF_115)") (pintype "passive"))
    (pad "2" smd roundrect (at 0.485 0) (size 0.59 0.64) (layers "B.Cu" "B.Paste" "B.Mask") (roundrect_rratio 0.25)
      (net 306 "1V2_SYS") (pintype "passive"))
  )

  (footprint "data-center-rdimm-ddr4-tester-footprints:C_0201" (layer "B.Cu")
    (at 174.7 80.075 -90)
    (descr "Capacitor SMD 0201")
    (tags "capacitor SMD 0201")
    (property "Author" "Antmicro")
    (property "Dielectric" "")
    (property "License" "Apache-2.0")
    (property "MPN" "CC0201KRX6S5BB104")
    (property "Manufacturer" "Yaego")
    (property "Sheetfile" "fpga-power.kicad_sch")
    (property "Sheetname" "FPGA power")
    (property "Val" "100n")
    (property "Voltage" "")
    (property "ki_description" " ")
    (attr smd)
    (fp_text reference "C89" (at -1.125 0.4 90) (layer "B.SilkS")
        (effects (font (size 0.7 0.7) (thickness 0.15)) (justify left bottom mirror))
    )
    (fp_text value "C_100n_0201" (at 0 -1.4 90) (layer "B.Fab") hide
        (effects (font (size 0.7 0.7) (thickness 0.15)) (justify left bottom mirror))
    )
    (fp_text user "Author: Antmicro" (at -0.72 -5.4 90) (layer "B.Fab") hide
        (effects (font (size 0.7 0.7) (thickness 0.15)) (justify left bottom mirror))
    )
    (fp_text user "License: Apache-2.0" (at -0.72 -4.4 90) (layer "B.Fab") hide
        (effects (font (size 0.7 0.7) (thickness 0.15)) (justify left bottom mirror))
    )
    (fp_text user "${REFERENCE}" (at -0.72 -3.4 90) (layer "B.Fab") hide
        (effects (font (size 0.7 0.7) (thickness 0.15)) (justify left bottom mirror))
    )
    (fp_rect (start -0.72 0.38) (end 0.72 -0.38)
      (stroke (width 0.05) (type solid)) (fill none) (layer "B.CrtYd"))
    (fp_rect (start 0.3 -0.15) (end -0.301 0.149)
      (stroke (width 0.15) (type solid)) (fill none) (layer "B.Fab"))
    (pad "" smd roundrect (at -0.349 0.002 270) (size 0.318 0.36) (layers "B.Paste") (roundrect_rratio 0.25))
    (pad "" smd roundrect (at 0.341 0.002 270) (size 0.318 0.36) (layers "B.Paste") (roundrect_rratio 0.25))
    (pad "1" smd roundrect (at -0.321 0.002 270) (size 0.46 0.4) (layers "B.Cu" "B.Mask") (roundrect_rratio 0.25)
      (net 143 "3V3_SYS") (pintype "passive"))
    (pad "2" smd roundrect (at 0.32 0.002 270) (size 0.46 0.4) (layers "B.Cu" "B.Mask") (roundrect_rratio 0.25)
      (net 9 "GND") (pintype "passive"))
  )

  (footprint "data-center-rdimm-ddr4-tester-footprints:C_0201" (layer "B.Cu")
    (at 194.2 99.5 180)
    (descr "Capacitor SMD 0201")
    (tags "capacitor SMD 0201")
    (property "Author" "Antmicro")
    (property "Dielectric" "")
    (property "License" "Apache-2.0")
    (property "MPN" "CC0201KRX6S5BB104")
    (property "Manufacturer" "Yaego")
    (property "Sheetfile" "fpga-power.kicad_sch")
    (property "Sheetname" "FPGA power")
    (property "Val" "100n")
    (property "Voltage" "")
    (property "ki_description" " ")
    (attr smd)
    (fp_text reference "C249" (at -3.47 -0.4) (layer "B.SilkS")
        (effects (font (size 0.7 0.7) (thickness 0.15)) (justify left bottom mirror))
    )
    (fp_text value "C_100n_0201" (at 0 -1.4) (layer "B.Fab") hide
        (effects (font (size 0.7 0.7) (thickness 0.15)) (justify left bottom mirror))
    )
    (fp_text user "Author: Antmicro" (at -0.72 -5.4) (layer "B.Fab") hide
        (effects (font (size 0.7 0.7) (thickness 0.15)) (justify left bottom mirror))
    )
    (fp_text user "License: Apache-2.0" (at -0.72 -4.4) (layer "B.Fab") hide
        (effects (font (size 0.7 0.7) (thickness 0.15)) (justify left bottom mirror))
    )
    (fp_text user "${REFERENCE}" (at -0.72 -3.4) (layer "B.Fab") hide
        (effects (font (size 0.7 0.7) (thickness 0.15)) (justify left bottom mirror))
    )
    (fp_rect (start -0.72 0.38) (end 0.72 -0.38)
      (stroke (width 0.05) (type solid)) (fill none) (layer "B.CrtYd"))
    (fp_rect (start 0.3 -0.15) (end -0.301 0.149)
      (stroke (width 0.15) (type solid)) (fill none) (layer "B.Fab"))
    (pad "" smd roundrect (at -0.349 0.002 180) (size 0.318 0.36) (layers "B.Paste") (roundrect_rratio 0.25))
    (pad "" smd roundrect (at 0.341 0.002 180) (size 0.318 0.36) (layers "B.Paste") (roundrect_rratio 0.25))
    (pad "1" smd roundrect (at -0.321 0.002 180) (size 0.46 0.4) (layers "B.Cu" "B.Mask") (roundrect_rratio 0.25)
      (net 306 "1V2_SYS") (pintype "passive"))
    (pad "2" smd roundrect (at 0.32 0.002 180) (size 0.46 0.4) (layers "B.Cu" "B.Mask") (roundrect_rratio 0.25)
      (net 9 "GND") (pintype "passive"))
  )

  (footprint "data-center-rdimm-ddr4-tester-footprints:C_0201" (layer "B.Cu")
    (at 184.4 80.15 -90)
    (descr "Capacitor SMD 0201")
    (tags "capacitor SMD 0201")
    (property "Author" "Antmicro")
    (property "Dielectric" "")
    (property "License" "Apache-2.0")
    (property "MPN" "CC0201KRX6S5BB104")
    (property "Manufacturer" "Yaego")
    (property "Sheetfile" "fpga-power.kicad_sch")
    (property "Sheetname" "FPGA power")
    (property "Val" "100n")
    (property "Voltage" "")
    (property "ki_description" " ")
    (attr smd)
    (fp_text reference "C295" (at -1.12 -1.08 90) (layer "B.SilkS")
        (effects (font (size 0.7 0.7) (thickness 0.15)) (justify left bottom mirror))
    )
    (fp_text value "C_100n_0201" (at 0 -1.4 90) (layer "B.Fab") hide
        (effects (font (size 0.7 0.7) (thickness 0.15)) (justify left bottom mirror))
    )
    (fp_text user "${REFERENCE}" (at -0.72 -3.4 90) (layer "B.Fab") hide
        (effects (font (size 0.7 0.7) (thickness 0.15)) (justify left bottom mirror))
    )
    (fp_text user "License: Apache-2.0" (at -0.72 -4.4 90) (layer "B.Fab") hide
        (effects (font (size 0.7 0.7) (thickness 0.15)) (justify left bottom mirror))
    )
    (fp_text user "Author: Antmicro" (at -0.72 -5.4 90) (layer "B.Fab") hide
        (effects (font (size 0.7 0.7) (thickness 0.15)) (justify left bottom mirror))
    )
    (fp_rect (start -0.72 0.38) (end 0.72 -0.38)
      (stroke (width 0.05) (type solid)) (fill none) (layer "B.CrtYd"))
    (fp_rect (start 0.3 -0.15) (end -0.301 0.149)
      (stroke (width 0.15) (type solid)) (fill none) (layer "B.Fab"))
    (pad "" smd roundrect (at -0.349 0.002 270) (size 0.318 0.36) (layers "B.Paste") (roundrect_rratio 0.25))
    (pad "" smd roundrect (at 0.341 0.002 270) (size 0.318 0.36) (layers "B.Paste") (roundrect_rratio 0.25))
    (pad "1" smd roundrect (at -0.321 0.002 270) (size 0.46 0.4) (layers "B.Cu" "B.Mask") (roundrect_rratio 0.25)
      (net 77 "VDDQ") (pintype "passive"))
    (pad "2" smd roundrect (at 0.32 0.002 270) (size 0.46 0.4) (layers "B.Cu" "B.Mask") (roundrect_rratio 0.25)
      (net 9 "GND") (pintype "passive"))
  )

  (footprint "data-center-rdimm-ddr4-tester-footprints:C_0603_1608Metric" (layer "B.Cu")
    (at 189.725 82.775 90)
    (descr "Capacitor SMD 0603")
    (tags "capacitor 0603")
    (property "Author" "Antmicro")
    (property "Dielectric" "")
    (property "License" "Apache-2.0")
    (property "MPN" "GRM188R60J476ME15D")
    (property "Manufacturer" "Murata")
    (property "Sheetfile" "fpga-power.kicad_sch")
    (property "Sheetname" "FPGA power")
    (property "Val" "47u")
    (property "Voltage" "")
    (property "ki_description" " ")
    (attr smd)
    (fp_text reference "C80" (at 1.085 -0.575 270) (layer "B.SilkS")
        (effects (font (size 0.7 0.7) (thickness 0.15)) (justify left bottom mirror))
    )
    (fp_text value "C_47u_0603" (at 0 -1.6 270) (layer "B.Fab") hide
        (effects (font (size 0.7 0.7) (thickness 0.15)) (justify left bottom mirror))
    )
    (fp_text user "Author: Antmicro" (at -1.682 -4.894 270) (layer "B.Fab") hide
        (effects (font (size 0.7 0.7) (thickness 0.15)) (justify left bottom mirror))
    )
    (fp_text user "${REFERENCE}" (at -1.682 -3.895 270) (layer "B.Fab") hide
        (effects (font (size 0.7 0.7) (thickness 0.15)) (justify left bottom mirror))
    )
    (fp_text user "License: Apache-2.0" (at -1.682 -5.895 270) (layer "B.Fab") hide
        (effects (font (size 0.7 0.7) (thickness 0.15)) (justify left bottom mirror))
    )
    (fp_line (start -0.3 -0.3) (end 0.3 -0.3)
      (stroke (width 0.15) (type solid)) (layer "B.SilkS"))
    (fp_line (start -0.3 0.3) (end 0.3 0.3)
      (stroke (width 0.15) (type solid)) (layer "B.SilkS"))
    (fp_rect (start -1.24 0.7) (end 1.24 -0.7)
      (stroke (width 0.05) (type solid)) (fill none) (layer "B.CrtYd"))
    (fp_rect (start -0.8 0.4) (end 0.8 -0.4)
      (stroke (width 0.15) (type solid)) (fill none) (layer "B.Fab"))
    (pad "1" smd roundrect (at -0.7 0 90) (size 0.6 0.8) (layers "B.Cu" "B.Paste" "B.Mask") (roundrect_rratio 0.2)
      (net 77 "VDDQ") (pintype "passive"))
    (pad "2" smd roundrect (at 0.7 0 90) (size 0.6 0.8) (layers "B.Cu" "B.Paste" "B.Mask") (roundrect_rratio 0.2)
      (net 9 "GND") (pintype "passive"))
  )

  (footprint "data-center-rdimm-ddr4-tester-footprints:R_0402_1005Metric" (layer "B.Cu")
    (at 185.65 129.9 180)
    (descr "Resistor SMD 0402")
    (tags "resistor SMD 0402")
    (property "Author" "Antmicro")
    (property "Current" "1A")
    (property "License" "Apache-2.0")
    (property "MPN" "ERJ2GE0R00X")
    (property "Manufacturer" "Panasonic")
    (property "Sheetfile" "ethernet.kicad_sch")
    (property "Sheetname" "Ethernet")
    (property "Tolerance" "")
    (property "Val" "0R")
    (property "ki_description" "0R resistor in 0402 package with unspecified tolerance")
    (attr smd)
    (fp_text reference "R161" (at -3.72 -0.35) (layer "B.SilkS")
        (effects (font (size 0.7 0.7) (thickness 0.15)) (justify left bottom mirror))
    )
    (fp_text value "R_0R_0402" (at 0 -1.4) (layer "B.Fab") hide
        (effects (font (size 0.7 0.7) (thickness 0.15)) (justify left bottom mirror))
    )
    (fp_text user "License: Apache-2.0" (at -0.95 -5.169) (layer "B.Fab") hide
        (effects (font (size 0.7 0.7) (thickness 0.15)) (justify left bottom mirror))
    )
    (fp_text user "${REFERENCE}" (at -0.95 -3.168) (layer "B.Fab") hide
        (effects (font (size 0.7 0.7) (thickness 0.15)) (justify left bottom mirror))
    )
    (fp_text user "Author: Antmicro" (at -0.95 -4.169) (layer "B.Fab") hide
        (effects (font (size 0.7 0.7) (thickness 0.15)) (justify left bottom mirror))
    )
    (fp_rect (start -0.93 0.47) (end 0.93 -0.47)
      (stroke (width 0.05) (type solid)) (fill none) (layer "B.CrtYd"))
    (fp_rect (start -0.5 0.25) (end 0.5 -0.25)
      (stroke (width 0.15) (type solid)) (fill none) (layer "B.Fab"))
    (pad "1" smd roundrect (at -0.485 0 180) (size 0.59 0.64) (layers "B.Cu" "B.Paste" "B.Mask") (roundrect_rratio 0.25)
      (net 381 "/Ethernet/VSS") (pintype "passive"))
    (pad "2" smd roundrect (at 0.485 0 180) (size 0.59 0.64) (layers "B.Cu" "B.Paste" "B.Mask") (roundrect_rratio 0.25)
      (net 629 "/Ethernet/MPS_DUTY") (pintype "passive"))
  )

  (footprint "data-center-rdimm-ddr4-tester-footprints:C_0201" (layer "B.Cu")
    (at 171.075 97.05 90)
    (descr "Capacitor SMD 0201")
    (tags "capacitor SMD 0201")
    (property "Author" "Antmicro")
    (property "Dielectric" "")
    (property "License" "Apache-2.0")
    (property "MPN" "CC0201KRX6S5BB104")
    (property "Manufacturer" "Yaego")
    (property "Sheetfile" "fpga-power.kicad_sch")
    (property "Sheetname" "FPGA power")
    (property "Val" "100n")
    (property "Voltage" "")
    (property "ki_description" " ")
    (attr smd)
    (fp_text reference "C87" (at 1.11 -0.425 270) (layer "B.SilkS")
        (effects (font (size 0.7 0.7) (thickness 0.15)) (justify left bottom mirror))
    )
    (fp_text value "C_100n_0201" (at 0 -1.4 270) (layer "B.Fab") hide
        (effects (font (size 0.7 0.7) (thickness 0.15)) (justify left bottom mirror))
    )
    (fp_text user "${REFERENCE}" (at -0.72 -3.4 270) (layer "B.Fab") hide
        (effects (font (size 0.7 0.7) (thickness 0.15)) (justify left bottom mirror))
    )
    (fp_text user "License: Apache-2.0" (at -0.72 -4.4 270) (layer "B.Fab") hide
        (effects (font (size 0.7 0.7) (thickness 0.15)) (justify left bottom mirror))
    )
    (fp_text user "Author: Antmicro" (at -0.72 -5.4 270) (layer "B.Fab") hide
        (effects (font (size 0.7 0.7) (thickness 0.15)) (justify left bottom mirror))
    )
    (fp_rect (start -0.72 0.38) (end 0.72 -0.38)
      (stroke (width 0.05) (type solid)) (fill none) (layer "B.CrtYd"))
    (fp_rect (start 0.3 -0.15) (end -0.301 0.149)
      (stroke (width 0.15) (type solid)) (fill none) (layer "B.Fab"))
    (pad "" smd roundrect (at -0.349 0.002 90) (size 0.318 0.36) (layers "B.Paste") (roundrect_rratio 0.25))
    (pad "" smd roundrect (at 0.341 0.002 90) (size 0.318 0.36) (layers "B.Paste") (roundrect_rratio 0.25))
    (pad "1" smd roundrect (at -0.321 0.002 90) (size 0.46 0.4) (layers "B.Cu" "B.Mask") (roundrect_rratio 0.25)
      (net 143 "3V3_SYS") (pintype "passive"))
    (pad "2" smd roundrect (at 0.32 0.002 90) (size 0.46 0.4) (layers "B.Cu" "B.Mask") (roundrect_rratio 0.25)
      (net 9 "GND") (pintype "passive"))
  )

  (footprint "data-center-rdimm-ddr4-tester-footprints:C_0201" (layer "B.Cu")
    (at 174.07 99.27 90)
    (descr "Capacitor SMD 0201")
    (tags "capacitor SMD 0201")
    (property "Author" "Antmicro")
    (property "Dielectric" "")
    (property "License" "Apache-2.0")
    (property "MPN" "CC0201KRX6S5BB104")
    (property "Manufacturer" "Yaego")
    (property "Sheetfile" "fpga-power.kicad_sch")
    (property "Sheetname" "FPGA power")
    (property "Val" "100n")
    (property "Voltage" "")
    (property "ki_description" " ")
    (attr smd)
    (fp_text reference "C302" (at 1.33 1.18 270) (layer "B.SilkS")
        (effects (font (size 0.7 0.7) (thickness 0.15)) (justify left bottom mirror))
    )
    (fp_text value "C_100n_0201" (at 0 -1.4 270) (layer "B.Fab") hide
        (effects (font (size 0.7 0.7) (thickness 0.15)) (justify left bottom mirror))
    )
    (fp_text user "${REFERENCE}" (at -0.72 -3.4 270) (layer "B.Fab") hide
        (effects (font (size 0.7 0.7) (thickness 0.15)) (justify left bottom mirror))
    )
    (fp_text user "Author: Antmicro" (at -0.72 -5.4 270) (layer "B.Fab") hide
        (effects (font (size 0.7 0.7) (thickness 0.15)) (justify left bottom mirror))
    )
    (fp_text user "License: Apache-2.0" (at -0.72 -4.4 270) (layer "B.Fab") hide
        (effects (font (size 0.7 0.7) (thickness 0.15)) (justify left bottom mirror))
    )
    (fp_rect (start -0.72 0.38) (end 0.72 -0.38)
      (stroke (width 0.05) (type solid)) (fill none) (layer "B.CrtYd"))
    (fp_rect (start 0.3 -0.15) (end -0.301 0.149)
      (stroke (width 0.15) (type solid)) (fill none) (layer "B.Fab"))
    (pad "" smd roundrect (at -0.349 0.002 90) (size 0.318 0.36) (layers "B.Paste") (roundrect_rratio 0.25))
    (pad "" smd roundrect (at 0.341 0.002 90) (size 0.318 0.36) (layers "B.Paste") (roundrect_rratio 0.25))
    (pad "1" smd roundrect (at -0.321 0.002 90) (size 0.46 0.4) (layers "B.Cu" "B.Mask") (roundrect_rratio 0.25)
      (net 143 "3V3_SYS") (pintype "passive"))
    (pad "2" smd roundrect (at 0.32 0.002 90) (size 0.46 0.4) (layers "B.Cu" "B.Mask") (roundrect_rratio 0.25)
      (net 9 "GND") (pintype "passive"))
  )

  (footprint "data-center-rdimm-ddr4-tester-footprints:C_0201" (layer "B.Cu")
    (at 192.15 98.65)
    (descr "Capacitor SMD 0201")
    (tags "capacitor SMD 0201")
    (property "Author" "Antmicro")
    (property "Dielectric" "")
    (property "License" "Apache-2.0")
    (property "MPN" "CC0201KRX6S5BB104")
    (property "Manufacturer" "Yaego")
    (property "Sheetfile" "fpga-power.kicad_sch")
    (property "Sheetname" "FPGA power")
    (property "Val" "100n")
    (property "Voltage" "")
    (property "ki_description" " ")
    (attr smd)
    (fp_text reference "C242" (at 3.48 0.22 180) (layer "B.SilkS")
        (effects (font (size 0.7 0.7) (thickness 0.15)) (justify left bottom mirror))
    )
    (fp_text value "C_100n_0201" (at 0 -1.4 180) (layer "B.Fab") hide
        (effects (font (size 0.7 0.7) (thickness 0.15)) (justify left bottom mirror))
    )
    (fp_text user "${REFERENCE}" (at -0.72 -3.4 180) (layer "B.Fab") hide
        (effects (font (size 0.7 0.7) (thickness 0.15)) (justify left bottom mirror))
    )
    (fp_text user "Author: Antmicro" (at -0.72 -5.4 180) (layer "B.Fab") hide
        (effects (font (size 0.7 0.7) (thickness 0.15)) (justify left bottom mirror))
    )
    (fp_text user "License: Apache-2.0" (at -0.72 -4.4 180) (layer "B.Fab") hide
        (effects (font (size 0.7 0.7) (thickness 0.15)) (justify left bottom mirror))
    )
    (fp_rect (start -0.72 0.38) (end 0.72 -0.38)
      (stroke (width 0.05) (type solid)) (fill none) (layer "B.CrtYd"))
    (fp_rect (start 0.3 -0.15) (end -0.301 0.149)
      (stroke (width 0.15) (type solid)) (fill none) (layer "B.Fab"))
    (pad "" smd roundrect (at -0.349 0.002) (size 0.318 0.36) (layers "B.Paste") (roundrect_rratio 0.25))
    (pad "" smd roundrect (at 0.341 0.002) (size 0.318 0.36) (layers "B.Paste") (roundrect_rratio 0.25))
    (pad "1" smd roundrect (at -0.321 0.002) (size 0.46 0.4) (layers "B.Cu" "B.Mask") (roundrect_rratio 0.25)
      (net 147 "1V0_SYS") (pintype "passive"))
    (pad "2" smd roundrect (at 0.32 0.002) (size 0.46 0.4) (layers "B.Cu" "B.Mask") (roundrect_rratio 0.25)
      (net 9 "GND") (pintype "passive"))
  )

  (footprint "data-center-rdimm-ddr4-tester-footprints:SC70-3" (layer "B.Cu")
    (at 238.9 80.4)
    (property "Author" "Antmicro")
    (property "License" "Apache-2.0")
    (property "MPN" "BSS138PW")
    (property "Manufacturer" "Nexperia")
    (property "Sheetfile" "interfaces.kicad_sch")
    (property "Sheetname" "Interfaces")
    (property "ki_description" "60 V, 320 mA N-channel enhancement mode Trench MOSFET, SC-70-3 aka SOT-323 package")
    (property "ki_keywords" "n-channel enhancement mosfet sc70 sc-70 sot-323 sot323")
    (attr smd)
    (fp_text reference "Q9" (at -1.35 0.41 180) (layer "B.SilkS")
        (effects (font (size 0.7 0.7) (thickness 0.15)) (justify left bottom mirror))
    )
    (fp_text value "BSS138PW" (at 0 -2.3 180) (layer "B.Fab") hide
        (effects (font (size 0.7 0.7) (thickness 0.15)) (justify left bottom mirror))
    )
    (fp_text user "License: Apache-2.0" (at -1.45 -6.782 180) (layer "B.Fab") hide
        (effects (font (size 0.7 0.7) (thickness 0.15)) (justify left bottom mirror))
    )
    (fp_text user "Author: Antmicro" (at -1.45 -5.782 180) (layer "B.Fab") hide
        (effects (font (size 0.7 0.7) (thickness 0.15)) (justify left bottom mirror))
    )
    (fp_text user "${REFERENCE}" (at -1.45 -4.783 180) (layer "B.Fab") hide
        (effects (font (size 0.7 0.7) (thickness 0.15)) (justify left bottom mirror))
    )
    (fp_line (start -0.3 -1) (end 0.627 -1.001)
      (stroke (width 0.15) (type solid)) (layer "B.SilkS"))
    (fp_line (start -0.3 1) (end 0.627 0.999)
      (stroke (width 0.15) (type solid)) (layer "B.SilkS"))
    (fp_line (start 0.627 -0.6) (end 0.627 -1.001)
      (stroke (width 0.15) (type solid)) (layer "B.SilkS"))
    (fp_line (start 0.627 0.6) (end 0.627 0.999)
      (stroke (width 0.15) (type solid)) (layer "B.SilkS"))
    (fp_rect (start 1.4 -1.3) (end -1.4 1.3)
      (stroke (width 0.05) (type solid)) (fill none) (layer "B.CrtYd"))
    (fp_rect (start -0.623 0.999) (end 0.627 -1.001)
      (stroke (width 0.15) (type solid)) (fill none) (layer "B.Fab"))
    (pad "1" smd rect (at -0.95 0.65 270) (size 0.6 0.8) (layers "B.Cu" "B.Paste" "B.Mask")
      (net 786 "HOT_SWAP_GREEN") (pinfunction "G") (pintype "bidirectional"))
    (pad "2" smd rect (at -0.95 -0.65 270) (size 0.6 0.8) (layers "B.Cu" "B.Paste" "B.Mask")
      (net 9 "GND") (pinfunction "S") (pintype "bidirectional"))
    (pad "3" smd rect (at 0.95 0 270) (size 0.6 0.8) (layers "B.Cu" "B.Paste" "B.Mask")
      (net 581 "Net-(Q9-D)") (pinfunction "D") (pintype "bidirectional"))
  )

  (footprint "data-center-rdimm-ddr4-tester-footprints:R_0603_1608Metric" (layer "B.Cu")
    (at 185.5 128.65 180)
    (descr "Resistor SMD 0603")
    (tags "resistor SMD 0603")
    (property "Author" "Antmicro")
    (property "License" "Apache-2.0")
    (property "MPN" "CR0603-FX-1301ELF")
    (property "Manufacturer" "Bourns")
    (property "Sheetfile" "ethernet.kicad_sch")
    (property "Sheetname" "Ethernet")
    (property "Tolerance" "1%")
    (property "Val" "1k3")
    (property "ki_description" "1k3 resistor in 0603 package with 1% tolerance")
    (attr smd)
    (fp_text reference "R156" (at -3.96 -0.36) (layer "B.SilkS")
        (effects (font (size 0.7 0.7) (thickness 0.15)) (justify left bottom mirror))
    )
    (fp_text value "R_1k3_0603" (at 0 -1.6) (layer "B.Fab") hide
        (effects (font (size 0.7 0.7) (thickness 0.15)) (justify left bottom mirror))
    )
    (fp_text user "License: Apache-2.0" (at -1.25 -5.9) (layer "B.Fab") hide
        (effects (font (size 0.7 0.7) (thickness 0.15)) (justify left bottom mirror))
    )
    (fp_text user "${REFERENCE}" (at -1.25 -3.898) (layer "B.Fab") hide
        (effects (font (size 0.7 0.7) (thickness 0.15)) (justify left bottom mirror))
    )
    (fp_text user "Author: Antmicro" (at -1.25 -4.9) (layer "B.Fab") hide
        (effects (font (size 0.7 0.7) (thickness 0.15)) (justify left bottom mirror))
    )
    (fp_line (start -0.3 -0.3) (end 0.3 -0.3)
      (stroke (width 0.15) (type solid)) (layer "B.SilkS"))
    (fp_line (start -0.3 0.3) (end 0.3 0.3)
      (stroke (width 0.15) (type solid)) (layer "B.SilkS"))
    (fp_rect (start -1.25 0.7) (end 1.25 -0.7)
      (stroke (width 0.05) (type solid)) (fill none) (layer "B.CrtYd"))
    (fp_rect (start -0.8 0.4) (end 0.8 -0.4)
      (stroke (width 0.15) (type solid)) (fill none) (layer "B.Fab"))
    (pad "1" smd roundrect (at -0.7 0 180) (size 0.6 0.8) (layers "B.Cu" "B.Paste" "B.Mask") (roundrect_rratio 0.2)
      (net 381 "/Ethernet/VSS") (pintype "passive"))
    (pad "2" smd roundrect (at 0.7 0 180) (size 0.6 0.8) (layers "B.Cu" "B.Paste" "B.Mask") (roundrect_rratio 0.2)
      (net 612 "/Ethernet/AMPS_CTL") (pintype "passive"))
  )

  (footprint "data-center-rdimm-ddr4-tester-footprints:C_0201" (layer "B.Cu")
    (at 170.02 101.98 -90)
    (descr "Capacitor SMD 0201")
    (tags "capacitor SMD 0201")
    (property "Author" "Antmicro")
    (property "Dielectric" "")
    (property "License" "Apache-2.0")
    (property "MPN" "CC0201KRX6S5BB104")
    (property "Manufacturer" "Yaego")
    (property "Sheetfile" "fpga-power.kicad_sch")
    (property "Sheetname" "FPGA power")
    (property "Val" "100n")
    (property "Voltage" "")
    (property "ki_description" " ")
    (attr smd)
    (fp_text reference "C306" (at -1.42 0.44 90) (layer "B.SilkS")
        (effects (font (size 0.7 0.7) (thickness 0.15)) (justify left bottom mirror))
    )
    (fp_text value "C_100n_0201" (at 0 -1.4 90) (layer "B.Fab") hide
        (effects (font (size 0.7 0.7) (thickness 0.15)) (justify left bottom mirror))
    )
    (fp_text user "${REFERENCE}" (at -0.72 -3.4 90) (layer "B.Fab") hide
        (effects (font (size 0.7 0.7) (thickness 0.15)) (justify left bottom mirror))
    )
    (fp_text user "License: Apache-2.0" (at -0.72 -4.4 90) (layer "B.Fab") hide
        (effects (font (size 0.7 0.7) (thickness 0.15)) (justify left bottom mirror))
    )
    (fp_text user "Author: Antmicro" (at -0.72 -5.4 90) (layer "B.Fab") hide
        (effects (font (size 0.7 0.7) (thickness 0.15)) (justify left bottom mirror))
    )
    (fp_rect (start -0.72 0.38) (end 0.72 -0.38)
      (stroke (width 0.05) (type solid)) (fill none) (layer "B.CrtYd"))
    (fp_rect (start 0.3 -0.15) (end -0.301 0.149)
      (stroke (width 0.15) (type solid)) (fill none) (layer "B.Fab"))
    (pad "" smd roundrect (at -0.349 0.002 270) (size 0.318 0.36) (layers "B.Paste") (roundrect_rratio 0.25))
    (pad "" smd roundrect (at 0.341 0.002 270) (size 0.318 0.36) (layers "B.Paste") (roundrect_rratio 0.25))
    (pad "1" smd roundrect (at -0.321 0.002 270) (size 0.46 0.4) (layers "B.Cu" "B.Mask") (roundrect_rratio 0.25)
      (net 143 "3V3_SYS") (pintype "passive"))
    (pad "2" smd roundrect (at 0.32 0.002 270) (size 0.46 0.4) (layers "B.Cu" "B.Mask") (roundrect_rratio 0.25)
      (net 9 "GND") (pintype "passive"))
  )

  (footprint "data-center-rdimm-ddr4-tester-footprints:C_0402_1005Metric" (layer "B.Cu")
    (at 119.535 91.1175 180)
    (descr "Capacitor SMD 0402")
    (tags "capacitor SMD 0402")
    (property "Author" "Antmicro")
    (property "Dielectric" "X5R")
    (property "License" "Apache-2.0")
    (property "MPN" "GRM155R61H104KE14D")
    (property "Manufacturer" "Murata")
    (property "Sheetfile" "supply.kicad_sch")
    (property "Sheetname" "Supply")
    (property "Val" "100n")
    (property "Voltage" "50V")
    (property "ki_description" " ")
    (attr smd)
    (fp_text reference "C234" (at -1.395 -1.3225) (layer "B.SilkS")
        (effects (font (size 0.7 0.7) (thickness 0.15)) (justify left bottom mirror))
    )
    (fp_text value "C_100n_0402" (at 0 -1.4) (layer "B.Fab") hide
        (effects (font (size 0.7 0.7) (thickness 0.15)) (justify left bottom mirror))
    )
    (fp_text user "License: Apache-2.0" (at -0.932 -5.17) (layer "B.Fab") hide
        (effects (font (size 0.7 0.7) (thickness 0.15)) (justify left bottom mirror))
    )
    (fp_text user "${REFERENCE}" (at -0.932 -3.168) (layer "B.Fab") hide
        (effects (font (size 0.7 0.7) (thickness 0.15)) (justify left bottom mirror))
    )
    (fp_text user "Author: Antmicro" (at -0.932 -4.17) (layer "B.Fab") hide
        (effects (font (size 0.7 0.7) (thickness 0.15)) (justify left bottom mirror))
    )
    (fp_rect (start -0.94 0.47) (end 0.94 -0.47)
      (stroke (width 0.05) (type solid)) (fill none) (layer "B.CrtYd"))
    (fp_rect (start -0.499 0.249) (end 0.499 -0.249)
      (stroke (width 0.15) (type solid)) (fill none) (layer "B.Fab"))
    (pad "1" smd roundrect (at -0.484 0 180) (size 0.59 0.64) (layers "B.Cu" "B.Paste" "B.Mask") (roundrect_rratio 0.25)
      (net 143 "3V3_SYS") (pintype "passive"))
    (pad "2" smd roundrect (at 0.484 0 180) (size 0.59 0.64) (layers "B.Cu" "B.Paste" "B.Mask") (roundrect_rratio 0.25)
      (net 9 "GND") (pintype "passive"))
  )

  (footprint "data-center-rdimm-ddr4-tester-footprints:SOD-123F" (layer "B.Cu")
    (at 180.91 122.95)
    (property "Author" "Antmicro")
    (property "License" "Apache-2.0")
    (property "MPN" "PTVS58VS1UR,115")
    (property "Manufacturer" "Nexperia")
    (property "Sheetfile" "ethernet.kicad_sch")
    (property "Sheetname" "Ethernet")
    (property "ki_description" "400 W Transient Voltage Suppressor")
    (property "ki_keywords" "400 W Transient Voltage Suppressor")
    (attr smd)
    (fp_text reference "D14" (at 8.08 -3.2 180) (layer "B.SilkS")
        (effects (font (size 0.7 0.7) (thickness 0.15)) (justify left bottom mirror))
    )
    (fp_text value "PTVS58VS1UR,115" (at 0 -2.1 180) (layer "B.Fab") hide
        (effects (font (size 0.7 0.7) (thickness 0.15)) (justify left bottom mirror))
    )
    (fp_text user "License: Apache-2.0" (at -2.202 -6.2 180) (layer "B.Fab") hide
        (effects (font (size 0.7 0.7) (thickness 0.15)) (justify left bottom mirror))
    )
    (fp_text user "Author: Antmicro" (at -2.202 -4.998 180) (layer "B.Fab") hide
        (effects (font (size 0.7 0.7) (thickness 0.15)) (justify left bottom mirror))
    )
    (fp_text user "${REFERENCE}" (at -2.202 -3.798 180) (layer "B.Fab") hide
        (effects (font (size 0.7 0.7) (thickness 0.15)) (justify left bottom mirror))
    )
    (fp_line (start -0.7 0.8) (end -0.7 -0.8)
      (stroke (width 0.15) (type solid)) (layer "B.SilkS"))
    (fp_line (start -2.21 -1.1) (end -2.21 1.1)
      (stroke (width 0.05) (type solid)) (layer "B.CrtYd"))
    (fp_line (start 2.2 -1.1) (end -2.21 -1.1)
      (stroke (width 0.05) (type solid)) (layer "B.CrtYd"))
    (fp_line (start 2.2 1.1) (end -2.21 1.1)
      (stroke (width 0.05) (type solid)) (layer "B.CrtYd"))
    (fp_line (start 2.2 1.1) (end 2.2 -1.1)
      (stroke (width 0.05) (type solid)) (layer "B.CrtYd"))
    (fp_line (start -0.8 0.8) (end -0.8 -0.8)
      (stroke (width 0.1) (type solid)) (layer "B.Fab"))
    (fp_rect (start -1.75 0.802) (end 1.749 -0.8)
      (stroke (width 0.1) (type solid)) (fill none) (layer "B.Fab"))
    (pad "A" smd roundrect (at 1.398 0) (size 1.2 1.2) (layers "B.Cu" "B.Paste" "B.Mask") (roundrect_rratio 0.25)
      (net 381 "/Ethernet/VSS") (pinfunction "A") (pintype "passive"))
    (pad "K" smd roundrect (at -1.401 0) (size 1.2 1.2) (layers "B.Cu" "B.Paste" "B.Mask") (roundrect_rratio 0.25)
      (net 360 "/Ethernet/VDD") (pinfunction "C") (pintype "passive"))
  )

  (footprint "data-center-rdimm-ddr4-tester-footprints:C_0201" (layer "B.Cu")
    (at 174.825 81.65 180)
    (descr "Capacitor SMD 0201")
    (tags "capacitor SMD 0201")
    (property "Author" "Antmicro")
    (property "Dielectric" "")
    (property "License" "Apache-2.0")
    (property "MPN" "CC0201KRX6S5BB104")
    (property "Manufacturer" "Yaego")
    (property "Sheetfile" "fpga-power.kicad_sch")
    (property "Sheetname" "FPGA power")
    (property "Val" "100n")
    (property "Voltage" "")
    (property "ki_description" " ")
    (attr smd)
    (fp_text reference "C92" (at 0.505 -0.39) (layer "B.SilkS")
        (effects (font (size 0.7 0.7) (thickness 0.15)) (justify left bottom mirror))
    )
    (fp_text value "C_100n_0201" (at 0 -1.4) (layer "B.Fab") hide
        (effects (font (size 0.7 0.7) (thickness 0.15)) (justify left bottom mirror))
    )
    (fp_text user "${REFERENCE}" (at -0.72 -3.4) (layer "B.Fab") hide
        (effects (font (size 0.7 0.7) (thickness 0.15)) (justify left bottom mirror))
    )
    (fp_text user "License: Apache-2.0" (at -0.72 -4.4) (layer "B.Fab") hide
        (effects (font (size 0.7 0.7) (thickness 0.15)) (justify left bottom mirror))
    )
    (fp_text user "Author: Antmicro" (at -0.72 -5.4) (layer "B.Fab") hide
        (effects (font (size 0.7 0.7) (thickness 0.15)) (justify left bottom mirror))
    )
    (fp_rect (start -0.72 0.38) (end 0.72 -0.38)
      (stroke (width 0.05) (type solid)) (fill none) (layer "B.CrtYd"))
    (fp_rect (start 0.3 -0.15) (end -0.301 0.149)
      (stroke (width 0.15) (type solid)) (fill none) (layer "B.Fab"))
    (pad "" smd roundrect (at -0.349 0.002 180) (size 0.318 0.36) (layers "B.Paste") (roundrect_rratio 0.25))
    (pad "" smd roundrect (at 0.341 0.002 180) (size 0.318 0.36) (layers "B.Paste") (roundrect_rratio 0.25))
    (pad "1" smd roundrect (at -0.321 0.002 180) (size 0.46 0.4) (layers "B.Cu" "B.Mask") (roundrect_rratio 0.25)
      (net 143 "3V3_SYS") (pintype "passive"))
    (pad "2" smd roundrect (at 0.32 0.002 180) (size 0.46 0.4) (layers "B.Cu" "B.Mask") (roundrect_rratio 0.25)
      (net 9 "GND") (pintype "passive"))
  )

  (footprint "data-center-rdimm-ddr4-tester-footprints:SC70-3" (layer "B.Cu")
    (at 238.9 83.1)
    (property "Author" "Antmicro")
    (property "License" "Apache-2.0")
    (property "MPN" "BSS138PW")
    (property "Manufacturer" "Nexperia")
    (property "Sheetfile" "interfaces.kicad_sch")
    (property "Sheetname" "Interfaces")
    (property "ki_description" "60 V, 320 mA N-channel enhancement mode Trench MOSFET, SC-70-3 aka SOT-323 package")
    (property "ki_keywords" "n-channel enhancement mosfet sc70 sc-70 sot-323 sot323")
    (attr smd)
    (fp_text reference "Q1" (at -1.35 0.41 180) (layer "B.SilkS")
        (effects (font (size 0.7 0.7) (thickness 0.15)) (justify left bottom mirror))
    )
    (fp_text value "BSS138PW" (at 0 -2.3 180) (layer "B.Fab") hide
        (effects (font (size 0.7 0.7) (thickness 0.15)) (justify left bottom mirror))
    )
    (fp_text user "${REFERENCE}" (at -1.45 -4.783 180) (layer "B.Fab") hide
        (effects (font (size 0.7 0.7) (thickness 0.15)) (justify left bottom mirror))
    )
    (fp_text user "License: Apache-2.0" (at -1.45 -6.782 180) (layer "B.Fab") hide
        (effects (font (size 0.7 0.7) (thickness 0.15)) (justify left bottom mirror))
    )
    (fp_text user "Author: Antmicro" (at -1.45 -5.782 180) (layer "B.Fab") hide
        (effects (font (size 0.7 0.7) (thickness 0.15)) (justify left bottom mirror))
    )
    (fp_line (start -0.3 -1) (end 0.627 -1.001)
      (stroke (width 0.15) (type solid)) (layer "B.SilkS"))
    (fp_line (start -0.3 1) (end 0.627 0.999)
      (stroke (width 0.15) (type solid)) (layer "B.SilkS"))
    (fp_line (start 0.627 -0.6) (end 0.627 -1.001)
      (stroke (width 0.15) (type solid)) (layer "B.SilkS"))
    (fp_line (start 0.627 0.6) (end 0.627 0.999)
      (stroke (width 0.15) (type solid)) (layer "B.SilkS"))
    (fp_rect (start 1.4 -1.3) (end -1.4 1.3)
      (stroke (width 0.05) (type solid)) (fill none) (layer "B.CrtYd"))
    (fp_rect (start -0.623 0.999) (end 0.627 -1.001)
      (stroke (width 0.15) (type solid)) (fill none) (layer "B.Fab"))
    (pad "1" smd rect (at -0.95 0.65 270) (size 0.6 0.8) (layers "B.Cu" "B.Paste" "B.Mask")
      (net 784 "HOT_SWAP_YELLOW") (pinfunction "G") (pintype "bidirectional"))
    (pad "2" smd rect (at -0.95 -0.65 270) (size 0.6 0.8) (layers "B.Cu" "B.Paste" "B.Mask")
      (net 9 "GND") (pinfunction "S") (pintype "bidirectional"))
    (pad "3" smd rect (at 0.95 0 270) (size 0.6 0.8) (layers "B.Cu" "B.Paste" "B.Mask")
      (net 573 "Net-(Q1-D)") (pinfunction "D") (pintype "bidirectional"))
  )

  (footprint "data-center-rdimm-ddr4-tester-footprints:Fiducial_1mm_Mask2mm" (layer "B.Cu")
    (at 113 129.5 180)
    (descr "Circular Fiducial, 1mm bare copper, 3mm soldermask opening")
    (tags "fiducial")
    (property "Author" "Antmicro")
    (property "License" "Apache-2.0")
    (property "MPN" "")
    (property "Manufacturer" "")
    (property "Sheetfile" "data-center-rdimm-ddr4-tester.kicad_sch")
    (property "Sheetname" "")
    (property "exclude_from_bom" "")
    (property "ki_description" "Fiducial Marker for use with single board only")
    (attr exclude_from_pos_files exclude_from_bom)
    (fp_text reference "FID5" (at -1.06 1.37) (layer "B.SilkS")
        (effects (font (size 0.7 0.7) (thickness 0.15)) (justify left bottom mirror))
    )
    (fp_text value "Fiducial_1mm_Mask2mm" (at 0 -2.2) (layer "B.Fab") hide
        (effects (font (size 0.7 0.7) (thickness 0.15)) (justify left bottom mirror))
    )
    (fp_text user "${REFERENCE}" (at -1.25 -4.603) (layer "B.Fab") hide
        (effects (font (size 0.7 0.7) (thickness 0.15)) (justify left bottom mirror))
    )
    (fp_text user "License: Apache-2.0" (at -1.25 -7.003) (layer "B.Fab") hide
        (effects (font (size 0.7 0.7) (thickness 0.15)) (justify left bottom mirror))
    )
    (fp_text user "Author: Antmicro" (at -1.25 -5.803) (layer "B.Fab") hide
        (effects (font (size 0.7 0.7) (thickness 0.15)) (justify left bottom mirror))
    )
    (fp_circle (center 0 0) (end 1.24 0)
      (stroke (width 0.05) (type solid)) (fill none) (layer "B.CrtYd"))
    (fp_circle (center 0 0) (end 0.999 0)
      (stroke (width 0.15) (type solid)) (fill none) (layer "B.Fab"))
    (pad "" smd circle (at 0 0 180) (size 1 1) (layers "B.Cu" "B.Mask")
      (solder_mask_margin 0.5) (clearance 0.5))
  )

  (footprint "data-center-rdimm-ddr4-tester-footprints:R_0402_1005Metric" (layer "B.Cu")
    (at 117.725 95.45 90)
    (descr "Resistor SMD 0402")
    (tags "resistor SMD 0402")
    (property "Author" "Antmicro")
    (property "License" "Apache-2.0")
    (property "MPN" "CR0402-FX-1003GLF")
    (property "Manufacturer" "Bourns")
    (property "Sheetfile" "supply.kicad_sch")
    (property "Sheetname" "Supply")
    (property "Tolerance" "1%")
    (property "Val" "100k")
    (property "ki_description" "100k resistor in 0402 package with 1% tolerance")
    (attr smd)
    (fp_text reference "R214" (at 1.83 -0.545 270) (layer "B.SilkS")
        (effects (font (size 0.7 0.7) (thickness 0.15)) (justify left bottom mirror))
    )
    (fp_text value "R_100k_0402" (at 0 -1.4 270) (layer "B.Fab") hide
        (effects (font (size 0.7 0.7) (thickness 0.15)) (justify left bottom mirror))
    )
    (fp_text user "Author: Antmicro" (at -0.95 -4.169 270) (layer "B.Fab") hide
        (effects (font (size 0.7 0.7) (thickness 0.15)) (justify left bottom mirror))
    )
    (fp_text user "License: Apache-2.0" (at -0.95 -5.169 270) (layer "B.Fab") hide
        (effects (font (size 0.7 0.7) (thickness 0.15)) (justify left bottom mirror))
    )
    (fp_text user "${REFERENCE}" (at -0.95 -3.168 270) (layer "B.Fab") hide
        (effects (font (size 0.7 0.7) (thickness 0.15)) (justify left bottom mirror))
    )
    (fp_rect (start -0.93 0.47) (end 0.93 -0.47)
      (stroke (width 0.05) (type solid)) (fill none) (layer "B.CrtYd"))
    (fp_rect (start -0.5 0.25) (end 0.5 -0.25)
      (stroke (width 0.15) (type solid)) (fill none) (layer "B.Fab"))
    (pad "1" smd roundrect (at -0.485 0 90) (size 0.59 0.64) (layers "B.Cu" "B.Paste" "B.Mask") (roundrect_rratio 0.25)
      (net 9 "GND") (pintype "passive"))
    (pad "2" smd roundrect (at 0.485 0 90) (size 0.59 0.64) (layers "B.Cu" "B.Paste" "B.Mask") (roundrect_rratio 0.25)
      (net 799 "FPGA_SLP_S4") (pintype "passive"))
  )

  (footprint "data-center-rdimm-ddr4-tester-footprints:DFN3538" (layer "B.Cu")
    (at 177.21 119.7 90)
    (property "Author" "Antmicro")
    (property "License" "Apache-2.0")
    (property "MPN" "CD-MMBL110S")
    (property "Manufacturer" "Bourns")
    (property "Sheetfile" "ethernet.kicad_sch")
    (property "Sheetname" "Ethernet")
    (property "ki_description" "Bridge Rectifiers 1000V 1A MMBL DFN3538")
    (attr smd)
    (fp_text reference "D13" (at 2.27 1.07 unlocked) (layer "B.SilkS")
        (effects (font (size 0.7 0.7) (thickness 0.15)) (justify left bottom mirror))
    )
    (fp_text value "CD-MMBL110S" (at 0 -3.5 270 unlocked) (layer "B.Fab") hide
        (effects (font (size 0.7 0.7) (thickness 0.15)) (justify left bottom mirror))
    )
    (fp_text user "~" (at -0.31 -2.59 270 unlocked) (layer "B.SilkS")
        (effects (font (size 0.7 0.7) (thickness 0.15)) (justify left bottom mirror))
    )
    (fp_text user "Author: Antmicro" (at -2.1 -5.599 270) (layer "B.Fab") hide
        (effects (font (size 0.7 0.7) (thickness 0.15)) (justify left bottom mirror))
    )
    (fp_text user "${REFERENCE}" (at -2.1 -4.599 270) (layer "B.Fab") hide
        (effects (font (size 0.7 0.7) (thickness 0.15)) (justify left bottom mirror))
    )
    (fp_text user "License: Apache-2.0" (at -2.1 -6.599 270) (layer "B.Fab") hide
        (effects (font (size 0.7 0.7) (thickness 0.15)) (justify left bottom mirror))
    )
    (fp_line (start -1.8 -2.05) (end -1.6 -2.05)
      (stroke (width 0.15) (type solid)) (layer "B.SilkS"))
    (fp_line (start -1.8 1.5) (end -1.8 -2.05)
      (stroke (width 0.15) (type solid)) (layer "B.SilkS"))
    (fp_line (start -0.95 -2.05) (end 0.95 -2.05)
      (stroke (width 0.15) (type solid)) (layer "B.SilkS"))
    (fp_line (start -0.95 2) (end 0.95 2)
      (stroke (width 0.15) (type solid)) (layer "B.SilkS"))
    (fp_line (start -0.902 2.25) (end -0.6 2.25)
      (stroke (width 0.15) (type solid)) (layer "B.SilkS"))
    (fp_line (start 0.748 2.452) (end 0.748 2.15)
      (stroke (width 0.15) (type solid)) (layer "B.SilkS"))
    (fp_line (start 0.9 2.301) (end 0.598 2.301)
      (stroke (width 0.15) (type solid)) (layer "B.SilkS"))
    (fp_line (start 1.6 -2.05) (end 1.8 -2.05)
      (stroke (width 0.15) (type solid)) (layer "B.SilkS"))
    (fp_line (start 1.6 2) (end 1.8 2)
      (stroke (width 0.15) (type solid)) (layer "B.SilkS"))
    (fp_line (start 1.8 2) (end 1.8 -2.05)
      (stroke (width 0.15) (type solid)) (layer "B.SilkS"))
    (fp_rect (start -2.1 2.6) (end 2.1 -2.6)
      (stroke (width 0.05) (type solid)) (fill none) (layer "B.CrtYd"))
    (fp_line (start -1.051 2) (end -1.801 1.25)
      (stroke (width 0.15) (type solid)) (layer "B.Fab"))
    (fp_rect (start 1.8 -2.048) (end -1.8 2)
      (stroke (width 0.15) (type solid)) (fill none) (layer "B.Fab"))
    (pad "1" smd roundrect (at -1.27 1.85) (size 1.4 0.48) (layers "B.Cu" "B.Paste" "B.Mask") (roundrect_rratio 0.25)
      (net 807 "/Ethernet/VSS_RAW") (pinfunction "1") (pintype "output"))
    (pad "2" smd roundrect (at 1.27 1.85) (size 1.4 0.48) (layers "B.Cu" "B.Paste" "B.Mask") (roundrect_rratio 0.25)
      (net 808 "/Ethernet/VDD_RAW") (pinfunction "2") (pintype "output"))
    (pad "3" smd roundrect (at -1.27 -1.85) (size 1.4 0.48) (layers "B.Cu" "B.Paste" "B.Mask") (roundrect_rratio 0.25)
      (net 607 "/Ethernet/PAIR_78") (pinfunction "3") (pintype "input"))
    (pad "4" smd roundrect (at 1.27 -1.85) (size 1.4 0.48) (layers "B.Cu" "B.Paste" "B.Mask") (roundrect_rratio 0.25)
      (net 608 "/Ethernet/PAIR_910") (pinfunction "4") (pintype "input"))
  )

  (footprint "data-center-rdimm-ddr4-tester-footprints:R_0402_1005Metric" (layer "B.Cu")
    (at 241.4 82.5 180)
    (descr "Resistor SMD 0402")
    (tags "resistor SMD 0402")
    (property "Author" "Antmicro")
    (property "License" "Apache-2.0")
    (property "MPN" "CR0402-FX-3300GLF")
    (property "Manufacturer" "Bourns")
    (property "Sheetfile" "interfaces.kicad_sch")
    (property "Sheetname" "Interfaces")
    (property "Tolerance" "1%")
    (property "Val" "330R")
    (property "ki_description" "330R resistor in 0402 package with 1% tolerance")
    (attr smd)
    (fp_text reference "R187" (at -1.67 -1.31) (layer "B.SilkS")
        (effects (font (size 0.7 0.7) (thickness 0.15)) (justify left bottom mirror))
    )
    (fp_text value "R_330R_0402" (at 0 -1.4) (layer "B.Fab") hide
        (effects (font (size 0.7 0.7) (thickness 0.15)) (justify left bottom mirror))
    )
    (fp_text user "Author: Antmicro" (at -0.95 -4.169) (layer "B.Fab") hide
        (effects (font (size 0.7 0.7) (thickness 0.15)) (justify left bottom mirror))
    )
    (fp_text user "${REFERENCE}" (at -0.95 -3.168) (layer "B.Fab") hide
        (effects (font (size 0.7 0.7) (thickness 0.15)) (justify left bottom mirror))
    )
    (fp_text user "License: Apache-2.0" (at -0.95 -5.169) (layer "B.Fab") hide
        (effects (font (size 0.7 0.7) (thickness 0.15)) (justify left bottom mirror))
    )
    (fp_rect (start -0.93 0.47) (end 0.93 -0.47)
      (stroke (width 0.05) (type solid)) (fill none) (layer "B.CrtYd"))
    (fp_rect (start -0.5 0.25) (end 0.5 -0.25)
      (stroke (width 0.15) (type solid)) (fill none) (layer "B.Fab"))
    (pad "1" smd roundrect (at -0.485 0 180) (size 0.59 0.64) (layers "B.Cu" "B.Paste" "B.Mask") (roundrect_rratio 0.25)
      (net 106 "Net-(D17-C_{Y})") (pintype "passive"))
    (pad "2" smd roundrect (at 0.485 0 180) (size 0.59 0.64) (layers "B.Cu" "B.Paste" "B.Mask") (roundrect_rratio 0.25)
      (net 573 "Net-(Q1-D)") (pintype "passive"))
  )

  (footprint "data-center-rdimm-ddr4-tester-footprints:C_0402_1005Metric" (layer "B.Cu")
    (at 231.8 126.3 90)
    (descr "Capacitor SMD 0402")
    (tags "capacitor SMD 0402")
    (property "Author" "Antmicro")
    (property "Dielectric" "")
    (property "License" "Apache-2.0")
    (property "MPN" "C1005X6S1A105K050BC")
    (property "Manufacturer" "TDK")
    (property "Sheetfile" "supply.kicad_sch")
    (property "Sheetname" "Supply")
    (property "Val" "1u")
    (property "Voltage" "")
    (property "ki_description" " ")
    (attr smd)
    (fp_text reference "C281" (at 1.34 1.3 270) (layer "B.SilkS")
        (effects (font (size 0.7 0.7) (thickness 0.15)) (justify left bottom mirror))
    )
    (fp_text value "C_1u_0402" (at 0 -1.4 270) (layer "B.Fab") hide
        (effects (font (size 0.7 0.7) (thickness 0.15)) (justify left bottom mirror))
    )
    (fp_text user "${REFERENCE}" (at -0.932 -3.168 270) (layer "B.Fab") hide
        (effects (font (size 0.7 0.7) (thickness 0.15)) (justify left bottom mirror))
    )
    (fp_text user "Author: Antmicro" (at -0.932 -4.17 270) (layer "B.Fab") hide
        (effects (font (size 0.7 0.7) (thickness 0.15)) (justify left bottom mirror))
    )
    (fp_text user "License: Apache-2.0" (at -0.932 -5.17 270) (layer "B.Fab") hide
        (effects (font (size 0.7 0.7) (thickness 0.15)) (justify left bottom mirror))
    )
    (fp_rect (start -0.94 0.47) (end 0.94 -0.47)
      (stroke (width 0.05) (type solid)) (fill none) (layer "B.CrtYd"))
    (fp_rect (start -0.499 0.249) (end 0.499 -0.249)
      (stroke (width 0.15) (type solid)) (fill none) (layer "B.Fab"))
    (pad "1" smd roundrect (at -0.484 0 90) (size 0.59 0.64) (layers "B.Cu" "B.Paste" "B.Mask") (roundrect_rratio 0.25)
      (net 846 "5V_ON_OFF") (pintype "passive"))
    (pad "2" smd roundrect (at 0.484 0 90) (size 0.59 0.64) (layers "B.Cu" "B.Paste" "B.Mask") (roundrect_rratio 0.25)
      (net 9 "GND") (pintype "passive"))
  )

  (footprint "data-center-rdimm-ddr4-tester-footprints:C_0603_1608Metric" (layer "B.Cu")
    (at 182.075 98.175)
    (descr "Capacitor SMD 0603")
    (tags "capacitor 0603")
    (property "Author" "Antmicro")
    (property "Dielectric" "")
    (property "License" "Apache-2.0")
    (property "MPN" "GRM188R60J476ME15D")
    (property "Manufacturer" "Murata")
    (property "Sheetfile" "fpga-power.kicad_sch")
    (property "Sheetname" "FPGA power")
    (property "Val" "47u")
    (property "Voltage" "")
    (property "ki_description" " ")
    (attr smd)
    (fp_text reference "C78" (at 1.535 -0.555 180) (layer "B.SilkS")
        (effects (font (size 0.7 0.7) (thickness 0.15)) (justify left bottom mirror))
    )
    (fp_text value "C_47u_0603" (at 0 -1.6 180) (layer "B.Fab") hide
        (effects (font (size 0.7 0.7) (thickness 0.15)) (justify left bottom mirror))
    )
    (fp_text user "Author: Antmicro" (at -1.682 -4.894 180) (layer "B.Fab") hide
        (effects (font (size 0.7 0.7) (thickness 0.15)) (justify left bottom mirror))
    )
    (fp_text user "${REFERENCE}" (at -1.682 -3.895 180) (layer "B.Fab") hide
        (effects (font (size 0.7 0.7) (thickness 0.15)) (justify left bottom mirror))
    )
    (fp_text user "License: Apache-2.0" (at -1.682 -5.895 180) (layer "B.Fab") hide
        (effects (font (size 0.7 0.7) (thickness 0.15)) (justify left bottom mirror))
    )
    (fp_line (start -0.3 -0.3) (end 0.3 -0.3)
      (stroke (width 0.15) (type solid)) (layer "B.SilkS"))
    (fp_line (start -0.3 0.3) (end 0.3 0.3)
      (stroke (width 0.15) (type solid)) (layer "B.SilkS"))
    (fp_rect (start -1.24 0.7) (end 1.24 -0.7)
      (stroke (width 0.05) (type solid)) (fill none) (layer "B.CrtYd"))
    (fp_rect (start -0.8 0.4) (end 0.8 -0.4)
      (stroke (width 0.15) (type solid)) (fill none) (layer "B.Fab"))
    (pad "1" smd roundrect (at -0.7 0) (size 0.6 0.8) (layers "B.Cu" "B.Paste" "B.Mask") (roundrect_rratio 0.2)
      (net 143 "3V3_SYS") (pintype "passive"))
    (pad "2" smd roundrect (at 0.7 0) (size 0.6 0.8) (layers "B.Cu" "B.Paste" "B.Mask") (roundrect_rratio 0.2)
      (net 9 "GND") (pintype "passive"))
  )

  (footprint "data-center-rdimm-ddr4-tester-footprints:C_0201" (layer "B.Cu")
    (at 191.6 100.725)
    (descr "Capacitor SMD 0201")
    (tags "capacitor SMD 0201")
    (property "Author" "Antmicro")
    (property "Dielectric" "")
    (property "License" "Apache-2.0")
    (property "MPN" "CC0201KRX6S5BB104")
    (property "Manufacturer" "Yaego")
    (property "Sheetfile" "fpga-power.kicad_sch")
    (property "Sheetname" "FPGA power")
    (property "Val" "100n")
    (property "Voltage" "")
    (property "ki_description" " ")
    (attr smd)
    (fp_text reference "C241" (at 3.26 0.385 180) (layer "B.SilkS")
        (effects (font (size 0.7 0.7) (thickness 0.15)) (justify left bottom mirror))
    )
    (fp_text value "C_100n_0201" (at 0 -1.4 180) (layer "B.Fab") hide
        (effects (font (size 0.7 0.7) (thickness 0.15)) (justify left bottom mirror))
    )
    (fp_text user "Author: Antmicro" (at -0.72 -5.4 180) (layer "B.Fab") hide
        (effects (font (size 0.7 0.7) (thickness 0.15)) (justify left bottom mirror))
    )
    (fp_text user "License: Apache-2.0" (at -0.72 -4.4 180) (layer "B.Fab") hide
        (effects (font (size 0.7 0.7) (thickness 0.15)) (justify left bottom mirror))
    )
    (fp_text user "${REFERENCE}" (at -0.72 -3.4 180) (layer "B.Fab") hide
        (effects (font (size 0.7 0.7) (thickness 0.15)) (justify left bottom mirror))
    )
    (fp_rect (start -0.72 0.38) (end 0.72 -0.38)
      (stroke (width 0.05) (type solid)) (fill none) (layer "B.CrtYd"))
    (fp_rect (start 0.3 -0.15) (end -0.301 0.149)
      (stroke (width 0.15) (type solid)) (fill none) (layer "B.Fab"))
    (pad "" smd roundrect (at -0.349 0.002) (size 0.318 0.36) (layers "B.Paste") (roundrect_rratio 0.25))
    (pad "" smd roundrect (at 0.341 0.002) (size 0.318 0.36) (layers "B.Paste") (roundrect_rratio 0.25))
    (pad "1" smd roundrect (at -0.321 0.002) (size 0.46 0.4) (layers "B.Cu" "B.Mask") (roundrect_rratio 0.25)
      (net 147 "1V0_SYS") (pintype "passive"))
    (pad "2" smd roundrect (at 0.32 0.002) (size 0.46 0.4) (layers "B.Cu" "B.Mask") (roundrect_rratio 0.25)
      (net 9 "GND") (pintype "passive"))
  )

  (footprint "data-center-rdimm-ddr4-tester-footprints:C_0201" (layer "B.Cu")
    (at 192.475 93.525)
    (descr "Capacitor SMD 0201")
    (tags "capacitor SMD 0201")
    (property "Author" "Antmicro")
    (property "Dielectric" "")
    (property "License" "Apache-2.0")
    (property "MPN" "CC0201KRX6S5BB104")
    (property "Manufacturer" "Yaego")
    (property "Sheetfile" "fpga-power.kicad_sch")
    (property "Sheetname" "FPGA power")
    (property "Val" "100n")
    (property "Voltage" "")
    (property "ki_description" " ")
    (attr smd)
    (fp_text reference "C240" (at 3.355 0.495 180) (layer "B.SilkS")
        (effects (font (size 0.7 0.7) (thickness 0.15)) (justify left bottom mirror))
    )
    (fp_text value "C_100n_0201" (at 0 -1.4 180) (layer "B.Fab") hide
        (effects (font (size 0.7 0.7) (thickness 0.15)) (justify left bottom mirror))
    )
    (fp_text user "License: Apache-2.0" (at -0.72 -4.4 180) (layer "B.Fab") hide
        (effects (font (size 0.7 0.7) (thickness 0.15)) (justify left bottom mirror))
    )
    (fp_text user "${REFERENCE}" (at -0.72 -3.4 180) (layer "B.Fab") hide
        (effects (font (size 0.7 0.7) (thickness 0.15)) (justify left bottom mirror))
    )
    (fp_text user "Author: Antmicro" (at -0.72 -5.4 180) (layer "B.Fab") hide
        (effects (font (size 0.7 0.7) (thickness 0.15)) (justify left bottom mirror))
    )
    (fp_rect (start -0.72 0.38) (end 0.72 -0.38)
      (stroke (width 0.05) (type solid)) (fill none) (layer "B.CrtYd"))
    (fp_rect (start 0.3 -0.15) (end -0.301 0.149)
      (stroke (width 0.15) (type solid)) (fill none) (layer "B.Fab"))
    (pad "" smd roundrect (at -0.349 0.002) (size 0.318 0.36) (layers "B.Paste") (roundrect_rratio 0.25))
    (pad "" smd roundrect (at 0.341 0.002) (size 0.318 0.36) (layers "B.Paste") (roundrect_rratio 0.25))
    (pad "1" smd roundrect (at -0.321 0.002) (size 0.46 0.4) (layers "B.Cu" "B.Mask") (roundrect_rratio 0.25)
      (net 147 "1V0_SYS") (pintype "passive"))
    (pad "2" smd roundrect (at 0.32 0.002) (size 0.46 0.4) (layers "B.Cu" "B.Mask") (roundrect_rratio 0.25)
      (net 9 "GND") (pintype "passive"))
  )

  (footprint "data-center-rdimm-ddr4-tester-footprints:R_0603_1608Metric" (layer "B.Cu")
    (at 114.3 114.1 90)
    (descr "Resistor SMD 0603")
    (tags "resistor SMD 0603")
    (property "Author" "Antmicro")
    (property "License" "Apache-2.0")
    (property "MPN" "ERJ-UP3F3300V")
    (property "Manufacturer" "Panasonic")
    (property "Sheetfile" "supply.kicad_sch")
    (property "Sheetname" "Supply")
    (property "Tolerance" "1%")
    (property "Val" "330R")
    (property "ki_description" "330R resistor in 0603 package with 1% tolerance")
    (attr smd)
    (fp_text reference "R114" (at 1.3 1.52 270) (layer "B.SilkS")
        (effects (font (size 0.7 0.7) (thickness 0.15)) (justify left bottom mirror))
    )
    (fp_text value "R_330R_0.25W_0603" (at 0 -1.6 270) (layer "B.Fab") hide
        (effects (font (size 0.7 0.7) (thickness 0.15)) (justify left bottom mirror))
    )
    (fp_text user "License: Apache-2.0" (at -1.25 -5.9 270) (layer "B.Fab") hide
        (effects (font (size 0.7 0.7) (thickness 0.15)) (justify left bottom mirror))
    )
    (fp_text user "${REFERENCE}" (at -1.25 -3.898 270) (layer "B.Fab") hide
        (effects (font (size 0.7 0.7) (thickness 0.15)) (justify left bottom mirror))
    )
    (fp_text user "Author: Antmicro" (at -1.25 -4.9 270) (layer "B.Fab") hide
        (effects (font (size 0.7 0.7) (thickness 0.15)) (justify left bottom mirror))
    )
    (fp_line (start -0.3 -0.3) (end 0.3 -0.3)
      (stroke (width 0.15) (type solid)) (layer "B.SilkS"))
    (fp_line (start -0.3 0.3) (end 0.3 0.3)
      (stroke (width 0.15) (type solid)) (layer "B.SilkS"))
    (fp_rect (start -1.25 0.7) (end 1.25 -0.7)
      (stroke (width 0.05) (type solid)) (fill none) (layer "B.CrtYd"))
    (fp_rect (start -0.8 0.4) (end 0.8 -0.4)
      (stroke (width 0.15) (type solid)) (fill none) (layer "B.Fab"))
    (pad "1" smd roundrect (at -0.7 0 90) (size 0.6 0.8) (layers "B.Cu" "B.Paste" "B.Mask") (roundrect_rratio 0.2)
      (net 857 "Net-(R114-Pad1)") (pintype "passive"))
    (pad "2" smd roundrect (at 0.7 0 90) (size 0.6 0.8) (layers "B.Cu" "B.Paste" "B.Mask") (roundrect_rratio 0.2)
      (net 143 "3V3_SYS") (pintype "passive"))
  )

  (footprint "data-center-rdimm-ddr4-tester-footprints:R_0402_1005Metric" (layer "B.Cu")
    (at 241.4 78.4 180)
    (descr "Resistor SMD 0402")
    (tags "resistor SMD 0402")
    (property "Author" "Antmicro")
    (property "License" "Apache-2.0")
    (property "MPN" "CR0402-FX-3300GLF")
    (property "Manufacturer" "Bourns")
    (property "Sheetfile" "interfaces.kicad_sch")
    (property "Sheetname" "Interfaces")
    (property "Tolerance" "1%")
    (property "Val" "330R")
    (property "ki_description" "330R resistor in 0402 package with 1% tolerance")
    (attr smd)
    (fp_text reference "R189" (at -1.64 -1.25) (layer "B.SilkS")
        (effects (font (size 0.7 0.7) (thickness 0.15)) (justify left bottom mirror))
    )
    (fp_text value "R_330R_0402" (at 0 -1.4) (layer "B.Fab") hide
        (effects (font (size 0.7 0.7) (thickness 0.15)) (justify left bottom mirror))
    )
    (fp_text user "Author: Antmicro" (at -0.95 -4.169) (layer "B.Fab") hide
        (effects (font (size 0.7 0.7) (thickness 0.15)) (justify left bottom mirror))
    )
    (fp_text user "${REFERENCE}" (at -0.95 -3.168) (layer "B.Fab") hide
        (effects (font (size 0.7 0.7) (thickness 0.15)) (justify left bottom mirror))
    )
    (fp_text user "License: Apache-2.0" (at -0.95 -5.169) (layer "B.Fab") hide
        (effects (font (size 0.7 0.7) (thickness 0.15)) (justify left bottom mirror))
    )
    (fp_rect (start -0.93 0.47) (end 0.93 -0.47)
      (stroke (width 0.05) (type solid)) (fill none) (layer "B.CrtYd"))
    (fp_rect (start -0.5 0.25) (end 0.5 -0.25)
      (stroke (width 0.15) (type solid)) (fill none) (layer "B.Fab"))
    (pad "1" smd roundrect (at -0.485 0 180) (size 0.59 0.64) (layers "B.Cu" "B.Paste" "B.Mask") (roundrect_rratio 0.25)
      (net 101 "Net-(D17-C_{R})") (pintype "passive"))
    (pad "2" smd roundrect (at 0.485 0 180) (size 0.59 0.64) (layers "B.Cu" "B.Paste" "B.Mask") (roundrect_rratio 0.25)
      (net 582 "Net-(Q10-D)") (pintype "passive"))
  )

  (footprint "data-center-rdimm-ddr4-tester-footprints:C_0201" (layer "B.Cu")
    (at 175.225 94.075 -90)
    (descr "Capacitor SMD 0201")
    (tags "capacitor SMD 0201")
    (property "Author" "Antmicro")
    (property "Dielectric" "")
    (property "License" "Apache-2.0")
    (property "MPN" "CC0201KRX6S5BB104")
    (property "Manufacturer" "Yaego")
    (property "Sheetfile" "fpga-power.kicad_sch")
    (property "Sheetname" "FPGA power")
    (property "Val" "100n")
    (property "Voltage" "")
    (property "ki_description" " ")
    (attr smd)
    (fp_text reference "C95" (at -2.845 -0.395 90) (layer "B.SilkS")
        (effects (font (size 0.7 0.7) (thickness 0.15)) (justify left bottom mirror))
    )
    (fp_text value "C_100n_0201" (at 0 -1.4 90) (layer "B.Fab") hide
        (effects (font (size 0.7 0.7) (thickness 0.15)) (justify left bottom mirror))
    )
    (fp_text user "License: Apache-2.0" (at -0.72 -4.4 90) (layer "B.Fab") hide
        (effects (font (size 0.7 0.7) (thickness 0.15)) (justify left bottom mirror))
    )
    (fp_text user "Author: Antmicro" (at -0.72 -5.4 90) (layer "B.Fab") hide
        (effects (font (size 0.7 0.7) (thickness 0.15)) (justify left bottom mirror))
    )
    (fp_text user "${REFERENCE}" (at -0.72 -3.4 90) (layer "B.Fab") hide
        (effects (font (size 0.7 0.7) (thickness 0.15)) (justify left bottom mirror))
    )
    (fp_rect (start -0.72 0.38) (end 0.72 -0.38)
      (stroke (width 0.05) (type solid)) (fill none) (layer "B.CrtYd"))
    (fp_rect (start 0.3 -0.15) (end -0.301 0.149)
      (stroke (width 0.15) (type solid)) (fill none) (layer "B.Fab"))
    (pad "" smd roundrect (at -0.349 0.002 270) (size 0.318 0.36) (layers "B.Paste") (roundrect_rratio 0.25))
    (pad "" smd roundrect (at 0.341 0.002 270) (size 0.318 0.36) (layers "B.Paste") (roundrect_rratio 0.25))
    (pad "1" smd roundrect (at -0.321 0.002 270) (size 0.46 0.4) (layers "B.Cu" "B.Mask") (roundrect_rratio 0.25)
      (net 143 "3V3_SYS") (pintype "passive"))
    (pad "2" smd roundrect (at 0.32 0.002 270) (size 0.46 0.4) (layers "B.Cu" "B.Mask") (roundrect_rratio 0.25)
      (net 9 "GND") (pintype "passive"))
  )

  (footprint "data-center-rdimm-ddr4-tester-footprints:C_2220_5650Metric" (layer "B.Cu")
    (at 195.05 120.05)
    (descr "Capacitor SMD 2220")
    (tags "capacitor SMD 2220")
    (property "Author" "Antmicro")
    (property "Dielectric" "")
    (property "License" "Apache-2.0")
    (property "MPN" "C5750X7S2A226M280KB")
    (property "Manufacturer" "TDK")
    (property "Sheetfile" "ethernet.kicad_sch")
    (property "Sheetname" "Ethernet")
    (property "Val" "22u/100V")
    (property "Voltage" "")
    (property "ki_description" " ")
    (attr smd)
    (fp_text reference "C224" (at 4.5 -1.39 270) (layer "B.SilkS")
        (effects (font (size 0.7 0.7) (thickness 0.15)) (justify left bottom mirror))
    )
    (fp_text value "C_22u_100V_2220" (at 0 -3.9 180) (layer "B.Fab") hide
        (effects (font (size 0.7 0.7) (thickness 0.15)) (justify left bottom mirror))
    )
    (fp_text user "${REFERENCE}" (at -3.7 -5.9 180) (layer "B.Fab") hide
        (effects (font (size 0.7 0.7) (thickness 0.15)) (justify left bottom mirror))
    )
    (fp_text user "License: Apache-2.0" (at -3.7 -6.9 180) (layer "B.Fab") hide
        (effects (font (size 0.7 0.7) (thickness 0.15)) (justify left bottom mirror))
    )
    (fp_text user "Author: Antmicro" (at -3.7 -7.9 180) (layer "B.Fab") hide
        (effects (font (size 0.7 0.7) (thickness 0.15)) (justify left bottom mirror))
    )
    (fp_line (start -1.415 -2.61) (end 1.415 -2.61)
      (stroke (width 0.15) (type solid)) (layer "B.SilkS"))
    (fp_line (start -1.415 2.61) (end 1.415 2.61)
      (stroke (width 0.15) (type solid)) (layer "B.SilkS"))
    (fp_rect (start -3.7 2.95) (end 3.7 -2.95)
      (stroke (width 0.05) (type solid)) (fill none) (layer "B.CrtYd"))
    (fp_rect (start -2.85 2.5) (end 2.85 -2.5)
      (stroke (width 0.15) (type solid)) (fill none) (layer "B.Fab"))
    (pad "1" smd roundrect (at -2.55 0) (size 1.8 5.4) (layers "B.Cu" "B.Paste" "B.Mask") (roundrect_rratio 0.138889)
      (net 360 "/Ethernet/VDD") (pintype "passive"))
    (pad "2" smd roundrect (at 2.55 0) (size 1.8 5.4) (layers "B.Cu" "B.Paste" "B.Mask") (roundrect_rratio 0.138889)
      (net 604 "GNDD") (pintype "passive"))
  )

  (footprint "data-center-rdimm-ddr4-tester-footprints:R_0402_1005Metric" (layer "B.Cu")
    (at 123.715 90.096)
    (descr "Resistor SMD 0402")
    (tags "resistor SMD 0402")
    (property "Author" "Antmicro")
    (property "License" "Apache-2.0")
    (property "MPN" "CR0402-FX-1002GLF")
    (property "Manufacturer" "Bourns")
    (property "Sheetfile" "supply.kicad_sch")
    (property "Sheetname" "Supply")
    (property "Tolerance" "1%")
    (property "Val" "10k")
    (property "ki_description" "10k resistor in 0402 package with 1% tolerance")
    (attr smd)
    (fp_text reference "R195" (at 1.205 1.614 180) (layer "B.SilkS")
        (effects (font (size 0.7 0.7) (thickness 0.15)) (justify left bottom mirror))
    )
    (fp_text value "R_10k_0402" (at 0 -1.4 180) (layer "B.Fab") hide
        (effects (font (size 0.7 0.7) (thickness 0.15)) (justify left bottom mirror))
    )
    (fp_text user "Author: Antmicro" (at -0.95 -4.169 180) (layer "B.Fab") hide
        (effects (font (size 0.7 0.7) (thickness 0.15)) (justify left bottom mirror))
    )
    (fp_text user "${REFERENCE}" (at -0.95 -3.168 180) (layer "B.Fab") hide
        (effects (font (size 0.7 0.7) (thickness 0.15)) (justify left bottom mirror))
    )
    (fp_text user "License: Apache-2.0" (at -0.95 -5.169 180) (layer "B.Fab") hide
        (effects (font (size 0.7 0.7) (thickness 0.15)) (justify left bottom mirror))
    )
    (fp_rect (start -0.93 0.47) (end 0.93 -0.47)
      (stroke (width 0.05) (type solid)) (fill none) (layer "B.CrtYd"))
    (fp_rect (start -0.5 0.25) (end 0.5 -0.25)
      (stroke (width 0.15) (type solid)) (fill none) (layer "B.Fab"))
    (pad "1" smd roundrect (at -0.485 0) (size 0.59 0.64) (layers "B.Cu" "B.Paste" "B.Mask") (roundrect_rratio 0.25)
      (net 143 "3V3_SYS") (pintype "passive"))
    (pad "2" smd roundrect (at 0.485 0) (size 0.59 0.64) (layers "B.Cu" "B.Paste" "B.Mask") (roundrect_rratio 0.25)
      (net 661 "Net-(U20-~{PWRDN})") (pintype "passive"))
  )

  (footprint "data-center-rdimm-ddr4-tester-footprints:C_0201" (layer "B.Cu")
    (at 194.35 91.5 180)
    (descr "Capacitor SMD 0201")
    (tags "capacitor SMD 0201")
    (property "Author" "Antmicro")
    (property "Dielectric" "")
    (property "License" "Apache-2.0")
    (property "MPN" "CC0201KRX6S5BB104")
    (property "Manufacturer" "Yaego")
    (property "Sheetfile" "fpga-power.kicad_sch")
    (property "Sheetname" "FPGA power")
    (property "Val" "100n")
    (property "Voltage" "")
    (property "ki_description" " ")
    (attr smd)
    (fp_text reference "C254" (at -4.39 -0.2) (layer "B.SilkS")
        (effects (font (size 0.7 0.7) (thickness 0.15)) (justify left bottom mirror))
    )
    (fp_text value "C_100n_0201" (at 0 -1.4) (layer "B.Fab") hide
        (effects (font (size 0.7 0.7) (thickness 0.15)) (justify left bottom mirror))
    )
    (fp_text user "${REFERENCE}" (at -0.72 -3.4) (layer "B.Fab") hide
        (effects (font (size 0.7 0.7) (thickness 0.15)) (justify left bottom mirror))
    )
    (fp_text user "License: Apache-2.0" (at -0.72 -4.4) (layer "B.Fab") hide
        (effects (font (size 0.7 0.7) (thickness 0.15)) (justify left bottom mirror))
    )
    (fp_text user "Author: Antmicro" (at -0.72 -5.4) (layer "B.Fab") hide
        (effects (font (size 0.7 0.7) (thickness 0.15)) (justify left bottom mirror))
    )
    (fp_rect (start -0.72 0.38) (end 0.72 -0.38)
      (stroke (width 0.05) (type solid)) (fill none) (layer "B.CrtYd"))
    (fp_rect (start 0.3 -0.15) (end -0.301 0.149)
      (stroke (width 0.15) (type solid)) (fill none) (layer "B.Fab"))
    (pad "" smd roundrect (at -0.349 0.002 180) (size 0.318 0.36) (layers "B.Paste") (roundrect_rratio 0.25))
    (pad "" smd roundrect (at 0.341 0.002 180) (size 0.318 0.36) (layers "B.Paste") (roundrect_rratio 0.25))
    (pad "1" smd roundrect (at -0.321 0.002 180) (size 0.46 0.4) (layers "B.Cu" "B.Mask") (roundrect_rratio 0.25)
      (net 306 "1V2_SYS") (pintype "passive"))
    (pad "2" smd roundrect (at 0.32 0.002 180) (size 0.46 0.4) (layers "B.Cu" "B.Mask") (roundrect_rratio 0.25)
      (net 9 "GND") (pintype "passive"))
  )

  (footprint "data-center-rdimm-ddr4-tester-footprints:C_0201" (layer "B.Cu")
    (at 193.2 87.375)
    (descr "Capacitor SMD 0201")
    (tags "capacitor SMD 0201")
    (property "Author" "Antmicro")
    (property "Dielectric" "")
    (property "License" "Apache-2.0")
    (property "MPN" "CC0201KRX6S5BB104")
    (property "Manufacturer" "Yaego")
    (property "Sheetfile" "fpga-power.kicad_sch")
    (property "Sheetname" "FPGA power")
    (property "Val" "100n")
    (property "Voltage" "")
    (property "ki_description" " ")
    (attr smd)
    (fp_text reference "C300" (at 3.52 0.365 180) (layer "B.SilkS")
        (effects (font (size 0.7 0.7) (thickness 0.15)) (justify left bottom mirror))
    )
    (fp_text value "C_100n_0201" (at 0 -1.4 180) (layer "B.Fab") hide
        (effects (font (size 0.7 0.7) (thickness 0.15)) (justify left bottom mirror))
    )
    (fp_text user "${REFERENCE}" (at -0.72 -3.4 180) (layer "B.Fab") hide
        (effects (font (size 0.7 0.7) (thickness 0.15)) (justify left bottom mirror))
    )
    (fp_text user "Author: Antmicro" (at -0.72 -5.4 180) (layer "B.Fab") hide
        (effects (font (size 0.7 0.7) (thickness 0.15)) (justify left bottom mirror))
    )
    (fp_text user "License: Apache-2.0" (at -0.72 -4.4 180) (layer "B.Fab") hide
        (effects (font (size 0.7 0.7) (thickness 0.15)) (justify left bottom mirror))
    )
    (fp_rect (start -0.72 0.38) (end 0.72 -0.38)
      (stroke (width 0.05) (type solid)) (fill none) (layer "B.CrtYd"))
    (fp_rect (start 0.3 -0.15) (end -0.301 0.149)
      (stroke (width 0.15) (type solid)) (fill none) (layer "B.Fab"))
    (pad "" smd roundrect (at -0.349 0.002) (size 0.318 0.36) (layers "B.Paste") (roundrect_rratio 0.25))
    (pad "" smd roundrect (at 0.341 0.002) (size 0.318 0.36) (layers "B.Paste") (roundrect_rratio 0.25))
    (pad "1" smd roundrect (at -0.321 0.002) (size 0.46 0.4) (layers "B.Cu" "B.Mask") (roundrect_rratio 0.25)
      (net 143 "3V3_SYS") (pintype "passive"))
    (pad "2" smd roundrect (at 0.32 0.002) (size 0.46 0.4) (layers "B.Cu" "B.Mask") (roundrect_rratio 0.25)
      (net 9 "GND") (pintype "passive"))
  )

  (footprint "data-center-rdimm-ddr4-tester-footprints:C_0201" (layer "B.Cu")
    (at 175.325 84.675 180)
    (descr "Capacitor SMD 0201")
    (tags "capacitor SMD 0201")
    (property "Author" "Antmicro")
    (property "Dielectric" "")
    (property "License" "Apache-2.0")
    (property "MPN" "CC0201KRX6S5BB104")
    (property "Manufacturer" "Yaego")
    (property "Sheetfile" "fpga-power.kicad_sch")
    (property "Sheetname" "FPGA power")
    (property "Val" "100n")
    (property "Voltage" "")
    (property "ki_description" " ")
    (attr smd)
    (fp_text reference "C298" (at -0.865 0.475) (layer "B.SilkS")
        (effects (font (size 0.7 0.7) (thickness 0.15)) (justify left bottom mirror))
    )
    (fp_text value "C_100n_0201" (at 0 -1.4) (layer "B.Fab") hide
        (effects (font (size 0.7 0.7) (thickness 0.15)) (justify left bottom mirror))
    )
    (fp_text user "License: Apache-2.0" (at -0.72 -4.4) (layer "B.Fab") hide
        (effects (font (size 0.7 0.7) (thickness 0.15)) (justify left bottom mirror))
    )
    (fp_text user "${REFERENCE}" (at -0.72 -3.4) (layer "B.Fab") hide
        (effects (font (size 0.7 0.7) (thickness 0.15)) (justify left bottom mirror))
    )
    (fp_text user "Author: Antmicro" (at -0.72 -5.4) (layer "B.Fab") hide
        (effects (font (size 0.7 0.7) (thickness 0.15)) (justify left bottom mirror))
    )
    (fp_rect (start -0.72 0.38) (end 0.72 -0.38)
      (stroke (width 0.05) (type solid)) (fill none) (layer "B.CrtYd"))
    (fp_rect (start 0.3 -0.15) (end -0.301 0.149)
      (stroke (width 0.15) (type solid)) (fill none) (layer "B.Fab"))
    (pad "" smd roundrect (at -0.349 0.002 180) (size 0.318 0.36) (layers "B.Paste") (roundrect_rratio 0.25))
    (pad "" smd roundrect (at 0.341 0.002 180) (size 0.318 0.36) (layers "B.Paste") (roundrect_rratio 0.25))
    (pad "1" smd roundrect (at -0.321 0.002 180) (size 0.46 0.4) (layers "B.Cu" "B.Mask") (roundrect_rratio 0.25)
      (net 143 "3V3_SYS") (pintype "passive"))
    (pad "2" smd roundrect (at 0.32 0.002 180) (size 0.46 0.4) (layers "B.Cu" "B.Mask") (roundrect_rratio 0.25)
      (net 9 "GND") (pintype "passive"))
  )

  (footprint "data-center-rdimm-ddr4-tester-footprints:C_0201" (layer "B.Cu")
    (at 178.05 92.225 -90)
    (descr "Capacitor SMD 0201")
    (tags "capacitor SMD 0201")
    (property "Author" "Antmicro")
    (property "Dielectric" "")
    (property "License" "Apache-2.0")
    (property "MPN" "CC0201KRX6S5BB104")
    (property "Manufacturer" "Yaego")
    (property "Sheetfile" "fpga-power.kicad_sch")
    (property "Sheetname" "FPGA power")
    (property "Val" "100n")
    (property "Voltage" "")
    (property "ki_description" " ")
    (attr smd)
    (fp_text reference "C301" (at -1.265 0.51 90) (layer "B.SilkS")
        (effects (font (size 0.7 0.7) (thickness 0.15)) (justify left bottom mirror))
    )
    (fp_text value "C_100n_0201" (at 0 -1.4 90) (layer "B.Fab") hide
        (effects (font (size 0.7 0.7) (thickness 0.15)) (justify left bottom mirror))
    )
    (fp_text user "License: Apache-2.0" (at -0.72 -4.4 90) (layer "B.Fab") hide
        (effects (font (size 0.7 0.7) (thickness 0.15)) (justify left bottom mirror))
    )
    (fp_text user "Author: Antmicro" (at -0.72 -5.4 90) (layer "B.Fab") hide
        (effects (font (size 0.7 0.7) (thickness 0.15)) (justify left bottom mirror))
    )
    (fp_text user "${REFERENCE}" (at -0.72 -3.4 90) (layer "B.Fab") hide
        (effects (font (size 0.7 0.7) (thickness 0.15)) (justify left bottom mirror))
    )
    (fp_rect (start -0.72 0.38) (end 0.72 -0.38)
      (stroke (width 0.05) (type solid)) (fill none) (layer "B.CrtYd"))
    (fp_rect (start 0.3 -0.15) (end -0.301 0.149)
      (stroke (width 0.15) (type solid)) (fill none) (layer "B.Fab"))
    (pad "" smd roundrect (at -0.349 0.002 270) (size 0.318 0.36) (layers "B.Paste") (roundrect_rratio 0.25))
    (pad "" smd roundrect (at 0.341 0.002 270) (size 0.318 0.36) (layers "B.Paste") (roundrect_rratio 0.25))
    (pad "1" smd roundrect (at -0.321 0.002 270) (size 0.46 0.4) (layers "B.Cu" "B.Mask") (roundrect_rratio 0.25)
      (net 143 "3V3_SYS") (pintype "passive"))
    (pad "2" smd roundrect (at 0.32 0.002 270) (size 0.46 0.4) (layers "B.Cu" "B.Mask") (roundrect_rratio 0.25)
      (net 9 "GND") (pintype "passive"))
  )

  (footprint "data-center-rdimm-ddr4-tester-footprints:SOIC-4_4.55x2.6mm_P1.27" (layer "B.Cu")
    (at 164.5 133.525)
    (descr "ACPL-217-500E")
    (tags "Integrated Circuit")
    (property "Author" "Antmicro")
    (property "Description" "Broadcom ACPL-217-500E DC Input Transistor Output Optocoupler, Surface Mount, 4-Pin SO")
    (property "License" "Apache-2.0")
    (property "MPN" "ACPL-217-500E")
    (property "Manufacturer" "Broadcom")
    (property "Sheetfile" "ethernet.kicad_sch")
    (property "Sheetname" "Ethernet")
    (property "ki_description" "Broadcom ACPL-217-500E DC Input Transistor Output Optocoupler, Surface Mount, 4-Pin SO")
    (attr smd)
    (fp_text reference "IC2" (at 0 -1.695 180) (layer "B.SilkS")
        (effects (font (size 0.7 0.7) (thickness 0.15)) (justify left bottom mirror))
    )
    (fp_text value "ACPL-217-500E" (at -4.25 -2.75 180) (layer "B.Fab") hide
        (effects (font (size 0.7 0.7) (thickness 0.15)) (justify left bottom mirror))
    )
    (fp_text user "." (at -2.7 1.6 180) (layer "B.SilkS")
        (effects (font (size 1 1) (thickness 0.15)) (justify mirror))
    )
    (fp_text user "${REFERENCE}" (at -4.3 -4.25 180) (layer "B.Fab") hide
        (effects (font (size 0.7 0.7) (thickness 0.15)) (justify left bottom mirror))
    )
    (fp_text user "License: Apache-2.0" (at -4.25 -7 180) (layer "B.Fab") hide
        (effects (font (size 0.7 0.7) (thickness 0.15)) (justify left bottom mirror))
    )
    (fp_text user "Author: Antmicro" (at -4.3 -5.5 180) (layer "B.Fab") hide
        (effects (font (size 0.7 0.7) (thickness 0.15)) (justify left bottom mirror))
    )
    (fp_line (start -2.3 -1.1) (end -2.3 -1.4)
      (stroke (width 0.12) (type solid)) (layer "B.SilkS"))
    (fp_line (start -2.3 1.4) (end -1.8 1.4)
      (stroke (width 0.12) (type solid)) (layer "B.SilkS"))
    (fp_line (start -1.8 -1.4) (end -2.3 -1.4)
      (stroke (width 0.12) (type solid)) (layer "B.SilkS"))
    (fp_line (start 1.8 1.4) (end 2.3 1.4)
      (stroke (width 0.12) (type solid)) (layer "B.SilkS"))
    (fp_line (start 2.3 -1.4) (end 1.8 -1.4)
      (stroke (width 0.12) (type solid)) (layer "B.SilkS"))
    (fp_line (start 2.3 -1.1) (end 2.3 -1.4)
      (stroke (width 0.12) (type solid)) (layer "B.SilkS"))
    (fp_line (start 2.3 1.1) (end 2.3 1.4)
      (stroke (width 0.12) (type solid)) (layer "B.SilkS"))
    (fp_line (start -4.3 -1.69) (end -4.3 1.7)
      (stroke (width 0.05) (type solid)) (layer "B.CrtYd"))
    (fp_line (start -4.3 1.7) (end 4.29 1.7)
      (stroke (width 0.05) (type solid)) (layer "B.CrtYd"))
    (fp_line (start 4.29 -1.69) (end -4.3 -1.69)
      (stroke (width 0.05) (type solid)) (layer "B.CrtYd"))
    (fp_line (start 4.29 1.7) (end 4.29 -1.69)
      (stroke (width 0.05) (type solid)) (layer "B.CrtYd"))
    (fp_line (start -2.201 -1.3) (end -2.201 1.301)
      (stroke (width 0.15) (type solid)) (layer "B.Fab"))
    (fp_line (start -2.201 0.03) (end -0.931 1.301)
      (stroke (width 0.15) (type solid)) (layer "B.Fab"))
    (fp_line (start -2.201 1.301) (end 2.2 1.301)
      (stroke (width 0.15) (type solid)) (layer "B.Fab"))
    (fp_line (start 2.2 -1.3) (end -2.201 -1.3)
      (stroke (width 0.15) (type solid)) (layer "B.Fab"))
    (fp_line (start 2.2 1.301) (end 2.2 -1.3)
      (stroke (width 0.15) (type solid)) (layer "B.Fab"))
    (pad "1" smd roundrect (at -3.125 0.635 270) (size 0.65 1.85) (layers "B.Cu" "B.Paste" "B.Mask") (roundrect_rratio 0.15)
      (net 626 "VIN_RAW") (pintype "passive"))
    (pad "2" smd roundrect (at -3.125 -0.634 270) (size 0.65 1.85) (layers "B.Cu" "B.Paste" "B.Mask") (roundrect_rratio 0.15)
      (net 628 "Net-(IC2-Pad2)") (pintype "passive"))
    (pad "3" smd roundrect (at 3.124 -0.634 270) (size 0.65 1.85) (layers "B.Cu" "B.Paste" "B.Mask") (roundrect_rratio 0.15)
      (net 627 "Net-(IC2-Pad3)") (pintype "passive"))
    (pad "4" smd roundrect (at 3.124 0.635 270) (size 0.65 1.85) (layers "B.Cu" "B.Paste" "B.Mask") (roundrect_rratio 0.15)
      (net 615 "/Ethernet/POE_ACTIVE") (pintype "passive"))
  )

  (footprint "data-center-rdimm-ddr4-tester-footprints:R_0402_1005Metric" (layer "B.Cu")
    (at 138.96 98.72 -90)
    (descr "Resistor SMD 0402")
    (tags "resistor SMD 0402")
    (property "Author" "Antmicro")
    (property "License" "Apache-2.0")
    (property "MPN" "CR0402-FX-1003GLF")
    (property "Manufacturer" "Bourns")
    (property "Sheetfile" "supply.kicad_sch")
    (property "Sheetname" "Supply")
    (property "Tolerance" "1%")
    (property "Val" "100k")
    (property "ki_description" "100k resistor in 0402 package with 1% tolerance")
    (attr smd)
    (fp_text reference "R215" (at -1.32 -1.44 90) (layer "B.SilkS")
        (effects (font (size 0.7 0.7) (thickness 0.15)) (justify left bottom mirror))
    )
    (fp_text value "R_100k_0402" (at 0 -1.4 90) (layer "B.Fab") hide
        (effects (font (size 0.7 0.7) (thickness 0.15)) (justify left bottom mirror))
    )
    (fp_text user "Author: Antmicro" (at -0.95 -4.169 90) (layer "B.Fab") hide
        (effects (font (size 0.7 0.7) (thickness 0.15)) (justify left bottom mirror))
    )
    (fp_text user "License: Apache-2.0" (at -0.95 -5.169 90) (layer "B.Fab") hide
        (effects (font (size 0.7 0.7) (thickness 0.15)) (justify left bottom mirror))
    )
    (fp_text user "${REFERENCE}" (at -0.95 -3.168 90) (layer "B.Fab") hide
        (effects (font (size 0.7 0.7) (thickness 0.15)) (justify left bottom mirror))
    )
    (fp_rect (start -0.93 0.47) (end 0.93 -0.47)
      (stroke (width 0.05) (type solid)) (fill none) (layer "B.CrtYd"))
    (fp_rect (start -0.5 0.25) (end 0.5 -0.25)
      (stroke (width 0.15) (type solid)) (fill none) (layer "B.Fab"))
    (pad "1" smd roundrect (at -0.485 0 270) (size 0.59 0.64) (layers "B.Cu" "B.Paste" "B.Mask") (roundrect_rratio 0.25)
      (net 9 "GND") (pintype "passive"))
    (pad "2" smd roundrect (at 0.485 0 270) (size 0.59 0.64) (layers "B.Cu" "B.Paste" "B.Mask") (roundrect_rratio 0.25)
      (net 800 "FPGA_VTT_CNTL") (pintype "passive"))
  )

  (footprint "data-center-rdimm-ddr4-tester-footprints:C_0402_1005Metric" (layer "B.Cu")
    (at 131.425 105.55 90)
    (descr "Capacitor SMD 0402")
    (tags "capacitor SMD 0402")
    (property "Author" "Antmicro")
    (property "Dielectric" "X5R")
    (property "License" "Apache-2.0")
    (property "MPN" "GRM155R61H104KE14D")
    (property "Manufacturer" "Murata")
    (property "Sheetfile" "supply.kicad_sch")
    (property "Sheetname" "Supply")
    (property "Val" "100n")
    (property "Voltage" "50V")
    (property "ki_description" " ")
    (attr smd)
    (fp_text reference "C236" (at 0.88 1.205 270) (layer "B.SilkS")
        (effects (font (size 0.7 0.7) (thickness 0.15)) (justify left bottom mirror))
    )
    (fp_text value "C_100n_0402" (at 0 -1.4 270) (layer "B.Fab") hide
        (effects (font (size 0.7 0.7) (thickness 0.15)) (justify left bottom mirror))
    )
    (fp_text user "License: Apache-2.0" (at -0.932 -5.17 270) (layer "B.Fab") hide
        (effects (font (size 0.7 0.7) (thickness 0.15)) (justify left bottom mirror))
    )
    (fp_text user "${REFERENCE}" (at -0.932 -3.168 270) (layer "B.Fab") hide
        (effects (font (size 0.7 0.7) (thickness 0.15)) (justify left bottom mirror))
    )
    (fp_text user "Author: Antmicro" (at -0.932 -4.17 270) (layer "B.Fab") hide
        (effects (font (size 0.7 0.7) (thickness 0.15)) (justify left bottom mirror))
    )
    (fp_rect (start -0.94 0.47) (end 0.94 -0.47)
      (stroke (width 0.05) (type solid)) (fill none) (layer "B.CrtYd"))
    (fp_rect (start -0.499 0.249) (end 0.499 -0.249)
      (stroke (width 0.15) (type solid)) (fill none) (layer "B.Fab"))
    (pad "1" smd roundrect (at -0.484 0 90) (size 0.59 0.64) (layers "B.Cu" "B.Paste" "B.Mask") (roundrect_rratio 0.25)
      (net 307 "5V0_SYS") (pintype "passive"))
    (pad "2" smd roundrect (at 0.484 0 90) (size 0.59 0.64) (layers "B.Cu" "B.Paste" "B.Mask") (roundrect_rratio 0.25)
      (net 9 "GND") (pintype "passive"))
  )

  (footprint "data-center-rdimm-ddr4-tester-footprints:R_0402_1005Metric" (layer "B.Cu")
    (at 176.25 127.105 180)
    (descr "Resistor SMD 0402")
    (tags "resistor SMD 0402")
    (property "Author" "Antmicro")
    (property "DNP" "DNP")
    (property "License" "Apache-2.0")
    (property "MPN" "CR0402-FX-1002GLF")
    (property "Manufacturer" "Bourns")
    (property "Sheetfile" "ethernet.kicad_sch")
    (property "Sheetname" "Ethernet")
    (property "Tolerance" "1%")
    (property "Val" "10k")
    (property "dnp" "")
    (property "exclude_from_bom" "")
    (property "ki_description" "10k resistor in 0402 package with 1% tolerance")
    (attr exclude_from_pos_files exclude_from_bom)
    (fp_text reference "R182" (at 0.73 -0.445) (layer "B.SilkS")
        (effects (font (size 0.7 0.7) (thickness 0.15)) (justify left bottom mirror))
    )
    (fp_text value "R_10k_0402" (at 0 -1.4) (layer "B.Fab") hide
        (effects (font (size 0.7 0.7) (thickness 0.15)) (justify left bottom mirror))
    )
    (fp_text user "License: Apache-2.0" (at -0.95 -5.169) (layer "B.Fab") hide
        (effects (font (size 0.7 0.7) (thickness 0.15)) (justify left bottom mirror))
    )
    (fp_text user "Author: Antmicro" (at -0.95 -4.169) (layer "B.Fab") hide
        (effects (font (size 0.7 0.7) (thickness 0.15)) (justify left bottom mirror))
    )
    (fp_text user "${REFERENCE}" (at -0.95 -3.168) (layer "B.Fab") hide
        (effects (font (size 0.7 0.7) (thickness 0.15)) (justify left bottom mirror))
    )
    (fp_rect (start -0.93 0.47) (end 0.93 -0.47)
      (stroke (width 0.05) (type solid)) (fill none) (layer "B.CrtYd"))
    (fp_rect (start -0.5 0.25) (end 0.5 -0.25)
      (stroke (width 0.15) (type solid)) (fill none) (layer "B.Fab"))
    (pad "1" smd roundrect (at -0.485 0 180) (size 0.59 0.64) (layers "B.Cu" "B.Paste" "B.Mask") (roundrect_rratio 0.25)
      (net 659 "Net-(U13-~{BT})") (pintype "passive"))
    (pad "2" smd roundrect (at 0.485 0 180) (size 0.59 0.64) (layers "B.Cu" "B.Paste" "B.Mask") (roundrect_rratio 0.25)
      (net 360 "/Ethernet/VDD") (pintype "passive"))
  )

  (footprint "data-center-rdimm-ddr4-tester-footprints:C_0201" (layer "B.Cu")
    (at 189.8 80 90)
    (descr "Capacitor SMD 0201")
    (tags "capacitor SMD 0201")
    (property "Author" "Antmicro")
    (property "Dielectric" "")
    (property "License" "Apache-2.0")
    (property "MPN" "CC0201KRX6S5BB104")
    (property "Manufacturer" "Yaego")
    (property "Sheetfile" "fpga-power.kicad_sch")
    (property "Sheetname" "FPGA power")
    (property "Val" "100n")
    (property "Voltage" "")
    (property "ki_description" " ")
    (attr smd)
    (fp_text reference "C286" (at 1.13 1.19 270) (layer "B.SilkS")
        (effects (font (size 0.7 0.7) (thickness 0.15)) (justify left bottom mirror))
    )
    (fp_text value "C_100n_0201" (at 0 -1.4 270) (layer "B.Fab") hide
        (effects (font (size 0.7 0.7) (thickness 0.15)) (justify left bottom mirror))
    )
    (fp_text user "Author: Antmicro" (at -0.72 -5.4 270) (layer "B.Fab") hide
        (effects (font (size 0.7 0.7) (thickness 0.15)) (justify left bottom mirror))
    )
    (fp_text user "${REFERENCE}" (at -0.72 -3.4 270) (layer "B.Fab") hide
        (effects (font (size 0.7 0.7) (thickness 0.15)) (justify left bottom mirror))
    )
    (fp_text user "License: Apache-2.0" (at -0.72 -4.4 270) (layer "B.Fab") hide
        (effects (font (size 0.7 0.7) (thickness 0.15)) (justify left bottom mirror))
    )
    (fp_rect (start -0.72 0.38) (end 0.72 -0.38)
      (stroke (width 0.05) (type solid)) (fill none) (layer "B.CrtYd"))
    (fp_rect (start 0.3 -0.15) (end -0.301 0.149)
      (stroke (width 0.15) (type solid)) (fill none) (layer "B.Fab"))
    (pad "" smd roundrect (at -0.349 0.002 90) (size 0.318 0.36) (layers "B.Paste") (roundrect_rratio 0.25))
    (pad "" smd roundrect (at 0.341 0.002 90) (size 0.318 0.36) (layers "B.Paste") (roundrect_rratio 0.25))
    (pad "1" smd roundrect (at -0.321 0.002 90) (size 0.46 0.4) (layers "B.Cu" "B.Mask") (roundrect_rratio 0.25)
      (net 77 "VDDQ") (pintype "passive"))
    (pad "2" smd roundrect (at 0.32 0.002 90) (size 0.46 0.4) (layers "B.Cu" "B.Mask") (roundrect_rratio 0.25)
      (net 9 "GND") (pintype "passive"))
  )

  (footprint "data-center-rdimm-ddr4-tester-footprints:R_0402_1005Metric" (layer "B.Cu")
    (at 128.775 102.8)
    (descr "Resistor SMD 0402")
    (tags "resistor SMD 0402")
    (property "Author" "Antmicro")
    (property "Current" "1A")
    (property "DNP" "DNP")
    (property "License" "Apache-2.0")
    (property "MPN" "ERJ2GE0R00X")
    (property "Manufacturer" "Panasonic")
    (property "Sheetfile" "supply.kicad_sch")
    (property "Sheetname" "Supply")
    (property "Tolerance" "")
    (property "Val" "0R")
    (property "dnp" "")
    (property "exclude_from_bom" "")
    (property "ki_description" "0R resistor in 0402 package with unspecified tolerance")
    (attr exclude_from_pos_files exclude_from_bom)
    (fp_text reference "R191" (at 1.435 -0.53 180) (layer "B.SilkS")
        (effects (font (size 0.7 0.7) (thickness 0.15)) (justify left bottom mirror))
    )
    (fp_text value "R_0R_0402" (at 0 -1.4 180) (layer "B.Fab") hide
        (effects (font (size 0.7 0.7) (thickness 0.15)) (justify left bottom mirror))
    )
    (fp_text user "${REFERENCE}" (at -0.95 -3.168 180) (layer "B.Fab") hide
        (effects (font (size 0.7 0.7) (thickness 0.15)) (justify left bottom mirror))
    )
    (fp_text user "License: Apache-2.0" (at -0.95 -5.169 180) (layer "B.Fab") hide
        (effects (font (size 0.7 0.7) (thickness 0.15)) (justify left bottom mirror))
    )
    (fp_text user "Author: Antmicro" (at -0.95 -4.169 180) (layer "B.Fab") hide
        (effects (font (size 0.7 0.7) (thickness 0.15)) (justify left bottom mirror))
    )
    (fp_rect (start -0.93 0.47) (end 0.93 -0.47)
      (stroke (width 0.05) (type solid)) (fill none) (layer "B.CrtYd"))
    (fp_rect (start -0.5 0.25) (end 0.5 -0.25)
      (stroke (width 0.15) (type solid)) (fill none) (layer "B.Fab"))
    (pad "1" smd roundrect (at -0.485 0) (size 0.59 0.64) (layers "B.Cu" "B.Paste" "B.Mask") (roundrect_rratio 0.25)
      (net 536 "/Supply/SYS_PWR_GOOD") (pintype "passive"))
    (pad "2" smd roundrect (at 0.485 0) (size 0.59 0.64) (layers "B.Cu" "B.Paste" "B.Mask") (roundrect_rratio 0.25)
      (net 790 "/Supply/PWR_SEQ_EN") (pintype "passive"))
  )

  (footprint "data-center-rdimm-ddr4-tester-footprints:Fiducial_1mm_Mask2mm" (layer "B.Cu")
    (at 252.65 133.95 180)
    (descr "Circular Fiducial, 1mm bare copper, 3mm soldermask opening")
    (tags "fiducial")
    (property "Author" "Antmicro")
    (property "License" "Apache-2.0")
    (property "MPN" "")
    (property "Manufacturer" "")
    (property "Sheetfile" "data-center-rdimm-ddr4-tester.kicad_sch")
    (property "Sheetname" "")
    (property "exclude_from_bom" "")
    (property "ki_description" "Fiducial Marker for use with single board only")
    (attr exclude_from_pos_files exclude_from_bom)
    (fp_text reference "FID4" (at -2.2 1.38) (layer "B.SilkS")
        (effects (font (size 0.7 0.7) (thickness 0.15)) (justify left bottom mirror))
    )
    (fp_text value "Fiducial_1mm_Mask2mm" (at 0 -2.2) (layer "B.Fab")
        (effects (font (size 0.7 0.7) (thickness 0.15)) (justify left bottom mirror))
    )
    (fp_text user "Author: Antmicro" (at -1.25 -5.803) (layer "B.Fab") hide
        (effects (font (size 0.7 0.7) (thickness 0.15)) (justify left bottom mirror))
    )
    (fp_text user "${REFERENCE}" (at -1.25 -4.603) (layer "B.Fab") hide
        (effects (font (size 0.7 0.7) (thickness 0.15)) (justify left bottom mirror))
    )
    (fp_text user "License: Apache-2.0" (at -1.25 -7.003) (layer "B.Fab") hide
        (effects (font (size 0.7 0.7) (thickness 0.15)) (justify left bottom mirror))
    )
    (fp_circle (center 0 0) (end 1.24 0)
      (stroke (width 0.05) (type solid)) (fill none) (layer "B.CrtYd"))
    (fp_circle (center 0 0) (end 0.999 0)
      (stroke (width 0.15) (type solid)) (fill none) (layer "B.Fab"))
    (pad "" smd circle (at 0 0 180) (size 1 1) (layers "B.Cu" "B.Mask")
      (solder_mask_margin 0.5) (clearance 0.5))
  )

  (footprint "data-center-rdimm-ddr4-tester-footprints:R_0402_1005Metric" (layer "B.Cu")
    (at 166.2 101.8 180)
    (descr "Resistor SMD 0402")
    (tags "resistor SMD 0402")
    (property "Author" "Antmicro")
    (property "Current" "1A")
    (property "DNP" "DNP")
    (property "License" "Apache-2.0")
    (property "MPN" "ERJ2GE0R00X")
    (property "Manufacturer" "Panasonic")
    (property "Sheetfile" "ethernet.kicad_sch")
    (property "Sheetname" "Ethernet")
    (property "Tolerance" "")
    (property "Val" "0R")
    (property "dnp" "")
    (property "exclude_from_bom" "")
    (property "ki_description" "0R resistor in 0402 package with unspecified tolerance")
    (attr exclude_from_pos_files exclude_from_bom)
    (fp_text reference "R206" (at -1.91 -2.27) (layer "B.SilkS")
        (effects (font (size 0.7 0.7) (thickness 0.15)) (justify left bottom mirror))
    )
    (fp_text value "R_0R_0402" (at 0 -1.4) (layer "B.Fab") hide
        (effects (font (size 0.7 0.7) (thickness 0.15)) (justify left bottom mirror))
    )
    (fp_text user "License: Apache-2.0" (at -0.95 -5.169) (layer "B.Fab") hide
        (effects (font (size 0.7 0.7) (thickness 0.15)) (justify left bottom mirror))
    )
    (fp_text user "${REFERENCE}" (at -0.95 -3.168) (layer "B.Fab") hide
        (effects (font (size 0.7 0.7) (thickness 0.15)) (justify left bottom mirror))
    )
    (fp_text user "Author: Antmicro" (at -0.95 -4.169) (layer "B.Fab") hide
        (effects (font (size 0.7 0.7) (thickness 0.15)) (justify left bottom mirror))
    )
    (fp_rect (start -0.93 0.47) (end 0.93 -0.47)
      (stroke (width 0.05) (type solid)) (fill none) (layer "B.CrtYd"))
    (fp_rect (start -0.5 0.25) (end 0.5 -0.25)
      (stroke (width 0.15) (type solid)) (fill none) (layer "B.Fab"))
    (pad "1" smd roundrect (at -0.485 0 180) (size 0.59 0.64) (layers "B.Cu" "B.Paste" "B.Mask") (roundrect_rratio 0.25)
      (net 796 "ETH_SEL") (pintype "passive"))
    (pad "2" smd roundrect (at 0.485 0 180) (size 0.59 0.64) (layers "B.Cu" "B.Paste" "B.Mask") (roundrect_rratio 0.25)
      (net 662 "Net-(U16-SEL)") (pintype "passive"))
  )

  (footprint "data-center-rdimm-ddr4-tester-footprints:C_0402_1005Metric" (layer "B.Cu")
    (at 198.784 111.003)
    (descr "Capacitor SMD 0402")
    (tags "capacitor SMD 0402")
    (property "Author" "Antmicro")
    (property "Dielectric" "X5R")
    (property "License" "Apache-2.0")
    (property "MPN" "GRM155R61H104KE14D")
    (property "Manufacturer" "Murata")
    (property "Sheetfile" "ethernet.kicad_sch")
    (property "Sheetname" "Ethernet")
    (property "Val" "100n")
    (property "Voltage" "50V")
    (property "ki_description" " ")
    (attr smd)
    (fp_text reference "C229" (at 1.526 -0.643 180) (layer "B.SilkS")
        (effects (font (size 0.7 0.7) (thickness 0.15)) (justify left bottom mirror))
    )
    (fp_text value "C_100n_0402" (at 0 -1.4 180) (layer "B.Fab") hide
        (effects (font (size 0.7 0.7) (thickness 0.15)) (justify left bottom mirror))
    )
    (fp_text user "License: Apache-2.0" (at -0.932 -5.17 180) (layer "B.Fab") hide
        (effects (font (size 0.7 0.7) (thickness 0.15)) (justify left bottom mirror))
    )
    (fp_text user "Author: Antmicro" (at -0.932 -4.17 180) (layer "B.Fab") hide
        (effects (font (size 0.7 0.7) (thickness 0.15)) (justify left bottom mirror))
    )
    (fp_text user "${REFERENCE}" (at -0.932 -3.168 180) (layer "B.Fab") hide
        (effects (font (size 0.7 0.7) (thickness 0.15)) (justify left bottom mirror))
    )
    (fp_rect (start -0.94 0.47) (end 0.94 -0.47)
      (stroke (width 0.05) (type solid)) (fill none) (layer "B.CrtYd"))
    (fp_rect (start -0.499 0.249) (end 0.499 -0.249)
      (stroke (width 0.15) (type solid)) (fill none) (layer "B.Fab"))
    (pad "1" smd roundrect (at -0.484 0) (size 0.59 0.64) (layers "B.Cu" "B.Paste" "B.Mask") (roundrect_rratio 0.25)
      (net 864 "VIN_POE") (pintype "passive"))
    (pad "2" smd roundrect (at 0.484 0) (size 0.59 0.64) (layers "B.Cu" "B.Paste" "B.Mask") (roundrect_rratio 0.25)
      (net 9 "GND") (pintype "passive"))
  )

  (footprint "data-center-rdimm-ddr4-tester-footprints:SC70-3" (layer "B.Cu")
    (at 134.6 109.3 180)
    (property "Author" "Antmicro")
    (property "License" "Apache-2.0")
    (property "MPN" "BSS138PW")
    (property "Manufacturer" "Nexperia")
    (property "Sheetfile" "supply.kicad_sch")
    (property "Sheetname" "Supply")
    (property "ki_description" "60 V, 320 mA N-channel enhancement mode Trench MOSFET, SC-70-3 aka SOT-323 package")
    (property "ki_keywords" "n-channel enhancement mosfet sc70 sc-70 sot-323 sot323")
    (attr smd)
    (fp_text reference "Q11" (at -0.7 -1.19 90) (layer "B.SilkS")
        (effects (font (size 0.7 0.7) (thickness 0.15)) (justify left bottom mirror))
    )
    (fp_text value "BSS138PW" (at 0 -2.3) (layer "B.Fab") hide
        (effects (font (size 0.7 0.7) (thickness 0.15)) (justify left bottom mirror))
    )
    (fp_text user "Author: Antmicro" (at -1.45 -5.782) (layer "B.Fab") hide
        (effects (font (size 0.7 0.7) (thickness 0.15)) (justify left bottom mirror))
    )
    (fp_text user "License: Apache-2.0" (at -1.45 -6.782) (layer "B.Fab") hide
        (effects (font (size 0.7 0.7) (thickness 0.15)) (justify left bottom mirror))
    )
    (fp_text user "${REFERENCE}" (at -1.45 -4.783) (layer "B.Fab") hide
        (effects (font (size 0.7 0.7) (thickness 0.15)) (justify left bottom mirror))
    )
    (fp_line (start -0.3 -1) (end 0.627 -1.001)
      (stroke (width 0.15) (type solid)) (layer "B.SilkS"))
    (fp_line (start -0.3 1) (end 0.627 0.999)
      (stroke (width 0.15) (type solid)) (layer "B.SilkS"))
    (fp_line (start 0.627 -0.6) (end 0.627 -1.001)
      (stroke (width 0.15) (type solid)) (layer "B.SilkS"))
    (fp_line (start 0.627 0.6) (end 0.627 0.999)
      (stroke (width 0.15) (type solid)) (layer "B.SilkS"))
    (fp_rect (start 1.4 -1.3) (end -1.4 1.3)
      (stroke (width 0.05) (type solid)) (fill none) (layer "B.CrtYd"))
    (fp_rect (start -0.623 0.999) (end 0.627 -1.001)
      (stroke (width 0.15) (type solid)) (fill none) (layer "B.Fab"))
    (pad "1" smd rect (at -0.95 0.65 90) (size 0.6 0.8) (layers "B.Cu" "B.Paste" "B.Mask")
      (net 804 "FPGA_POWER_CYCLE") (pinfunction "G") (pintype "bidirectional"))
    (pad "2" smd rect (at -0.95 -0.65 90) (size 0.6 0.8) (layers "B.Cu" "B.Paste" "B.Mask")
      (net 9 "GND") (pinfunction "S") (pintype "bidirectional"))
    (pad "3" smd rect (at 0.95 0 90) (size 0.6 0.8) (layers "B.Cu" "B.Paste" "B.Mask")
      (net 583 "Net-(Q11-D)") (pinfunction "D") (pintype "bidirectional"))
  )

  (footprint "data-center-rdimm-ddr4-tester-footprints:R_0402_1005Metric" (layer "B.Cu")
    (at 228.55 123)
    (descr "Resistor SMD 0402")
    (tags "resistor SMD 0402")
    (property "Author" "Antmicro")
    (property "License" "Apache-2.0")
    (property "MPN" "CR0402-FX-1002GLF")
    (property "Manufacturer" "Bourns")
    (property "Sheetfile" "supply.kicad_sch")
    (property "Sheetname" "Supply")
    (property "Tolerance" "1%")
    (property "Val" "10k")
    (property "ki_description" "10k resistor in 0402 package with 1% tolerance")
    (attr smd)
    (fp_text reference "R220" (at 1.5 -1.52 180) (layer "B.SilkS")
        (effects (font (size 0.7 0.7) (thickness 0.15)) (justify left bottom mirror))
    )
    (fp_text value "R_10k_0402" (at 0 -1.4 180) (layer "B.Fab") hide
        (effects (font (size 0.7 0.7) (thickness 0.15)) (justify left bottom mirror))
    )
    (fp_text user "License: Apache-2.0" (at -0.95 -5.169 180) (layer "B.Fab") hide
        (effects (font (size 0.7 0.7) (thickness 0.15)) (justify left bottom mirror))
    )
    (fp_text user "${REFERENCE}" (at -0.95 -3.168 180) (layer "B.Fab") hide
        (effects (font (size 0.7 0.7) (thickness 0.15)) (justify left bottom mirror))
    )
    (fp_text user "Author: Antmicro" (at -0.95 -4.169 180) (layer "B.Fab") hide
        (effects (font (size 0.7 0.7) (thickness 0.15)) (justify left bottom mirror))
    )
    (fp_rect (start -0.93 0.47) (end 0.93 -0.47)
      (stroke (width 0.05) (type solid)) (fill none) (layer "B.CrtYd"))
    (fp_rect (start -0.5 0.25) (end 0.5 -0.25)
      (stroke (width 0.15) (type solid)) (fill none) (layer "B.Fab"))
    (pad "1" smd roundrect (at -0.485 0) (size 0.59 0.64) (layers "B.Cu" "B.Paste" "B.Mask") (roundrect_rratio 0.25)
      (net 860 "/Supply/~{CLR}") (pintype "passive"))
    (pad "2" smd roundrect (at 0.485 0) (size 0.59 0.64) (layers "B.Cu" "B.Paste" "B.Mask") (roundrect_rratio 0.25)
      (net 859 "/Supply/OUT") (pintype "passive"))
  )

  (footprint "data-center-rdimm-ddr4-tester-footprints:C_0201" (layer "B.Cu")
    (at 194.2 101.6 180)
    (descr "Capacitor SMD 0201")
    (tags "capacitor SMD 0201")
    (property "Author" "Antmicro")
    (property "Dielectric" "")
    (property "License" "Apache-2.0")
    (property "MPN" "CC0201KRX6S5BB104")
    (property "Manufacturer" "Yaego")
    (property "Sheetfile" "fpga-power.kicad_sch")
    (property "Sheetname" "FPGA power")
    (property "Val" "100n")
    (property "Voltage" "")
    (property "ki_description" " ")
    (attr smd)
    (fp_text reference "C248" (at -3.44 -0.37) (layer "B.SilkS")
        (effects (font (size 0.7 0.7) (thickness 0.15)) (justify left bottom mirror))
    )
    (fp_text value "C_100n_0201" (at 0 -1.4) (layer "B.Fab") hide
        (effects (font (size 0.7 0.7) (thickness 0.15)) (justify left bottom mirror))
    )
    (fp_text user "${REFERENCE}" (at -0.72 -3.4) (layer "B.Fab") hide
        (effects (font (size 0.7 0.7) (thickness 0.15)) (justify left bottom mirror))
    )
    (fp_text user "License: Apache-2.0" (at -0.72 -4.4) (layer "B.Fab") hide
        (effects (font (size 0.7 0.7) (thickness 0.15)) (justify left bottom mirror))
    )
    (fp_text user "Author: Antmicro" (at -0.72 -5.4) (layer "B.Fab") hide
        (effects (font (size 0.7 0.7) (thickness 0.15)) (justify left bottom mirror))
    )
    (fp_rect (start -0.72 0.38) (end 0.72 -0.38)
      (stroke (width 0.05) (type solid)) (fill none) (layer "B.CrtYd"))
    (fp_rect (start 0.3 -0.15) (end -0.301 0.149)
      (stroke (width 0.15) (type solid)) (fill none) (layer "B.Fab"))
    (pad "" smd roundrect (at -0.349 0.002 180) (size 0.318 0.36) (layers "B.Paste") (roundrect_rratio 0.25))
    (pad "" smd roundrect (at 0.341 0.002 180) (size 0.318 0.36) (layers "B.Paste") (roundrect_rratio 0.25))
    (pad "1" smd roundrect (at -0.321 0.002 180) (size 0.46 0.4) (layers "B.Cu" "B.Mask") (roundrect_rratio 0.25)
      (net 306 "1V2_SYS") (pintype "passive"))
    (pad "2" smd roundrect (at 0.32 0.002 180) (size 0.46 0.4) (layers "B.Cu" "B.Mask") (roundrect_rratio 0.25)
      (net 9 "GND") (pintype "passive"))
  )

  (footprint "data-center-rdimm-ddr4-tester-footprints:C_0805_2012Metric" (layer "B.Cu")
    (at 188.1 124.5 180)
    (descr "Capacitor SMD 0805")
    (tags "capacitor SMD 0805")
    (property "Author" "Antmicro")
    (property "Dielectric" "X7R")
    (property "License" "Apache-2.0")
    (property "MPN" "CL21B104KCFNNNE")
    (property "Manufacturer" "SAMSUNG")
    (property "Sheetfile" "ethernet.kicad_sch")
    (property "Sheetname" "Ethernet")
    (property "Val" "100n/100V")
    (property "Voltage" "100V")
    (property "ki_description" " ")
    (attr smd)
    (fp_text reference "C222" (at -1.39 1.03) (layer "B.SilkS")
        (effects (font (size 0.7 0.7) (thickness 0.15)) (justify left bottom mirror))
    )
    (fp_text value "C_100n_0805_100V" (at 0 -1.947) (layer "B.Fab") hide
        (effects (font (size 0.7 0.7) (thickness 0.15)) (justify left bottom mirror))
    )
    (fp_text user "Author: Antmicro" (at -1.9 -5.947) (layer "B.Fab") hide
        (effects (font (size 0.7 0.7) (thickness 0.15)) (justify left bottom mirror))
    )
    (fp_text user "${REFERENCE}" (at -1.9 -3.947) (layer "B.Fab") hide
        (effects (font (size 0.7 0.7) (thickness 0.15)) (justify left bottom mirror))
    )
    (fp_text user "License: Apache-2.0" (at -1.9 -4.947) (layer "B.Fab") hide
        (effects (font (size 0.7 0.7) (thickness 0.15)) (justify left bottom mirror))
    )
    (fp_line (start -0.3 -0.8) (end 0.3 -0.8)
      (stroke (width 0.15) (type solid)) (layer "B.SilkS"))
    (fp_line (start -0.3 0.8) (end 0.3 0.8)
      (stroke (width 0.15) (type solid)) (layer "B.SilkS"))
    (fp_rect (start -1.9 0.93) (end 1.9 -0.93)
      (stroke (width 0.05) (type solid)) (fill none) (layer "B.CrtYd"))
    (fp_rect (start -0.95 0.675) (end 0.95 -0.675)
      (stroke (width 0.15) (type solid)) (fill none) (layer "B.Fab"))
    (pad "1" smd rect (at -1.05 0 180) (size 1.2 1.2) (layers "B.Cu" "B.Paste" "B.Mask")
      (net 360 "/Ethernet/VDD") (pintype "passive"))
    (pad "2" smd rect (at 1.05 0 180) (size 1.2 1.2) (layers "B.Cu" "B.Paste" "B.Mask")
      (net 381 "/Ethernet/VSS") (pintype "passive"))
  )

  (footprint "data-center-rdimm-ddr4-tester-footprints:SOT-753" (layer "B.Cu")
    (at 136.29 99.74 -90)
    (property "Author" "Antmicro")
    (property "License" "Apache-2.0")
    (property "MPN" "SN74AHCT1G125DBVR")
    (property "Manufacturer" "Texas Instruments")
    (property "Sheetfile" "supply.kicad_sch")
    (property "Sheetname" "Supply")
    (attr smd)
    (fp_text reference "U22" (at -1.16 2.04 90) (layer "B.SilkS")
        (effects (font (size 0.7 0.7) (thickness 0.15)) (justify left bottom mirror))
    )
    (fp_text value "SN74AHCT1G125_SOT" (at 0 -2.9 90) (layer "B.Fab") hide
        (effects (font (size 0.7 0.7) (thickness 0.15)) (justify left bottom mirror))
    )
    (fp_text user "Author: Antmicro" (at -1.651 -7.225 90) (layer "B.Fab") hide
        (effects (font (size 0.7 0.7) (thickness 0.15)) (justify left bottom mirror))
    )
    (fp_text user "${REFERENCE}" (at -1.651 -6.025 90) (layer "B.Fab") hide
        (effects (font (size 0.7 0.7) (thickness 0.15)) (justify left bottom mirror))
    )
    (fp_text user "License: Apache-2.0" (at -1.651 -8.425 90) (layer "B.Fab") hide
        (effects (font (size 0.7 0.7) (thickness 0.15)) (justify left bottom mirror))
    )
    (fp_line (start -1.651 1) (end -1.651 0.701)
      (stroke (width 0.15) (type solid)) (layer "B.SilkS"))
    (fp_line (start -1.648 -1) (end -1.648 -0.677)
      (stroke (width 0.15) (type solid)) (layer "B.SilkS"))
    (fp_line (start -1.5 -1) (end -1.648 -1)
      (stroke (width 0.15) (type solid)) (layer "B.SilkS"))
    (fp_line (start -1.5 1) (end -1.651 1)
      (stroke (width 0.15) (type solid)) (layer "B.SilkS"))
    (fp_line (start 1.5 -0.998) (end 1.648 -0.998)
      (stroke (width 0.15) (type solid)) (layer "B.SilkS"))
    (fp_line (start 1.5 1) (end 1.648 1)
      (stroke (width 0.15) (type solid)) (layer "B.SilkS"))
    (fp_line (start 1.648 -0.998) (end 1.648 -0.699)
      (stroke (width 0.15) (type solid)) (layer "B.SilkS"))
    (fp_line (start 1.648 1) (end 1.648 0.677)
      (stroke (width 0.15) (type solid)) (layer "B.SilkS"))
    (fp_circle (center -1.5 -1.35) (end -1.46 -1.4)
      (stroke (width 0.15) (type solid)) (fill solid) (layer "B.SilkS"))
    (fp_rect (start -1.7 1.901) (end 1.699 -1.898)
      (stroke (width 0.05) (type solid)) (fill none) (layer "B.CrtYd"))
    (fp_line (start -1.526 -0.623) (end -1.526 0.875)
      (stroke (width 0.15) (type solid)) (layer "B.Fab"))
    (fp_line (start -1.526 -0.623) (end -1.351 -0.873)
      (stroke (width 0.15) (type solid)) (layer "B.Fab"))
    (fp_line (start -1.526 0.875) (end 1.523 0.875)
      (stroke (width 0.15) (type solid)) (layer "B.Fab"))
    (fp_line (start -1.351 -0.873) (end 1.523 -0.873)
      (stroke (width 0.15) (type solid)) (layer "B.Fab"))
    (fp_line (start 1.523 0.875) (end 1.523 -0.873)
      (stroke (width 0.15) (type solid)) (layer "B.Fab"))
    (pad "1" smd roundrect (at -0.951 -1.35 270) (size 0.6 1.05) (layers "B.Cu" "B.Paste" "B.Mask") (roundrect_rratio 0.25)
      (net 800 "FPGA_VTT_CNTL") (pinfunction "~{OE}") (pintype "input"))
    (pad "2" smd roundrect (at 0 -1.35 270) (size 0.6 1.05) (layers "B.Cu" "B.Paste" "B.Mask") (roundrect_rratio 0.25)
      (net 153 "/Supply/VCC_IO_EN") (pinfunction "A") (pintype "input"))
    (pad "3" smd roundrect (at 0.949 -1.35 270) (size 0.6 1.05) (layers "B.Cu" "B.Paste" "B.Mask") (roundrect_rratio 0.25)
      (net 9 "GND") (pinfunction "GND") (pintype "power_in"))
    (pad "4" smd roundrect (at 0.949 1.351 270) (size 0.6 1.05) (layers "B.Cu" "B.Paste" "B.Mask") (roundrect_rratio 0.25)
      (net 793 "/Supply/VTT_CNTL") (pinfunction "Y") (pintype "output"))
    (pad "5" smd roundrect (at -0.951 1.351 270) (size 0.6 1.05) (layers "B.Cu" "B.Paste" "B.Mask") (roundrect_rratio 0.25)
      (net 307 "5V0_SYS") (pinfunction "V_{CC}") (pintype "power_in"))
  )

  (footprint "data-center-rdimm-ddr4-tester-footprints:R_0402_1005Metric" (layer "B.Cu")
    (at 122.525 96.45 -90)
    (descr "Resistor SMD 0402")
    (tags "resistor SMD 0402")
    (property "Author" "Antmicro")
    (property "Current" "1A")
    (property "DNP" "DNP")
    (property "License" "Apache-2.0")
    (property "MPN" "ERJ2GE0R00X")
    (property "Manufacturer" "Panasonic")
    (property "Sheetfile" "supply.kicad_sch")
    (property "Sheetname" "Supply")
    (property "Tolerance" "")
    (property "Val" "0R")
    (property "dnp" "")
    (property "exclude_from_bom" "")
    (property "ki_description" "0R resistor in 0402 package with unspecified tolerance")
    (attr exclude_from_pos_files exclude_from_bom)
    (fp_text reference "R197" (at -1.87 -1.355 90) (layer "B.SilkS")
        (effects (font (size 0.7 0.7) (thickness 0.15)) (justify left bottom mirror))
    )
    (fp_text value "R_0R_0402" (at 0 -1.4 90) (layer "B.Fab") hide
        (effects (font (size 0.7 0.7) (thickness 0.15)) (justify left bottom mirror))
    )
    (fp_text user "Author: Antmicro" (at -0.95 -4.169 90) (layer "B.Fab") hide
        (effects (font (size 0.7 0.7) (thickness 0.15)) (justify left bottom mirror))
    )
    (fp_text user "License: Apache-2.0" (at -0.95 -5.169 90) (layer "B.Fab") hide
        (effects (font (size 0.7 0.7) (thickness 0.15)) (justify left bottom mirror))
    )
    (fp_text user "${REFERENCE}" (at -0.95 -3.168 90) (layer "B.Fab") hide
        (effects (font (size 0.7 0.7) (thickness 0.15)) (justify left bottom mirror))
    )
    (fp_rect (start -0.93 0.47) (end 0.93 -0.47)
      (stroke (width 0.05) (type solid)) (fill none) (layer "B.CrtYd"))
    (fp_rect (start -0.5 0.25) (end 0.5 -0.25)
      (stroke (width 0.15) (type solid)) (fill none) (layer "B.Fab"))
    (pad "1" smd roundrect (at -0.485 0 270) (size 0.59 0.64) (layers "B.Cu" "B.Paste" "B.Mask") (roundrect_rratio 0.25)
      (net 152 "/Supply/VCC_AUX_EN") (pintype "passive"))
    (pad "2" smd roundrect (at 0.485 0 270) (size 0.59 0.64) (layers "B.Cu" "B.Paste" "B.Mask") (roundrect_rratio 0.25)
      (net 794 "/Supply/SLP_S4") (pintype "passive"))
  )

  (footprint "data-center-rdimm-ddr4-tester-footprints:C_0402_1005Metric" (layer "B.Cu")
    (at 130.075 111.2 180)
    (descr "Capacitor SMD 0402")
    (tags "capacitor SMD 0402")
    (property "Author" "Antmicro")
    (property "Dielectric" "X5R")
    (property "License" "Apache-2.0")
    (property "MPN" "GRM155R61H104KE14D")
    (property "Manufacturer" "Murata")
    (property "Sheetfile" "supply.kicad_sch")
    (property "Sheetname" "Supply")
    (property "Val" "100n")
    (property "Voltage" "50V")
    (property "ki_description" " ")
    (attr smd)
    (fp_text reference "C233" (at -0.825 -1.3) (layer "B.SilkS")
        (effects (font (size 0.7 0.7) (thickness 0.15)) (justify left bottom mirror))
    )
    (fp_text value "C_100n_0402" (at 0 -1.4) (layer "B.Fab") hide
        (effects (font (size 0.7 0.7) (thickness 0.15)) (justify left bottom mirror))
    )
    (fp_text user "License: Apache-2.0" (at -0.932 -5.17) (layer "B.Fab") hide
        (effects (font (size 0.7 0.7) (thickness 0.15)) (justify left bottom mirror))
    )
    (fp_text user "Author: Antmicro" (at -0.932 -4.17) (layer "B.Fab") hide
        (effects (font (size 0.7 0.7) (thickness 0.15)) (justify left bottom mirror))
    )
    (fp_text user "${REFERENCE}" (at -0.932 -3.168) (layer "B.Fab") hide
        (effects (font (size 0.7 0.7) (thickness 0.15)) (justify left bottom mirror))
    )
    (fp_rect (start -0.94 0.47) (end 0.94 -0.47)
      (stroke (width 0.05) (type solid)) (fill none) (layer "B.CrtYd"))
    (fp_rect (start -0.499 0.249) (end 0.499 -0.249)
      (stroke (width 0.15) (type solid)) (fill none) (layer "B.Fab"))
    (pad "1" smd roundrect (at -0.484 0 180) (size 0.59 0.64) (layers "B.Cu" "B.Paste" "B.Mask") (roundrect_rratio 0.25)
      (net 307 "5V0_SYS") (pintype "passive"))
    (pad "2" smd roundrect (at 0.484 0 180) (size 0.59 0.64) (layers "B.Cu" "B.Paste" "B.Mask") (roundrect_rratio 0.25)
      (net 9 "GND") (pintype "passive"))
  )

  (footprint "data-center-rdimm-ddr4-tester-footprints:C_0201" (layer "B.Cu")
    (at 184.175 98.725 180)
    (descr "Capacitor SMD 0201")
    (tags "capacitor SMD 0201")
    (property "Author" "Antmicro")
    (property "Dielectric" "")
    (property "License" "Apache-2.0")
    (property "MPN" "CC0201KRX6S5BB104")
    (property "Manufacturer" "Yaego")
    (property "Sheetfile" "fpga-power.kicad_sch")
    (property "Sheetname" "FPGA power")
    (property "Val" "100n")
    (property "Voltage" "")
    (property "ki_description" " ")
    (attr smd)
    (fp_text reference "C310" (at -1.955 0.515) (layer "B.SilkS")
        (effects (font (size 0.7 0.7) (thickness 0.15)) (justify left bottom mirror))
    )
    (fp_text value "C_100n_0201" (at 0 -1.4) (layer "B.Fab") hide
        (effects (font (size 0.7 0.7) (thickness 0.15)) (justify left bottom mirror))
    )
    (fp_text user "Author: Antmicro" (at -0.72 -5.4) (layer "B.Fab") hide
        (effects (font (size 0.7 0.7) (thickness 0.15)) (justify left bottom mirror))
    )
    (fp_text user "${REFERENCE}" (at -0.72 -3.4) (layer "B.Fab") hide
        (effects (font (size 0.7 0.7) (thickness 0.15)) (justify left bottom mirror))
    )
    (fp_text user "License: Apache-2.0" (at -0.72 -4.4) (layer "B.Fab") hide
        (effects (font (size 0.7 0.7) (thickness 0.15)) (justify left bottom mirror))
    )
    (fp_rect (start -0.72 0.38) (end 0.72 -0.38)
      (stroke (width 0.05) (type solid)) (fill none) (layer "B.CrtYd"))
    (fp_rect (start 0.3 -0.15) (end -0.301 0.149)
      (stroke (width 0.15) (type solid)) (fill none) (layer "B.Fab"))
    (pad "" smd roundrect (at -0.349 0.002 180) (size 0.318 0.36) (layers "B.Paste") (roundrect_rratio 0.25))
    (pad "" smd roundrect (at 0.341 0.002 180) (size 0.318 0.36) (layers "B.Paste") (roundrect_rratio 0.25))
    (pad "1" smd roundrect (at -0.321 0.002 180) (size 0.46 0.4) (layers "B.Cu" "B.Mask") (roundrect_rratio 0.25)
      (net 143 "3V3_SYS") (pintype "passive"))
    (pad "2" smd roundrect (at 0.32 0.002 180) (size 0.46 0.4) (layers "B.Cu" "B.Mask") (roundrect_rratio 0.25)
      (net 9 "GND") (pintype "passive"))
  )

  (footprint "data-center-rdimm-ddr4-tester-footprints:C_0201" (layer "B.Cu")
    (at 173.1 98.05 -90)
    (descr "Capacitor SMD 0201")
    (tags "capacitor SMD 0201")
    (property "Author" "Antmicro")
    (property "Dielectric" "")
    (property "License" "Apache-2.0")
    (property "MPN" "CC0201KRX6S5BB104")
    (property "Manufacturer" "Yaego")
    (property "Sheetfile" "fpga-power.kicad_sch")
    (property "Sheetname" "FPGA power")
    (property "Val" "100n")
    (property "Voltage" "")
    (property "ki_description" " ")
    (attr smd)
    (fp_text reference "C299" (at -1.41 0.52 90) (layer "B.SilkS")
        (effects (font (size 0.7 0.7) (thickness 0.15)) (justify left bottom mirror))
    )
    (fp_text value "C_100n_0201" (at 0 -1.4 90) (layer "B.Fab") hide
        (effects (font (size 0.7 0.7) (thickness 0.15)) (justify left bottom mirror))
    )
    (fp_text user "${REFERENCE}" (at -0.72 -3.4 90) (layer "B.Fab") hide
        (effects (font (size 0.7 0.7) (thickness 0.15)) (justify left bottom mirror))
    )
    (fp_text user "License: Apache-2.0" (at -0.72 -4.4 90) (layer "B.Fab") hide
        (effects (font (size 0.7 0.7) (thickness 0.15)) (justify left bottom mirror))
    )
    (fp_text user "Author: Antmicro" (at -0.72 -5.4 90) (layer "B.Fab") hide
        (effects (font (size 0.7 0.7) (thickness 0.15)) (justify left bottom mirror))
    )
    (fp_rect (start -0.72 0.38) (end 0.72 -0.38)
      (stroke (width 0.05) (type solid)) (fill none) (layer "B.CrtYd"))
    (fp_rect (start 0.3 -0.15) (end -0.301 0.149)
      (stroke (width 0.15) (type solid)) (fill none) (layer "B.Fab"))
    (pad "" smd roundrect (at -0.349 0.002 270) (size 0.318 0.36) (layers "B.Paste") (roundrect_rratio 0.25))
    (pad "" smd roundrect (at 0.341 0.002 270) (size 0.318 0.36) (layers "B.Paste") (roundrect_rratio 0.25))
    (pad "1" smd roundrect (at -0.321 0.002 270) (size 0.46 0.4) (layers "B.Cu" "B.Mask") (roundrect_rratio 0.25)
      (net 143 "3V3_SYS") (pintype "passive"))
    (pad "2" smd roundrect (at 0.32 0.002 270) (size 0.46 0.4) (layers "B.Cu" "B.Mask") (roundrect_rratio 0.25)
      (net 9 "GND") (pintype "passive"))
  )

  (footprint "data-center-rdimm-ddr4-tester-footprints:VQFN-16-1EP_3x3mm_P0.5mm_EP1.1x1.1mm" (layer "B.Cu")
    (at 126.8 90.8 -90)
    (descr "VQFN, 16 Pin (https://ww1.microchip.com/downloads/en/DeviceDoc/16L_VQFN-WFS_3x3mm_4MX_C04-00508a.pdf), generated with kicad-footprint-generator ipc_noLead_generator.py")
    (tags "VQFN NoLead")
    (property "Author" "Antmicro")
    (property "License" "Apache-2.0")
    (property "MPN" "PAC1954T-E/4MX")
    (property "Manufacturer" "Microchip Technology")
    (property "Sheetfile" "supply.kicad_sch")
    (property "Sheetname" "Supply")
    (property "ki_description" "Current/Voltage Monitor Regulator High-Side 16-VQFN (3x3)")
    (property "ki_keywords" "MONITOR, VOLTAGE")
    (attr smd)
    (fp_text reference "U20" (at 3.18 1.07 -180) (layer "B.SilkS")
        (effects (font (size 0.7 0.7) (thickness 0.15)) (justify left bottom mirror))
    )
    (fp_text value "PAC1954T-E_VQFN" (at 0 -2.797 90) (layer "B.Fab")
        (effects (font (size 0.7 0.7) (thickness 0.15)) (justify left bottom mirror))
    )
    (fp_text user "Author: Antmicro" (at -2.35 -5.997 90) (layer "B.Fab") hide
        (effects (font (size 0.7 0.7) (thickness 0.15)) (justify left bottom mirror))
    )
    (fp_text user "License: Apache-2.0" (at -2.35 -7.197 90) (layer "B.Fab") hide
        (effects (font (size 0.7 0.7) (thickness 0.15)) (justify left bottom mirror))
    )
    (fp_text user "${REFERENCE}" (at -2.35 -4.797 90) (layer "B.Fab") hide
        (effects (font (size 0.7 0.7) (thickness 0.15)) (justify left bottom mirror))
    )
    (fp_line (start -1.611 -1.61) (end -1.611 -1.134)
      (stroke (width 0.15) (type solid)) (layer "B.SilkS"))
    (fp_line (start -1.135 -1.61) (end -1.611 -1.61)
      (stroke (width 0.15) (type solid)) (layer "B.SilkS"))
    (fp_line (start -1.135 1.611) (end -1.611 1.611)
      (stroke (width 0.15) (type solid)) (layer "B.SilkS"))
    (fp_line (start 1.134 -1.61) (end 1.61 -1.61)
      (stroke (width 0.15) (type solid)) (layer "B.SilkS"))
    (fp_line (start 1.134 1.611) (end 1.61 1.611)
      (stroke (width 0.15) (type solid)) (layer "B.SilkS"))
    (fp_line (start 1.61 -1.61) (end 1.61 -1.134)
      (stroke (width 0.15) (type solid)) (layer "B.SilkS"))
    (fp_line (start 1.61 1.611) (end 1.61 1.135)
      (stroke (width 0.15) (type solid)) (layer "B.SilkS"))
    (fp_circle (center -2.3 0.75) (end -2.25 0.75)
      (stroke (width 0.15) (type solid)) (fill solid) (layer "B.SilkS"))
    (fp_rect (start -2 2) (end 1.999 -1.999)
      (stroke (width 0.05) (type solid)) (fill none) (layer "B.CrtYd"))
    (fp_line (start -1.5 -1.499) (end -1.5 0.75)
      (stroke (width 0.15) (type solid)) (layer "B.Fab"))
    (fp_line (start -1.5 0.75) (end -0.75 1.5)
      (stroke (width 0.15) (type solid)) (layer "B.Fab"))
    (fp_line (start -0.75 1.5) (end 1.499 1.5)
      (stroke (width 0.15) (type solid)) (layer "B.Fab"))
    (fp_line (start 1.499 -1.499) (end -1.5 -1.499)
      (stroke (width 0.15) (type solid)) (layer "B.Fab"))
    (fp_line (start 1.499 1.5) (end 1.499 -1.499)
      (stroke (width 0.15) (type solid)) (layer "B.Fab"))
    (fp_circle (center -2.3 0.75) (end -2.25 0.75)
      (stroke (width 0.15) (type solid)) (fill solid) (layer "B.Fab"))
    (pad "" smd roundrect (at 0 0 270) (size 0.89 0.89) (layers "B.Paste") (roundrect_rratio 0.25))
    (pad "1" smd roundrect (at -1.464 0.75 270) (size 0.775 0.25) (layers "B.Cu" "B.Paste" "B.Mask") (roundrect_rratio 0.25)
      (net 9 "GND") (pinfunction "SLOW/~{ALERT1}") (pintype "bidirectional"))
    (pad "2" smd roundrect (at -1.464 0.25 270) (size 0.775 0.25) (layers "B.Cu" "B.Paste" "B.Mask") (roundrect_rratio 0.25)
      (net 143 "3V3_SYS") (pinfunction "VDD") (pintype "power_in"))
    (pad "3" smd roundrect (at -1.464 -0.247 270) (size 0.775 0.25) (layers "B.Cu" "B.Paste" "B.Mask") (roundrect_rratio 0.25)
      (net 9 "GND") (pinfunction "GND") (pintype "power_in"))
    (pad "4" smd roundrect (at -1.464 -0.747 270) (size 0.775 0.25) (layers "B.Cu" "B.Paste" "B.Mask") (roundrect_rratio 0.25)
      (net 358 "SCL_3V3") (pinfunction "SCL") (pintype "input"))
    (pad "5" smd roundrect (at -0.75 -1.461 270) (size 0.25 0.775) (layers "B.Cu" "B.Paste" "B.Mask") (roundrect_rratio 0.25)
      (net 357 "SDA_3V3") (pinfunction "SDA") (pintype "bidirectional"))
    (pad "6" smd roundrect (at -0.25 -1.461 270) (size 0.25 0.775) (layers "B.Cu" "B.Paste" "B.Mask") (roundrect_rratio 0.25)
      (net 143 "3V3_SYS") (pinfunction "ADDRSEL") (pintype "bidirectional"))
    (pad "7" smd roundrect (at 0.247 -1.461 270) (size 0.25 0.775) (layers "B.Cu" "B.Paste" "B.Mask") (roundrect_rratio 0.25)
      (net 844 "/Supply/1V8_SEN_-") (pinfunction "IN3-") (pintype "input"))
    (pad "8" smd roundrect (at 0.747 -1.461 270) (size 0.25 0.775) (layers "B.Cu" "B.Paste" "B.Mask") (roundrect_rratio 0.25)
      (net 840 "/Supply/1V8_SEN_+") (pinfunction "IN3+") (pintype "input"))
    (pad "9" smd roundrect (at 1.461 -0.747 270) (size 0.775 0.25) (layers "B.Cu" "B.Paste" "B.Mask") (roundrect_rratio 0.25)
      (net 845 "/Supply/1V0_SEN_-") (pinfunction "IN4-") (pintype "input"))
    (pad "10" smd roundrect (at 1.461 -0.247 270) (size 0.775 0.25) (layers "B.Cu" "B.Paste" "B.Mask") (roundrect_rratio 0.25)
      (net 841 "/Supply/1V0_SEN_+") (pinfunction "IN4+") (pintype "input"))
    (pad "11" smd roundrect (at 1.461 0.25 270) (size 0.775 0.25) (layers "B.Cu" "B.Paste" "B.Mask") (roundrect_rratio 0.25)
      (net 838 "/Supply/5V0_SEN_+") (pinfunction "IN1+") (pintype "input"))
    (pad "12" smd roundrect (at 1.461 0.75 270) (size 0.775 0.25) (layers "B.Cu" "B.Paste" "B.Mask") (roundrect_rratio 0.25)
      (net 842 "/Supply/5V0_SEN_-") (pinfunction "IN1-") (pintype "input"))
    (pad "13" smd roundrect (at 0.747 1.464 270) (size 0.25 0.775) (layers "B.Cu" "B.Paste" "B.Mask") (roundrect_rratio 0.25)
      (net 839 "/Supply/3V3_SEN_+") (pinfunction "IN2+") (pintype "input"))
    (pad "14" smd roundrect (at 0.247 1.464 270) (size 0.25 0.775) (layers "B.Cu" "B.Paste" "B.Mask") (roundrect_rratio 0.25)
      (net 843 "/Supply/3V3_SEN_-") (pinfunction "IN2-") (pintype "input"))
    (pad "15" smd roundrect (at -0.25 1.464 270) (size 0.25 0.775) (layers "B.Cu" "B.Paste" "B.Mask") (roundrect_rratio 0.25)
      (net 9 "GND") (pinfunction "GPIO/~{ALERT2}") (pintype "bidirectional"))
    (pad "16" smd roundrect (at -0.75 1.464 270) (size 0.25 0.775) (layers "B.Cu" "B.Paste" "B.Mask") (roundrect_rratio 0.25)
      (net 661 "Net-(U20-~{PWRDN})") (pinfunction "~{PWRDN}") (pintype "input"))
    (pad "17" smd rect (at 0 0 270) (size 1.1 1.1) (layers "B.Cu" "B.Mask")
      (net 918 "unconnected-(U20-EP-Pad17)") (pinfunction "EP") (pintype "no_connect"))
  )

  (footprint "data-center-rdimm-ddr4-tester-footprints:SC-74-6_1.5x2.9mm_P0.95mm" (layer "B.Cu")
    (at 140 79.7 -90)
    (descr "https://assets.nexperia.com/documents/data-sheet/IP4220CZ6.pdf")
    (tags "sc74 sc-74 sot23-6 sot457 tsop6 tsop-6")
    (property "Author" "Antmicro")
    (property "License" "Apache-2.0")
    (property "MPN" "74LVC2G07GV,125")
    (property "Manufacturer" "Nexperia")
    (property "Sheetfile" "supply.kicad_sch")
    (property "Sheetname" "Supply")
    (property "ki_description" "Dual Buffer w/ Open Drain, Low-Voltage CMOS, TSOP6 (SOT457/SC-74/SOT23-6) package 1.1mm height, Texas Instruments Equivalent: SN74LVC2G07DBVR")
    (property "ki_keywords" "Dual Gate Buffer Open Drain LVC CMOS")
    (attr smd)
    (fp_text reference "U17" (at -1.63 -3.36 180) (layer "B.SilkS")
        (effects (font (size 0.7 0.7) (thickness 0.15)) (justify left bottom mirror))
    )
    (fp_text value "74LVC2G07_SOT457" (at -2 -2.999 90) (layer "B.Fab") hide
        (effects (font (size 0.7 0.7) (thickness 0.15)) (justify left bottom mirror))
    )
    (fp_text user "Author: Antmicro" (at -2.12 -4.999 90) (layer "B.Fab") hide
        (effects (font (size 0.7 0.7) (thickness 0.15)) (justify left bottom mirror))
    )
    (fp_text user "${REFERENCE}" (at -2.12 -7.399 90) (layer "B.Fab") hide
        (effects (font (size 0.7 0.7) (thickness 0.15)) (justify left bottom mirror))
    )
    (fp_text user "License: Apache-2.0" (at -2.12 -6.199 90) (layer "B.Fab") hide
        (effects (font (size 0.7 0.7) (thickness 0.15)) (justify left bottom mirror))
    )
    (fp_circle (center -2.07 0.956) (end -2.02 0.956)
      (stroke (width 0.15) (type solid)) (fill solid) (layer "B.SilkS"))
    (fp_circle (center -2.069 0.956) (end -2.02 0.956)
      (stroke (width 0.15) (type solid)) (fill solid) (layer "B.SilkS"))
    (fp_rect (start -1.714 1.897) (end 1.711 -1.896)
      (stroke (width 0.05) (type solid)) (fill none) (layer "B.CrtYd"))
    (fp_line (start -1.27 -1.372) (end -1.168 -1.372)
      (stroke (width 0.15) (type solid)) (layer "B.Fab"))
    (fp_line (start -1.27 0.915) (end -1.27 -1.372)
      (stroke (width 0.15) (type solid)) (layer "B.Fab"))
    (fp_line (start -1.168 -1.372) (end 1.219 -1.372)
      (stroke (width 0.15) (type solid)) (layer "B.Fab"))
    (fp_line (start -0.761 1.422) (end -1.27 0.915)
      (stroke (width 0.15) (type solid)) (layer "B.Fab"))
    (fp_line (start 1.219 -1.372) (end 1.219 1.422)
      (stroke (width 0.15) (type solid)) (layer "B.Fab"))
    (fp_line (start 1.219 1.422) (end -0.761 1.422)
      (stroke (width 0.15) (type solid)) (layer "B.Fab"))
    (fp_circle (center -2.069 0.956) (end -2.02 0.956)
      (stroke (width 0.15) (type solid)) (fill solid) (layer "B.Fab"))
    (pad "1" smd roundrect (at -1.214 0.955 270) (size 0.8 0.55) (layers "B.Cu" "B.Paste" "B.Mask") (roundrect_rratio 0.15)
      (net 152 "/Supply/VCC_AUX_EN") (pintype "input"))
    (pad "2" smd roundrect (at -1.214 0.003 270) (size 0.8 0.55) (layers "B.Cu" "B.Paste" "B.Mask") (roundrect_rratio 0.15)
      (net 9 "GND") (pinfunction "GND") (pintype "power_in"))
    (pad "3" smd roundrect (at -1.214 -0.947 270) (size 0.8 0.55) (layers "B.Cu" "B.Paste" "B.Mask") (roundrect_rratio 0.15)
      (net 151 "/Supply/VCC_INT_EN") (pintype "input"))
    (pad "4" smd roundrect (at 1.187 -0.947 270) (size 0.8 0.55) (layers "B.Cu" "B.Paste" "B.Mask") (roundrect_rratio 0.15)
      (net 855 "Net-(R29-Pad1)") (pintype "output"))
    (pad "5" smd roundrect (at 1.187 0.003 270) (size 0.8 0.55) (layers "B.Cu" "B.Paste" "B.Mask") (roundrect_rratio 0.15)
      (net 307 "5V0_SYS") (pinfunction "V_{CC}") (pintype "power_in"))
    (pad "6" smd roundrect (at 1.187 0.955 270) (size 0.8 0.55) (layers "B.Cu" "B.Paste" "B.Mask") (roundrect_rratio 0.15)
      (net 854 "Net-(R17-Pad1)") (pintype "output"))
  )

  (footprint "data-center-rdimm-ddr4-tester-footprints:FB_0805_2012Metric" (layer "B.Cu")
    (at 184.1 123.6 -90)
    (property "Author" "Antmicro")
    (property "License" "Apache-2.0")
    (property "MPN" "BLM21PG221SN1D")
    (property "Manufacturer" "Murata")
    (property "Sheetfile" "ethernet.kicad_sch")
    (property "Sheetname" "Ethernet")
    (attr smd)
    (fp_text reference "FB10" (at -1.19 -1.78 90) (layer "B.SilkS")
        (effects (font (size 0.7 0.7) (thickness 0.15)) (justify left bottom mirror))
    )
    (fp_text value "FB_220Z_2A_0603" (at 0 -1.8 90) (layer "B.Fab") hide
        (effects (font (size 0.7 0.7) (thickness 0.15)) (justify left bottom mirror))
    )
    (fp_text user "Author: Antmicro" (at -1.9 -4.4 90) (layer "B.Fab") hide
        (effects (font (size 0.7 0.7) (thickness 0.15)) (justify left bottom mirror))
    )
    (fp_text user "${REFERENCE}" (at -1.9 -3.1 90) (layer "B.Fab") hide
        (effects (font (size 0.7 0.7) (thickness 0.15)) (justify left bottom mirror))
    )
    (fp_text user "License: Apache-2.0" (at -1.9 -5.75 90) (layer "B.Fab") hide
        (effects (font (size 0.7 0.7) (thickness 0.15)) (justify left bottom mirror))
    )
    (fp_line (start -0.32 -0.699) (end 0.28 -0.699)
      (stroke (width 0.15) (type solid)) (layer "B.SilkS"))
    (fp_line (start -0.3 0.701) (end 0.298 0.701)
      (stroke (width 0.15) (type solid)) (layer "B.SilkS"))
    (fp_rect (start -1.75 0.85) (end 1.75 -0.85)
      (stroke (width 0.05) (type solid)) (fill none) (layer "B.CrtYd"))
    (fp_line (start -0.951 -0.68) (end 0.949 -0.68)
      (stroke (width 0.15) (type solid)) (layer "B.Fab"))
    (fp_line (start -0.951 0.677) (end -0.951 -0.675)
      (stroke (width 0.15) (type solid)) (layer "B.Fab"))
    (fp_line (start -0.951 0.682) (end 0.949 0.682)
      (stroke (width 0.15) (type solid)) (layer "B.Fab"))
    (fp_line (start 0.949 0.677) (end 0.949 -0.675)
      (stroke (width 0.15) (type solid)) (layer "B.Fab"))
    (pad "1" smd roundrect (at -1.1 0.001 270) (size 1 1.4) (layers "B.Cu" "B.Paste" "B.Mask") (roundrect_rratio 0.15)
      (net 807 "/Ethernet/VSS_RAW") (pintype "passive"))
    (pad "2" smd roundrect (at 1.1 0.001 270) (size 1 1.4) (layers "B.Cu" "B.Paste" "B.Mask") (roundrect_rratio 0.15)
      (net 381 "/Ethernet/VSS") (pintype "passive"))
  )

  (footprint "data-center-rdimm-ddr4-tester-footprints:R_0603_1608Metric" (layer "B.Cu")
    (at 181.91 124.8 180)
    (descr "Resistor SMD 0603")
    (tags "resistor SMD 0603")
    (property "Author" "Antmicro")
    (property "License" "Apache-2.0")
    (property "MPN" "CR0603-FX-63R4ELF")
    (property "Manufacturer" "Bourns")
    (property "Sheetfile" "ethernet.kicad_sch")
    (property "Sheetname" "Ethernet")
    (property "Tolerance" "1%")
    (property "Val" "63R4")
    (property "ki_description" "63R4 resistor in 0603 package with 1% tolerance")
    (attr smd)
    (fp_text reference "R85" (at -8.53 3.9) (layer "B.SilkS")
        (effects (font (size 0.7 0.7) (thickness 0.15)) (justify left bottom mirror))
    )
    (fp_text value "R_63R4_0603" (at 0 -1.6) (layer "B.Fab") hide
        (effects (font (size 0.7 0.7) (thickness 0.15)) (justify left bottom mirror))
    )
    (fp_text user "Author: Antmicro" (at -1.25 -4.9) (layer "B.Fab") hide
        (effects (font (size 0.7 0.7) (thickness 0.15)) (justify left bottom mirror))
    )
    (fp_text user "License: Apache-2.0" (at -1.25 -5.9) (layer "B.Fab") hide
        (effects (font (size 0.7 0.7) (thickness 0.15)) (justify left bottom mirror))
    )
    (fp_text user "${REFERENCE}" (at -1.25 -3.898) (layer "B.Fab") hide
        (effects (font (size 0.7 0.7) (thickness 0.15)) (justify left bottom mirror))
    )
    (fp_line (start -0.3 -0.3) (end 0.3 -0.3)
      (stroke (width 0.15) (type solid)) (layer "B.SilkS"))
    (fp_line (start -0.3 0.3) (end 0.3 0.3)
      (stroke (width 0.15) (type solid)) (layer "B.SilkS"))
    (fp_rect (start -1.25 0.7) (end 1.25 -0.7)
      (stroke (width 0.05) (type solid)) (fill none) (layer "B.CrtYd"))
    (fp_rect (start -0.8 0.4) (end 0.8 -0.4)
      (stroke (width 0.15) (type solid)) (fill none) (layer "B.Fab"))
    (pad "1" smd roundrect (at -0.7 0 180) (size 0.6 0.8) (layers "B.Cu" "B.Paste" "B.Mask") (roundrect_rratio 0.2)
      (net 381 "/Ethernet/VSS") (pintype "passive"))
    (pad "2" smd roundrect (at 0.7 0 180) (size 0.6 0.8) (layers "B.Cu" "B.Paste" "B.Mask") (roundrect_rratio 0.2)
      (net 611 "/Ethernet/CLSA") (pintype "passive"))
  )

  (footprint "data-center-rdimm-ddr4-tester-footprints:R_0603_1608Metric" (layer "B.Cu")
    (at 185.5 126.2 180)
    (descr "Resistor SMD 0603")
    (tags "resistor SMD 0603")
    (property "Author" "Antmicro")
    (property "License" "Apache-2.0")
    (property "MPN" "CR0603-FX-63R4ELF")
    (property "Manufacturer" "Bourns")
    (property "Sheetfile" "ethernet.kicad_sch")
    (property "Sheetname" "Ethernet")
    (property "Tolerance" "1%")
    (property "Val" "63R4")
    (property "ki_description" "63R4 resistor in 0603 package with 1% tolerance")
    (attr smd)
    (fp_text reference "R176" (at -3.92 -0.4) (layer "B.SilkS")
        (effects (font (size 0.7 0.7) (thickness 0.15)) (justify left bottom mirror))
    )
    (fp_text value "R_63R4_0603" (at 0 -1.6) (layer "B.Fab") hide
        (effects (font (size 0.7 0.7) (thickness 0.15)) (justify left bottom mirror))
    )
    (fp_text user "Author: Antmicro" (at -1.25 -4.9) (layer "B.Fab") hide
        (effects (font (size 0.7 0.7) (thickness 0.15)) (justify left bottom mirror))
    )
    (fp_text user "License: Apache-2.0" (at -1.25 -5.9) (layer "B.Fab") hide
        (effects (font (size 0.7 0.7) (thickness 0.15)) (justify left bottom mirror))
    )
    (fp_text user "${REFERENCE}" (at -1.25 -3.898) (layer "B.Fab") hide
        (effects (font (size 0.7 0.7) (thickness 0.15)) (justify left bottom mirror))
    )
    (fp_line (start -0.3 -0.3) (end 0.3 -0.3)
      (stroke (width 0.15) (type solid)) (layer "B.SilkS"))
    (fp_line (start -0.3 0.3) (end 0.3 0.3)
      (stroke (width 0.15) (type solid)) (layer "B.SilkS"))
    (fp_rect (start -1.25 0.7) (end 1.25 -0.7)
      (stroke (width 0.05) (type solid)) (fill none) (layer "B.CrtYd"))
    (fp_rect (start -0.8 0.4) (end 0.8 -0.4)
      (stroke (width 0.15) (type solid)) (fill none) (layer "B.Fab"))
    (pad "1" smd roundrect (at -0.7 0 180) (size 0.6 0.8) (layers "B.Cu" "B.Paste" "B.Mask") (roundrect_rratio 0.2)
      (net 381 "/Ethernet/VSS") (pintype "passive"))
    (pad "2" smd roundrect (at 0.7 0 180) (size 0.6 0.8) (layers "B.Cu" "B.Paste" "B.Mask") (roundrect_rratio 0.2)
      (net 618 "/Ethernet/CLSB") (pintype "passive"))
  )

  (footprint "data-center-rdimm-ddr4-tester-footprints:R_0402_1005Metric" (layer "B.Cu")
    (at 127.525 108.425 90)
    (descr "Resistor SMD 0402")
    (tags "resistor SMD 0402")
    (property "Author" "Antmicro")
    (property "License" "Apache-2.0")
    (property "MPN" "CR0402-FX-1003GLF")
    (property "Manufacturer" "Bourns")
    (property "Sheetfile" "supply.kicad_sch")
    (property "Sheetname" "Supply")
    (property "Tolerance" "1%")
    (property "Val" "100k")
    (property "ki_description" "100k resistor in 0402 package with 1% tolerance")
    (attr smd)
    (fp_text reference "R212" (at 1.265 -0.575 270) (layer "B.SilkS")
        (effects (font (size 0.7 0.7) (thickness 0.15)) (justify left bottom mirror))
    )
    (fp_text value "R_100k_0402" (at 0 -1.4 270) (layer "B.Fab") hide
        (effects (font (size 0.7 0.7) (thickness 0.15)) (justify left bottom mirror))
    )
    (fp_text user "${REFERENCE}" (at -0.95 -3.168 270) (layer "B.Fab") hide
        (effects (font (size 0.7 0.7) (thickness 0.15)) (justify left bottom mirror))
    )
    (fp_text user "Author: Antmicro" (at -0.95 -4.169 270) (layer "B.Fab") hide
        (effects (font (size 0.7 0.7) (thickness 0.15)) (justify left bottom mirror))
    )
    (fp_text user "License: Apache-2.0" (at -0.95 -5.169 270) (layer "B.Fab") hide
        (effects (font (size 0.7 0.7) (thickness 0.15)) (justify left bottom mirror))
    )
    (fp_rect (start -0.93 0.47) (end 0.93 -0.47)
      (stroke (width 0.05) (type solid)) (fill none) (layer "B.CrtYd"))
    (fp_rect (start -0.5 0.25) (end 0.5 -0.25)
      (stroke (width 0.15) (type solid)) (fill none) (layer "B.Fab"))
    (pad "1" smd roundrect (at -0.485 0 90) (size 0.59 0.64) (layers "B.Cu" "B.Paste" "B.Mask") (roundrect_rratio 0.25)
      (net 9 "GND") (pintype "passive"))
    (pad "2" smd roundrect (at 0.485 0 90) (size 0.59 0.64) (layers "B.Cu" "B.Paste" "B.Mask") (roundrect_rratio 0.25)
      (net 798 "/Supply/FPGA_PWR_DIS") (pintype "passive"))
  )

  (footprint "data-center-rdimm-ddr4-tester-footprints:R_0603_1608Metric" (layer "B.Cu")
    (at 186.62 83.32)
    (descr "Resistor SMD 0603")
    (tags "resistor SMD 0603")
    (property "Author" "Antmicro")
    (property "License" "Apache-2.0")
    (property "MPN" "CR0603-FX-80R6ELF")
    (property "Manufacturer" "Bourns")
    (property "Sheetfile" "fpga-banks-16-34.kicad_sch")
    (property "Sheetname" "FPGA banks 16-34")
    (property "Tolerance" "1%")
    (property "Val" "80R6")
    (property "ki_description" "80R6 resistor in 0603 package with 1% tolerance")
    (attr smd)
    (fp_text reference "R64" (at -0.91 0.36 180) (layer "B.SilkS")
        (effects (font (size 0.7 0.7) (thickness 0.15)) (justify left bottom mirror))
    )
    (fp_text value "R_80R6_0603" (at 0 -1.6 180) (layer "B.Fab") hide
        (effects (font (size 0.7 0.7) (thickness 0.15)) (justify left bottom mirror))
    )
    (fp_text user "${REFERENCE}" (at -1.25 -3.898 180) (layer "B.Fab") hide
        (effects (font (size 0.7 0.7) (thickness 0.15)) (justify left bottom mirror))
    )
    (fp_text user "Author: Antmicro" (at -1.25 -4.9 180) (layer "B.Fab") hide
        (effects (font (size 0.7 0.7) (thickness 0.15)) (justify left bottom mirror))
    )
    (fp_text user "License: Apache-2.0" (at -1.25 -5.9 180) (layer "B.Fab") hide
        (effects (font (size 0.7 0.7) (thickness 0.15)) (justify left bottom mirror))
    )
    (fp_line (start -0.3 -0.3) (end 0.3 -0.3)
      (stroke (width 0.15) (type solid)) (layer "B.SilkS"))
    (fp_line (start -0.3 0.3) (end 0.3 0.3)
      (stroke (width 0.15) (type solid)) (layer "B.SilkS"))
    (fp_rect (start -1.25 0.7) (end 1.25 -0.7)
      (stroke (width 0.05) (type solid)) (fill none) (layer "B.CrtYd"))
    (fp_rect (start -0.8 0.4) (end 0.8 -0.4)
      (stroke (width 0.15) (type solid)) (fill none) (layer "B.Fab"))
    (pad "1" smd roundrect (at -0.7 0) (size 0.6 0.8) (layers "B.Cu" "B.Paste" "B.Mask") (roundrect_rratio 0.2)
      (net 310 "VRP") (pintype "passive"))
    (pad "2" smd roundrect (at 0.7 0) (size 0.6 0.8) (layers "B.Cu" "B.Paste" "B.Mask") (roundrect_rratio 0.2)
      (net 9 "GND") (pintype "passive"))
  )

  (footprint "data-center-rdimm-ddr4-tester-footprints:C_0402_1005Metric" (layer "B.Cu")
    (at 135.11 97.37)
    (descr "Capacitor SMD 0402")
    (tags "capacitor SMD 0402")
    (property "Author" "Antmicro")
    (property "Dielectric" "X5R")
    (property "License" "Apache-2.0")
    (property "MPN" "GRM155R61H104KE14D")
    (property "Manufacturer" "Murata")
    (property "Sheetfile" "supply.kicad_sch")
    (property "Sheetname" "Supply")
    (property "Val" "100n")
    (property "Voltage" "50V")
    (property "ki_description" " ")
    (attr smd)
    (fp_text reference "C275" (at 1.44 -0.54 180) (layer "B.SilkS")
        (effects (font (size 0.7 0.7) (thickness 0.15)) (justify left bottom mirror))
    )
    (fp_text value "C_100n_0402" (at 0 -1.4 180) (layer "B.Fab") hide
        (effects (font (size 0.7 0.7) (thickness 0.15)) (justify left bottom mirror))
    )
    (fp_text user "Author: Antmicro" (at -0.932 -4.17 180) (layer "B.Fab") hide
        (effects (font (size 0.7 0.7) (thickness 0.15)) (justify left bottom mirror))
    )
    (fp_text user "License: Apache-2.0" (at -0.932 -5.17 180) (layer "B.Fab") hide
        (effects (font (size 0.7 0.7) (thickness 0.15)) (justify left bottom mirror))
    )
    (fp_text user "${REFERENCE}" (at -0.932 -3.168 180) (layer "B.Fab") hide
        (effects (font (size 0.7 0.7) (thickness 0.15)) (justify left bottom mirror))
    )
    (fp_rect (start -0.94 0.47) (end 0.94 -0.47)
      (stroke (width 0.05) (type solid)) (fill none) (layer "B.CrtYd"))
    (fp_rect (start -0.499 0.249) (end 0.499 -0.249)
      (stroke (width 0.15) (type solid)) (fill none) (layer "B.Fab"))
    (pad "1" smd roundrect (at -0.484 0) (size 0.59 0.64) (layers "B.Cu" "B.Paste" "B.Mask") (roundrect_rratio 0.25)
      (net 307 "5V0_SYS") (pintype "passive"))
    (pad "2" smd roundrect (at 0.484 0) (size 0.59 0.64) (layers "B.Cu" "B.Paste" "B.Mask") (roundrect_rratio 0.25)
      (net 9 "GND") (pintype "passive"))
  )

  (footprint "data-center-rdimm-ddr4-tester-footprints:C_1206_3216Metric" (layer "B.Cu")
    (at 193.5 114.03 180)
    (descr "Capacitor SMD 1206")
    (tags "capacitor SMD 1206")
    (property "Author" "Antmicro")
    (property "Dielectric" "")
    (property "License" "Apache-2.0")
    (property "MPN" "C3216X5R1C476M160AB")
    (property "Manufacturer" "TDK")
    (property "Sheetfile" "ethernet.kicad_sch")
    (property "Sheetname" "Ethernet")
    (property "Val" "47u/16V")
    (property "Voltage" "")
    (property "ki_description" " ")
    (attr smd)
    (fp_text reference "C227" (at -1.46 -2.07) (layer "B.SilkS")
        (effects (font (size 0.7 0.7) (thickness 0.15)) (justify left bottom mirror))
    )
    (fp_text value "C_47u_16V_1206" (at 0 -2.1) (layer "B.Fab") hide
        (effects (font (size 0.7 0.7) (thickness 0.15)) (justify left bottom mirror))
    )
    (fp_text user "License: Apache-2.0" (at -2.8 -6.6) (layer "B.Fab") hide
        (effects (font (size 0.7 0.7) (thickness 0.15)) (justify left bottom mirror))
    )
    (fp_text user "Author: Antmicro" (at -2.8 -5.6) (layer "B.Fab") hide
        (effects (font (size 0.7 0.7) (thickness 0.15)) (justify left bottom mirror))
    )
    (fp_text user "${REFERENCE}" (at -2.8 -4.6) (layer "B.Fab") hide
        (effects (font (size 0.7 0.7) (thickness 0.15)) (justify left bottom mirror))
    )
    (fp_line (start -2.625 0.3) (end -2.625 -0.3)
      (stroke (width 0.15) (type solid)) (layer "B.SilkS"))
    (fp_line (start 0.5 -0.9) (end -0.5 -0.9)
      (stroke (width 0.15) (type solid)) (layer "B.SilkS"))
    (fp_line (start 0.5 0.9) (end -0.5 0.9)
      (stroke (width 0.15) (type solid)) (layer "B.SilkS"))
    (fp_line (start 2.625 0.3) (end 2.625 -0.3)
      (stroke (width 0.15) (type solid)) (layer "B.SilkS"))
    (fp_rect (start -2.8 1.15) (end 2.8 -1.15)
      (stroke (width 0.05) (type solid)) (fill none) (layer "B.CrtYd"))
    (fp_rect (start -1.6 0.8) (end 1.6 -0.8)
      (stroke (width 0.15) (type solid)) (fill none) (layer "B.Fab"))
    (pad "1" smd rect (at -1.8 0 180) (size 1.5 1.8) (layers "B.Cu" "B.Paste" "B.Mask")
      (net 864 "VIN_POE") (pintype "passive"))
    (pad "2" smd rect (at 1.8 0 180) (size 1.5 1.8) (layers "B.Cu" "B.Paste" "B.Mask")
      (net 9 "GND") (pintype "passive"))
  )

  (footprint "data-center-rdimm-ddr4-tester-footprints:R_0402_1005Metric" (layer "B.Cu")
    (at 185.65 127.4 180)
    (descr "Resistor SMD 0402")
    (tags "resistor SMD 0402")
    (property "Author" "Antmicro")
    (property "License" "Apache-2.0")
    (property "MPN" "CR0402-FX-4992GLF")
    (property "Manufacturer" "Bourns")
    (property "Sheetfile" "ethernet.kicad_sch")
    (property "Sheetname" "Ethernet")
    (property "Tolerance" "1%")
    (property "Val" "49k9")
    (property "ki_description" "49k9 resistor in 0402 package with 1% tolerance")
    (attr smd)
    (fp_text reference "R159" (at -3.78 -0.37) (layer "B.SilkS")
        (effects (font (size 0.7 0.7) (thickness 0.15)) (justify left bottom mirror))
    )
    (fp_text value "R_49k9_0402" (at 0 -1.4) (layer "B.Fab") hide
        (effects (font (size 0.7 0.7) (thickness 0.15)) (justify left bottom mirror))
    )
    (fp_text user "Author: Antmicro" (at -0.95 -4.169) (layer "B.Fab") hide
        (effects (font (size 0.7 0.7) (thickness 0.15)) (justify left bottom mirror))
    )
    (fp_text user "License: Apache-2.0" (at -0.95 -5.169) (layer "B.Fab") hide
        (effects (font (size 0.7 0.7) (thickness 0.15)) (justify left bottom mirror))
    )
    (fp_text user "${REFERENCE}" (at -0.95 -3.168) (layer "B.Fab") hide
        (effects (font (size 0.7 0.7) (thickness 0.15)) (justify left bottom mirror))
    )
    (fp_rect (start -0.93 0.47) (end 0.93 -0.47)
      (stroke (width 0.05) (type solid)) (fill none) (layer "B.CrtYd"))
    (fp_rect (start -0.5 0.25) (end 0.5 -0.25)
      (stroke (width 0.15) (type solid)) (fill none) (layer "B.Fab"))
    (pad "1" smd roundrect (at -0.485 0 180) (size 0.59 0.64) (layers "B.Cu" "B.Paste" "B.Mask") (roundrect_rratio 0.25)
      (net 381 "/Ethernet/VSS") (pintype "passive"))
    (pad "2" smd roundrect (at 0.485 0 180) (size 0.59 0.64) (layers "B.Cu" "B.Paste" "B.Mask") (roundrect_rratio 0.25)
      (net 617 "/Ethernet/REF") (pintype "passive"))
  )

  (footprint "data-center-rdimm-ddr4-tester-footprints:C_0201" (layer "B.Cu")
    (at 179.925 83.05 90)
    (descr "Capacitor SMD 0201")
    (tags "capacitor SMD 0201")
    (property "Author" "Antmicro")
    (property "Dielectric" "")
    (property "License" "Apache-2.0")
    (property "MPN" "CC0201KRX6S5BB104")
    (property "Manufacturer" "Yaego")
    (property "Sheetfile" "fpga-power.kicad_sch")
    (property "Sheetname" "FPGA power")
    (property "Val" "100n")
    (property "Voltage" "")
    (property "ki_description" " ")
    (attr smd)
    (fp_text reference "C278" (at 1.09 -0.465 270) (layer "B.SilkS")
        (effects (font (size 0.7 0.7) (thickness 0.15)) (justify left bottom mirror))
    )
    (fp_text value "C_100n_0201" (at 0 -1.4 270) (layer "B.Fab") hide
        (effects (font (size 0.7 0.7) (thickness 0.15)) (justify left bottom mirror))
    )
    (fp_text user "Author: Antmicro" (at -0.72 -5.4 270) (layer "B.Fab") hide
        (effects (font (size 0.7 0.7) (thickness 0.15)) (justify left bottom mirror))
    )
    (fp_text user "${REFERENCE}" (at -0.72 -3.4 270) (layer "B.Fab") hide
        (effects (font (size 0.7 0.7) (thickness 0.15)) (justify left bottom mirror))
    )
    (fp_text user "License: Apache-2.0" (at -0.72 -4.4 270) (layer "B.Fab") hide
        (effects (font (size 0.7 0.7) (thickness 0.15)) (justify left bottom mirror))
    )
    (fp_rect (start -0.72 0.38) (end 0.72 -0.38)
      (stroke (width 0.05) (type solid)) (fill none) (layer "B.CrtYd"))
    (fp_rect (start 0.3 -0.15) (end -0.301 0.149)
      (stroke (width 0.15) (type solid)) (fill none) (layer "B.Fab"))
    (pad "" smd roundrect (at -0.349 0.002 90) (size 0.318 0.36) (layers "B.Paste") (roundrect_rratio 0.25))
    (pad "" smd roundrect (at 0.341 0.002 90) (size 0.318 0.36) (layers "B.Paste") (roundrect_rratio 0.25))
    (pad "1" smd roundrect (at -0.321 0.002 90) (size 0.46 0.4) (layers "B.Cu" "B.Mask") (roundrect_rratio 0.25)
      (net 77 "VDDQ") (pintype "passive"))
    (pad "2" smd roundrect (at 0.32 0.002 90) (size 0.46 0.4) (layers "B.Cu" "B.Mask") (roundrect_rratio 0.25)
      (net 9 "GND") (pintype "passive"))
  )

  (footprint "data-center-rdimm-ddr4-tester-footprints:C_0402_1005Metric" (layer "B.Cu")
    (at 133.5 119.3 180)
    (descr "Capacitor SMD 0402")
    (tags "capacitor SMD 0402")
    (property "Author" "Antmicro")
    (property "Dielectric" "")
    (property "License" "Apache-2.0")
    (property "MPN" "C1005X6S1A105K050BC")
    (property "Manufacturer" "TDK")
    (property "Sheetfile" "interfaces.kicad_sch")
    (property "Sheetname" "Interfaces")
    (property "Val" "1u")
    (property "Voltage" "")
    (property "ki_description" " ")
    (attr smd)
    (fp_text reference "C10" (at -1.13 0.55) (layer "B.SilkS")
        (effects (font (size 0.7 0.7) (thickness 0.15)) (justify left bottom mirror))
    )
    (fp_text value "C_1u_0402" (at 0 -1.4) (layer "B.Fab") hide
        (effects (font (size 0.7 0.7) (thickness 0.15)) (justify left bottom mirror))
    )
    (fp_text user "${REFERENCE}" (at -0.932 -3.168) (layer "B.Fab") hide
        (effects (font (size 0.7 0.7) (thickness 0.15)) (justify left bottom mirror))
    )
    (fp_text user "Author: Antmicro" (at -0.932 -4.17) (layer "B.Fab") hide
        (effects (font (size 0.7 0.7) (thickness 0.15)) (justify left bottom mirror))
    )
    (fp_text user "License: Apache-2.0" (at -0.932 -5.17) (layer "B.Fab") hide
        (effects (font (size 0.7 0.7) (thickness 0.15)) (justify left bottom mirror))
    )
    (fp_rect (start -0.94 0.47) (end 0.94 -0.47)
      (stroke (width 0.05) (type solid)) (fill none) (layer "B.CrtYd"))
    (fp_rect (start -0.499 0.249) (end 0.499 -0.249)
      (stroke (width 0.15) (type solid)) (fill none) (layer "B.Fab"))
    (pad "1" smd roundrect (at -0.484 0 180) (size 0.59 0.64) (layers "B.Cu" "B.Paste" "B.Mask") (roundrect_rratio 0.25)
      (net 143 "3V3_SYS") (pintype "passive"))
    (pad "2" smd roundrect (at 0.484 0 180) (size 0.59 0.64) (layers "B.Cu" "B.Paste" "B.Mask") (roundrect_rratio 0.25)
      (net 9 "GND") (pintype "passive"))
  )

  (footprint "data-center-rdimm-ddr4-tester-footprints:C_0603_1608Metric" (layer "B.Cu")
    (at 182 78.975)
    (descr "Capacitor SMD 0603")
    (tags "capacitor 0603")
    (property "Author" "Antmicro")
    (property "Dielectric" "")
    (property "License" "Apache-2.0")
    (property "MPN" "GRM188R60J476ME15D")
    (property "Manufacturer" "Murata")
    (property "Sheetfile" "fpga-power.kicad_sch")
    (property "Sheetname" "FPGA power")
    (property "Val" "47u")
    (property "Voltage" "")
    (property "ki_description" " ")
    (attr smd)
    (fp_text reference "C81" (at 0.12 1.285 180) (layer "B.SilkS")
        (effects (font (size 0.7 0.7) (thickness 0.15)) (justify left bottom mirror))
    )
    (fp_text value "C_47u_0603" (at 0 -1.6 180) (layer "B.Fab") hide
        (effects (font (size 0.7 0.7) (thickness 0.15)) (justify left bottom mirror))
    )
    (fp_text user "Author: Antmicro" (at -1.682 -4.894 180) (layer "B.Fab") hide
        (effects (font (size 0.7 0.7) (thickness 0.15)) (justify left bottom mirror))
    )
    (fp_text user "License: Apache-2.0" (at -1.682 -5.895 180) (layer "B.Fab") hide
        (effects (font (size 0.7 0.7) (thickness 0.15)) (justify left bottom mirror))
    )
    (fp_text user "${REFERENCE}" (at -1.682 -3.895 180) (layer "B.Fab") hide
        (effects (font (size 0.7 0.7) (thickness 0.15)) (justify left bottom mirror))
    )
    (fp_line (start -0.3 -0.3) (end 0.3 -0.3)
      (stroke (width 0.15) (type solid)) (layer "B.SilkS"))
    (fp_line (start -0.3 0.3) (end 0.3 0.3)
      (stroke (width 0.15) (type solid)) (layer "B.SilkS"))
    (fp_rect (start -1.24 0.7) (end 1.24 -0.7)
      (stroke (width 0.05) (type solid)) (fill none) (layer "B.CrtYd"))
    (fp_rect (start -0.8 0.4) (end 0.8 -0.4)
      (stroke (width 0.15) (type solid)) (fill none) (layer "B.Fab"))
    (pad "1" smd roundrect (at -0.7 0) (size 0.6 0.8) (layers "B.Cu" "B.Paste" "B.Mask") (roundrect_rratio 0.2)
      (net 77 "VDDQ") (pintype "passive"))
    (pad "2" smd roundrect (at 0.7 0) (size 0.6 0.8) (layers "B.Cu" "B.Paste" "B.Mask") (roundrect_rratio 0.2)
      (net 9 "GND") (pintype "passive"))
  )

  (footprint "data-center-rdimm-ddr4-tester-footprints:C_0201" (layer "B.Cu")
    (at 180.65 95.575)
    (descr "Capacitor SMD 0201")
    (tags "capacitor SMD 0201")
    (property "Author" "Antmicro")
    (property "Dielectric" "")
    (property "License" "Apache-2.0")
    (property "MPN" "CC0201KRX6S5BB104")
    (property "Manufacturer" "Yaego")
    (property "Sheetfile" "fpga-power.kicad_sch")
    (property "Sheetname" "FPGA power")
    (property "Val" "100n")
    (property "Voltage" "")
    (property "ki_description" " ")
    (attr smd)
    (fp_text reference "C309" (at 3.46 0.265 180) (layer "B.SilkS")
        (effects (font (size 0.7 0.7) (thickness 0.15)) (justify left bottom mirror))
    )
    (fp_text value "C_100n_0201" (at 0 -1.4 180) (layer "B.Fab") hide
        (effects (font (size 0.7 0.7) (thickness 0.15)) (justify left bottom mirror))
    )
    (fp_text user "${REFERENCE}" (at -0.72 -3.4 180) (layer "B.Fab") hide
        (effects (font (size 0.7 0.7) (thickness 0.15)) (justify left bottom mirror))
    )
    (fp_text user "Author: Antmicro" (at -0.72 -5.4 180) (layer "B.Fab") hide
        (effects (font (size 0.7 0.7) (thickness 0.15)) (justify left bottom mirror))
    )
    (fp_text user "License: Apache-2.0" (at -0.72 -4.4 180) (layer "B.Fab") hide
        (effects (font (size 0.7 0.7) (thickness 0.15)) (justify left bottom mirror))
    )
    (fp_rect (start -0.72 0.38) (end 0.72 -0.38)
      (stroke (width 0.05) (type solid)) (fill none) (layer "B.CrtYd"))
    (fp_rect (start 0.3 -0.15) (end -0.301 0.149)
      (stroke (width 0.15) (type solid)) (fill none) (layer "B.Fab"))
    (pad "" smd roundrect (at -0.349 0.002) (size 0.318 0.36) (layers "B.Paste") (roundrect_rratio 0.25))
    (pad "" smd roundrect (at 0.341 0.002) (size 0.318 0.36) (layers "B.Paste") (roundrect_rratio 0.25))
    (pad "1" smd roundrect (at -0.321 0.002) (size 0.46 0.4) (layers "B.Cu" "B.Mask") (roundrect_rratio 0.25)
      (net 143 "3V3_SYS") (pintype "passive"))
    (pad "2" smd roundrect (at 0.32 0.002) (size 0.46 0.4) (layers "B.Cu" "B.Mask") (roundrect_rratio 0.25)
      (net 9 "GND") (pintype "passive"))
  )

  (footprint "data-center-rdimm-ddr4-tester-footprints:C_0201" (layer "B.Cu")
    (at 182.47 99.67)
    (descr "Capacitor SMD 0201")
    (tags "capacitor SMD 0201")
    (property "Author" "Antmicro")
    (property "Dielectric" "")
    (property "License" "Apache-2.0")
    (property "MPN" "CC0201KRX6S5BB104")
    (property "Manufacturer" "Yaego")
    (property "Sheetfile" "fpga-power.kicad_sch")
    (property "Sheetname" "FPGA power")
    (property "Val" "100n")
    (property "Voltage" "")
    (property "ki_description" " ")
    (attr smd)
    (fp_text reference "C308" (at 1.05 1.17 180) (layer "B.SilkS")
        (effects (font (size 0.7 0.7) (thickness 0.15)) (justify left bottom mirror))
    )
    (fp_text value "C_100n_0201" (at 0 -1.4 180) (layer "B.Fab") hide
        (effects (font (size 0.7 0.7) (thickness 0.15)) (justify left bottom mirror))
    )
    (fp_text user "${REFERENCE}" (at -0.72 -3.4 180) (layer "B.Fab") hide
        (effects (font (size 0.7 0.7) (thickness 0.15)) (justify left bottom mirror))
    )
    (fp_text user "Author: Antmicro" (at -0.72 -5.4 180) (layer "B.Fab") hide
        (effects (font (size 0.7 0.7) (thickness 0.15)) (justify left bottom mirror))
    )
    (fp_text user "License: Apache-2.0" (at -0.72 -4.4 180) (layer "B.Fab") hide
        (effects (font (size 0.7 0.7) (thickness 0.15)) (justify left bottom mirror))
    )
    (fp_rect (start -0.72 0.38) (end 0.72 -0.38)
      (stroke (width 0.05) (type solid)) (fill none) (layer "B.CrtYd"))
    (fp_rect (start 0.3 -0.15) (end -0.301 0.149)
      (stroke (width 0.15) (type solid)) (fill none) (layer "B.Fab"))
    (pad "" smd roundrect (at -0.349 0.002) (size 0.318 0.36) (layers "B.Paste") (roundrect_rratio 0.25))
    (pad "" smd roundrect (at 0.341 0.002) (size 0.318 0.36) (layers "B.Paste") (roundrect_rratio 0.25))
    (pad "1" smd roundrect (at -0.321 0.002) (size 0.46 0.4) (layers "B.Cu" "B.Mask") (roundrect_rratio 0.25)
      (net 143 "3V3_SYS") (pintype "passive"))
    (pad "2" smd roundrect (at 0.32 0.002) (size 0.46 0.4) (layers "B.Cu" "B.Mask") (roundrect_rratio 0.25)
      (net 9 "GND") (pintype "passive"))
  )

  (footprint "data-center-rdimm-ddr4-tester-footprints:C_0201" (layer "B.Cu")
    (at 177.85 101.56 180)
    (descr "Capacitor SMD 0201")
    (tags "capacitor SMD 0201")
    (property "Author" "Antmicro")
    (property "Dielectric" "")
    (property "License" "Apache-2.0")
    (property "MPN" "CC0201KRX6S5BB104")
    (property "Manufacturer" "Yaego")
    (property "Sheetfile" "fpga-power.kicad_sch")
    (property "Sheetname" "FPGA power")
    (property "Val" "100n")
    (property "Voltage" "")
    (property "ki_description" " ")
    (attr smd)
    (fp_text reference "C83" (at -1.09 0.46) (layer "B.SilkS")
        (effects (font (size 0.7 0.7) (thickness 0.15)) (justify left bottom mirror))
    )
    (fp_text value "C_100n_0201" (at 0 -1.4) (layer "B.Fab") hide
        (effects (font (size 0.7 0.7) (thickness 0.15)) (justify left bottom mirror))
    )
    (fp_text user "License: Apache-2.0" (at -0.72 -4.4) (layer "B.Fab") hide
        (effects (font (size 0.7 0.7) (thickness 0.15)) (justify left bottom mirror))
    )
    (fp_text user "Author: Antmicro" (at -0.72 -5.4) (layer "B.Fab") hide
        (effects (font (size 0.7 0.7) (thickness 0.15)) (justify left bottom mirror))
    )
    (fp_text user "${REFERENCE}" (at -0.72 -3.4) (layer "B.Fab") hide
        (effects (font (size 0.7 0.7) (thickness 0.15)) (justify left bottom mirror))
    )
    (fp_rect (start -0.72 0.38) (end 0.72 -0.38)
      (stroke (width 0.05) (type solid)) (fill none) (layer "B.CrtYd"))
    (fp_rect (start 0.3 -0.15) (end -0.301 0.149)
      (stroke (width 0.15) (type solid)) (fill none) (layer "B.Fab"))
    (pad "" smd roundrect (at -0.349 0.002 180) (size 0.318 0.36) (layers "B.Paste") (roundrect_rratio 0.25))
    (pad "" smd roundrect (at 0.341 0.002 180) (size 0.318 0.36) (layers "B.Paste") (roundrect_rratio 0.25))
    (pad "1" smd roundrect (at -0.321 0.002 180) (size 0.46 0.4) (layers "B.Cu" "B.Mask") (roundrect_rratio 0.25)
      (net 143 "3V3_SYS") (pintype "passive"))
    (pad "2" smd roundrect (at 0.32 0.002 180) (size 0.46 0.4) (layers "B.Cu" "B.Mask") (roundrect_rratio 0.25)
      (net 9 "GND") (pintype "passive"))
  )

  (footprint "data-center-rdimm-ddr4-tester-footprints:C_0201" (layer "B.Cu")
    (at 171.075 78.1 -90)
    (descr "Capacitor SMD 0201")
    (tags "capacitor SMD 0201")
    (property "Author" "Antmicro")
    (property "Dielectric" "")
    (property "License" "Apache-2.0")
    (property "MPN" "CC0201KRX6S5BB104")
    (property "Manufacturer" "Yaego")
    (property "Sheetfile" "fpga-power.kicad_sch")
    (property "Sheetname" "FPGA power")
    (property "Val" "100n")
    (property "Voltage" "")
    (property "ki_description" " ")
    (attr smd)
    (fp_text reference "C90" (at -1.1 0.425 90) (layer "B.SilkS")
        (effects (font (size 0.7 0.7) (thickness 0.15)) (justify left bottom mirror))
    )
    (fp_text value "C_100n_0201" (at 0 -1.4 90) (layer "B.Fab") hide
        (effects (font (size 0.7 0.7) (thickness 0.15)) (justify left bottom mirror))
    )
    (fp_text user "Author: Antmicro" (at -0.72 -5.4 90) (layer "B.Fab") hide
        (effects (font (size 0.7 0.7) (thickness 0.15)) (justify left bottom mirror))
    )
    (fp_text user "License: Apache-2.0" (at -0.72 -4.4 90) (layer "B.Fab") hide
        (effects (font (size 0.7 0.7) (thickness 0.15)) (justify left bottom mirror))
    )
    (fp_text user "${REFERENCE}" (at -0.72 -3.4 90) (layer "B.Fab") hide
        (effects (font (size 0.7 0.7) (thickness 0.15)) (justify left bottom mirror))
    )
    (fp_rect (start -0.72 0.38) (end 0.72 -0.38)
      (stroke (width 0.05) (type solid)) (fill none) (layer "B.CrtYd"))
    (fp_rect (start 0.3 -0.15) (end -0.301 0.149)
      (stroke (width 0.15) (type solid)) (fill none) (layer "B.Fab"))
    (pad "" smd roundrect (at -0.349 0.002 270) (size 0.318 0.36) (layers "B.Paste") (roundrect_rratio 0.25))
    (pad "" smd roundrect (at 0.341 0.002 270) (size 0.318 0.36) (layers "B.Paste") (roundrect_rratio 0.25))
    (pad "1" smd roundrect (at -0.321 0.002 270) (size 0.46 0.4) (layers "B.Cu" "B.Mask") (roundrect_rratio 0.25)
      (net 143 "3V3_SYS") (pintype "passive"))
    (pad "2" smd roundrect (at 0.32 0.002 270) (size 0.46 0.4) (layers "B.Cu" "B.Mask") (roundrect_rratio 0.25)
      (net 9 "GND") (pintype "passive"))
  )

  (footprint "data-center-rdimm-ddr4-tester-footprints:C_0201" (layer "B.Cu")
    (at 196.1 100.525)
    (descr "Capacitor SMD 0201")
    (tags "capacitor SMD 0201")
    (property "Author" "Antmicro")
    (property "Dielectric" "")
    (property "License" "Apache-2.0")
    (property "MPN" "CC0201KRX6S5BB104")
    (property "Manufacturer" "Yaego")
    (property "Sheetfile" "fpga-power.kicad_sch")
    (property "Sheetname" "FPGA power")
    (property "Val" "100n")
    (property "Voltage" "")
    (property "ki_description" " ")
    (attr smd)
    (fp_text reference "C255" (at 3.43 0.365 180) (layer "B.SilkS")
        (effects (font (size 0.7 0.7) (thickness 0.15)) (justify left bottom mirror))
    )
    (fp_text value "C_100n_0201" (at 0 -1.4 180) (layer "B.Fab") hide
        (effects (font (size 0.7 0.7) (thickness 0.15)) (justify left bottom mirror))
    )
    (fp_text user "Author: Antmicro" (at -0.72 -5.4 180) (layer "B.Fab") hide
        (effects (font (size 0.7 0.7) (thickness 0.15)) (justify left bottom mirror))
    )
    (fp_text user "License: Apache-2.0" (at -0.72 -4.4 180) (layer "B.Fab") hide
        (effects (font (size 0.7 0.7) (thickness 0.15)) (justify left bottom mirror))
    )
    (fp_text user "${REFERENCE}" (at -0.72 -3.4 180) (layer "B.Fab") hide
        (effects (font (size 0.7 0.7) (thickness 0.15)) (justify left bottom mirror))
    )
    (fp_rect (start -0.72 0.38) (end 0.72 -0.38)
      (stroke (width 0.05) (type solid)) (fill none) (layer "B.CrtYd"))
    (fp_rect (start 0.3 -0.15) (end -0.301 0.149)
      (stroke (width 0.15) (type solid)) (fill none) (layer "B.Fab"))
    (pad "" smd roundrect (at -0.349 0.002) (size 0.318 0.36) (layers "B.Paste") (roundrect_rratio 0.25))
    (pad "" smd roundrect (at 0.341 0.002) (size 0.318 0.36) (layers "B.Paste") (roundrect_rratio 0.25))
    (pad "1" smd roundrect (at -0.321 0.002) (size 0.46 0.4) (layers "B.Cu" "B.Mask") (roundrect_rratio 0.25)
      (net 306 "1V2_SYS") (pintype "passive"))
    (pad "2" smd roundrect (at 0.32 0.002) (size 0.46 0.4) (layers "B.Cu" "B.Mask") (roundrect_rratio 0.25)
      (net 9 "GND") (pintype "passive"))
  )

  (footprint "data-center-rdimm-ddr4-tester-footprints:C_0402_1005Metric" (layer "B.Cu")
    (at 119.67 99.499)
    (descr "Capacitor SMD 0402")
    (tags "capacitor SMD 0402")
    (property "Author" "Antmicro")
    (property "Dielectric" "X5R")
    (property "License" "Apache-2.0")
    (property "MPN" "GRM155R61H104KE14D")
    (property "Manufacturer" "Murata")
    (property "Sheetfile" "supply.kicad_sch")
    (property "Sheetname" "Supply")
    (property "Val" "100n")
    (property "Voltage" "50V")
    (property "ki_description" " ")
    (attr smd)
    (fp_text reference "C237" (at 1.42 1.351 180) (layer "B.SilkS")
        (effects (font (size 0.7 0.7) (thickness 0.15)) (justify left bottom mirror))
    )
    (fp_text value "C_100n_0402" (at 0 -1.4 180) (layer "B.Fab") hide
        (effects (font (size 0.7 0.7) (thickness 0.15)) (justify left bottom mirror))
    )
    (fp_text user "Author: Antmicro" (at -0.932 -4.17 180) (layer "B.Fab") hide
        (effects (font (size 0.7 0.7) (thickness 0.15)) (justify left bottom mirror))
    )
    (fp_text user "License: Apache-2.0" (at -0.932 -5.17 180) (layer "B.Fab") hide
        (effects (font (size 0.7 0.7) (thickness 0.15)) (justify left bottom mirror))
    )
    (fp_text user "${REFERENCE}" (at -0.932 -3.168 180) (layer "B.Fab") hide
        (effects (font (size 0.7 0.7) (thickness 0.15)) (justify left bottom mirror))
    )
    (fp_rect (start -0.94 0.47) (end 0.94 -0.47)
      (stroke (width 0.05) (type solid)) (fill none) (layer "B.CrtYd"))
    (fp_rect (start -0.499 0.249) (end 0.499 -0.249)
      (stroke (width 0.15) (type solid)) (fill none) (layer "B.Fab"))
    (pad "1" smd roundrect (at -0.484 0) (size 0.59 0.64) (layers "B.Cu" "B.Paste" "B.Mask") (roundrect_rratio 0.25)
      (net 307 "5V0_SYS") (pintype "passive"))
    (pad "2" smd roundrect (at 0.484 0) (size 0.59 0.64) (layers "B.Cu" "B.Paste" "B.Mask") (roundrect_rratio 0.25)
      (net 9 "GND") (pintype "passive"))
  )

  (footprint "data-center-rdimm-ddr4-tester-footprints:R_0402_1005Metric" (layer "B.Cu")
    (at 199.05 54.75 -90)
    (descr "Resistor SMD 0402")
    (tags "resistor SMD 0402")
    (property "Author" "Antmicro")
    (property "Current" "1A")
    (property "DNP" "DNP")
    (property "License" "Apache-2.0")
    (property "MPN" "ERJ2GE0R00X")
    (property "Manufacturer" "Panasonic")
    (property "Sheetfile" "DDR4.kicad_sch")
    (property "Sheetname" "DDR4")
    (property "Tolerance" "")
    (property "Val" "0R")
    (property "dnp" "")
    (property "exclude_from_bom" "")
    (property "ki_description" "0R resistor in 0402 package with unspecified tolerance")
    (attr exclude_from_pos_files exclude_from_bom)
    (fp_text reference "R185" (at -4.05 -0.4 90) (layer "B.SilkS")
        (effects (font (size 0.7 0.7) (thickness 0.15)) (justify left bottom mirror))
    )
    (fp_text value "R_0R_0402" (at 0 -1.4 90) (layer "B.Fab") hide
        (effects (font (size 0.7 0.7) (thickness 0.15)) (justify left bottom mirror))
    )
    (fp_text user "${REFERENCE}" (at -0.95 -3.168 90) (layer "B.Fab") hide
        (effects (font (size 0.7 0.7) (thickness 0.15)) (justify left bottom mirror))
    )
    (fp_text user "License: Apache-2.0" (at -0.95 -5.169 90) (layer "B.Fab") hide
        (effects (font (size 0.7 0.7) (thickness 0.15)) (justify left bottom mirror))
    )
    (fp_text user "Author: Antmicro" (at -0.95 -4.169 90) (layer "B.Fab") hide
        (effects (font (size 0.7 0.7) (thickness 0.15)) (justify left bottom mirror))
    )
    (fp_rect (start -0.93 0.47) (end 0.93 -0.47)
      (stroke (width 0.05) (type solid)) (fill none) (layer "B.CrtYd"))
    (fp_rect (start -0.5 0.25) (end 0.5 -0.25)
      (stroke (width 0.15) (type solid)) (fill none) (layer "B.Fab"))
    (pad "1" smd roundrect (at -0.485 0 270) (size 0.59 0.64) (layers "B.Cu" "B.Paste" "B.Mask") (roundrect_rratio 0.25)
      (net 9 "GND") (pintype "passive"))
    (pad "2" smd roundrect (at 0.485 0 270) (size 0.59 0.64) (layers "B.Cu" "B.Paste" "B.Mask") (roundrect_rratio 0.25)
      (net 789 "DDR_PRESENCE") (pintype "passive"))
  )

  (footprint "data-center-rdimm-ddr4-tester-footprints:MicroSD_Wurth_693071020811" (layer "B.Cu")
    (at 132.95 129.009 180)
    (descr "SMT MICRO SD CARD CONNECTOR")
    (property "Author" "Antmicro")
    (property "License" "Apache-2.0")
    (property "MPN" "693071020811")
    (property "Manufacturer" "Würth Elektronik")
    (property "Sheetfile" "interfaces.kicad_sch")
    (property "Sheetname" "Interfaces")
    (property "ki_description" "SMT MICRO SD CARD CONNECTOR, PUSH-PUSH")
    (attr smd)
    (fp_text reference "J7" (at -8.93 -6.131) (layer "B.SilkS")
        (effects (font (size 0.7 0.7) (thickness 0.15)) (justify left bottom mirror))
    )
    (fp_text value "MicroSD_693071020811" (at -8.5 -11.5) (layer "B.Fab") hide
        (effects (font (size 0.7 0.7) (thickness 0.15)) (justify left bottom mirror))
    )
    (fp_text user "Author: Antmicro" (at -8.5 -14.5) (layer "B.Fab") hide
        (effects (font (size 0.7 0.7) (thickness 0.15)) (justify left bottom mirror))
    )
    (fp_text user "${REFERENCE}" (at -8.5 -13) (layer "B.Fab") hide
        (effects (font (size 0.7 0.7) (thickness 0.15)) (justify left bottom mirror))
    )
    (fp_text user "License: Apache-2.0" (at -8.5 -16) (layer "B.Fab") hide
        (effects (font (size 0.7 0.7) (thickness 0.15)) (justify left bottom mirror))
    )
    (fp_line (start -7.351 -1.431) (end -7.351 5.268)
      (stroke (width 0.15) (type solid)) (layer "B.SilkS"))
    (fp_line (start 2.8 8.4) (end 2.8 7.149)
      (stroke (width 0.15) (type solid)) (layer "B.SilkS"))
    (fp_line (start 6.2 7.149) (end 2.8 7.149)
      (stroke (width 0.15) (type solid)) (layer "B.SilkS"))
    (fp_line (start 7.349 -1.431) (end 7.349 5.268)
      (stroke (width 0.15) (type solid)) (layer "B.SilkS"))
    (fp_line (start 2.7 -2.982) (end 3.398 -2.982)
      (stroke (width 0.01) (type solid)) (layer "Edge.Cuts"))
    (fp_line (start 3.398 -3.982) (end 2.7 -3.982)
      (stroke (width 0.01) (type solid)) (layer "Edge.Cuts"))
    (fp_arc (start 2.2 -3.482) (mid 2.346 -3.836) (end 2.7 -3.982)
      (stroke (width 0.01) (type solid)) (layer "Edge.Cuts"))
    (fp_arc (start 2.7 -2.982) (mid 2.346 -3.128) (end 2.2 -3.482)
      (stroke (width 0.01) (type solid)) (layer "Edge.Cuts"))
    (fp_arc (start 3.398 -3.982) (mid 3.752498 -3.836498) (end 3.898 -3.482)
      (stroke (width 0.01) (type solid)) (layer "Edge.Cuts"))
    (fp_arc (start 3.898 -3.482) (mid 3.752498 -3.127502) (end 3.398 -2.982)
      (stroke (width 0.01) (type solid)) (layer "Edge.Cuts"))
    (fp_line (start -9.1 7.6) (end -9.1 5.45)
      (stroke (width 0.05) (type solid)) (layer "B.CrtYd"))
    (fp_line (start -9.1 7.6) (end -7.05 7.6)
      (stroke (width 0.05) (type solid)) (layer "B.CrtYd"))
    (fp_line (start -8.7 -4.55) (end -8.7 -1.6)
      (stroke (width 0.05) (type solid)) (layer "B.CrtYd"))
    (fp_line (start -8.7 -4.55) (end -7.55 -4.55)
      (stroke (width 0.05) (type solid)) (layer "B.CrtYd"))
    (fp_line (start -7.55 -7.7) (end -7.55 -4.55)
      (stroke (width 0.05) (type solid)) (layer "B.CrtYd"))
    (fp_line (start -7.55 -1.6) (end -8.7 -1.6)
      (stroke (width 0.05) (type solid)) (layer "B.CrtYd"))
    (fp_line (start -7.55 5.45) (end -9.1 5.45)
      (stroke (width 0.05) (type solid)) (layer "B.CrtYd"))
    (fp_line (start -7.55 5.45) (end -7.55 -1.6)
      (stroke (width 0.05) (type solid)) (layer "B.CrtYd"))
    (fp_line (start -7.05 8.7) (end -7.05 7.6)
      (stroke (width 0.05) (type solid)) (layer "B.CrtYd"))
    (fp_line (start -7.05 8.7) (end 2.75 8.7)
      (stroke (width 0.05) (type solid)) (layer "B.CrtYd"))
    (fp_line (start 2.75 7.6) (end 2.75 8.7)
      (stroke (width 0.05) (type solid)) (layer "B.CrtYd"))
    (fp_line (start 7.5 -7.7) (end -7.55 -7.7)
      (stroke (width 0.05) (type solid)) (layer "B.CrtYd"))
    (fp_line (start 7.5 -7.7) (end 7.5 -4.55)
      (stroke (width 0.05) (type solid)) (layer "B.CrtYd"))
    (fp_line (start 7.5 -1.6) (end 7.5 5.45)
      (stroke (width 0.05) (type solid)) (layer "B.CrtYd"))
    (fp_line (start 7.5 -1.6) (end 8.7 -1.6)
      (stroke (width 0.05) (type solid)) (layer "B.CrtYd"))
    (fp_line (start 7.5 5.45) (end 8.4 5.45)
      (stroke (width 0.05) (type solid)) (layer "B.CrtYd"))
    (fp_line (start 8.4 7.6) (end 2.75 7.6)
      (stroke (width 0.05) (type solid)) (layer "B.CrtYd"))
    (fp_line (start 8.4 7.6) (end 8.4 5.45)
      (stroke (width 0.05) (type solid)) (layer "B.CrtYd"))
    (fp_line (start 8.7 -4.55) (end 7.5 -4.55)
      (stroke (width 0.05) (type solid)) (layer "B.CrtYd"))
    (fp_line (start 8.7 -4.55) (end 8.7 -1.6)
      (stroke (width 0.05) (type solid)) (layer "B.CrtYd"))
    (fp_line (start -7.351 -7.501) (end 7.349 -7.501)
      (stroke (width 0.15) (type solid)) (layer "B.Fab"))
    (fp_line (start -7.351 7.149) (end -7.351 -7.352)
      (stroke (width 0.15) (type solid)) (layer "B.Fab"))
    (fp_line (start 7.349 -7.352) (end 7.349 7.149)
      (stroke (width 0.15) (type solid)) (layer "B.Fab"))
    (fp_line (start 7.349 7.149) (end -7.351 7.149)
      (stroke (width 0.15) (type solid)) (layer "B.Fab"))
    (pad "" np_thru_hole circle (at -4.952 -3.482 180) (size 1 1) (drill 1) (layers "*.Cu" "*.Mask"))
    (pad "1" smd rect (at 2.249 7.569 180) (size 0.7 1.9) (layers "B.Cu" "B.Paste" "B.Mask")
      (net 87 "SD_DAT2") (pinfunction "DAT2") (pintype "bidirectional"))
    (pad "2" smd rect (at 1.148 7.569 180) (size 0.7 1.9) (layers "B.Cu" "B.Paste" "B.Mask")
      (net 86 "SD_DAT3") (pinfunction "DAT3/CD") (pintype "bidirectional"))
    (pad "3" smd rect (at 0.05 7.569 180) (size 0.7 1.9) (layers "B.Cu" "B.Paste" "B.Mask")
      (net 85 "SD_CMD") (pinfunction "CMD") (pintype "input"))
    (pad "4" smd rect (at -1.051 7.569 180) (size 0.7 1.9) (layers "B.Cu" "B.Paste" "B.Mask")
      (net 143 "3V3_SYS") (pinfunction "VDD") (pintype "power_in"))
    (pad "5" smd rect (at -2.15 7.569 180) (size 0.7 1.9) (layers "B.Cu" "B.Paste" "B.Mask")
      (net 84 "SD_CLK") (pinfunction "CLK") (pintype "input"))
    (pad "6" smd rect (at -3.25 7.569 180) (size 0.7 1.9) (layers "B.Cu" "B.Paste" "B.Mask")
      (net 9 "GND") (pinfunction "VSS") (pintype "passive"))
    (pad "7" smd rect (at -4.351 7.569 180) (size 0.7 1.9) (layers "B.Cu" "B.Paste" "B.Mask")
      (net 83 "SD_DAT0") (pinfunction "DAT0") (pintype "input"))
    (pad "8" smd rect (at -5.452 7.569 180) (size 0.7 1.9) (layers "B.Cu" "B.Paste" "B.Mask")
      (net 82 "SD_DAT1") (pinfunction "DAT1") (pintype "input"))
    (pad "9" smd rect (at -6.55 7.569 180) (size 0.7 1.9) (layers "B.Cu" "B.Paste" "B.Mask")
      (net 564 "Net-(J7-CD_SW1)") (pinfunction "CD_SW1") (pintype "passive"))
    (pad "SH" smd rect (at -8.1 6.518 180) (size 1.7 1.8) (layers "B.Cu" "B.Paste" "B.Mask")
      (net 9 "GND") (pinfunction "SH") (pintype "passive"))
    (pad "SH" smd rect (at -7.851 -3.081 180) (size 1.4 2.6) (layers "B.Cu" "B.Paste" "B.Mask")
      (net 9 "GND") (pinfunction "SH") (pintype "passive"))
    (pad "SH" smd rect (at 7.4 6.518 180) (size 1.7 1.8) (layers "B.Cu" "B.Paste" "B.Mask")
      (net 9 "GND") (pinfunction "SH") (pintype "passive"))
    (pad "SH" smd rect (at 7.849 -3.081 180) (size 1.4 2.6) (layers "B.Cu" "B.Paste" "B.Mask")
      (net 9 "GND") (pinfunction "SH") (pintype "passive"))
  )

  (footprint "data-center-rdimm-ddr4-tester-footprints:R_0603_1608Metric" (layer "B.Cu")
    (at 170.85 132.95 180)
    (descr "Resistor SMD 0603")
    (tags "resistor SMD 0603")
    (property "Author" "Antmicro")
    (property "License" "Apache-2.0")
    (property "MPN" "CR0603-FX-1001ELF")
    (property "Manufacturer" "Bourns")
    (property "Sheetfile" "ethernet.kicad_sch")
    (property "Sheetname" "Ethernet")
    (property "Tolerance" "1%")
    (property "Val" "1k")
    (property "ki_description" "1k resistor in 0603 package with 1% tolerance")
    (attr smd)
    (fp_text reference "R183" (at -1.44 -1.4) (layer "B.SilkS")
        (effects (font (size 0.7 0.7) (thickness 0.15)) (justify left bottom mirror))
    )
    (fp_text value "R_1k_0603" (at 0 -1.6) (layer "B.Fab") hide
        (effects (font (size 0.7 0.7) (thickness 0.15)) (justify left bottom mirror))
    )
    (fp_text user "${REFERENCE}" (at -1.25 -3.898) (layer "B.Fab") hide
        (effects (font (size 0.7 0.7) (thickness 0.15)) (justify left bottom mirror))
    )
    (fp_text user "Author: Antmicro" (at -1.25 -4.9) (layer "B.Fab") hide
        (effects (font (size 0.7 0.7) (thickness 0.15)) (justify left bottom mirror))
    )
    (fp_text user "License: Apache-2.0" (at -1.25 -5.9) (layer "B.Fab") hide
        (effects (font (size 0.7 0.7) (thickness 0.15)) (justify left bottom mirror))
    )
    (fp_line (start -0.3 -0.3) (end 0.3 -0.3)
      (stroke (width 0.15) (type solid)) (layer "B.SilkS"))
    (fp_line (start -0.3 0.3) (end 0.3 0.3)
      (stroke (width 0.15) (type solid)) (layer "B.SilkS"))
    (fp_rect (start -1.25 0.7) (end 1.25 -0.7)
      (stroke (width 0.05) (type solid)) (fill none) (layer "B.CrtYd"))
    (fp_rect (start -0.8 0.4) (end 0.8 -0.4)
      (stroke (width 0.15) (type solid)) (fill none) (layer "B.Fab"))
    (pad "1" smd roundrect (at -0.7 0 180) (size 0.6 0.8) (layers "B.Cu" "B.Paste" "B.Mask") (roundrect_rratio 0.2)
      (net 604 "GNDD") (pintype "passive"))
    (pad "2" smd roundrect (at 0.7 0 180) (size 0.6 0.8) (layers "B.Cu" "B.Paste" "B.Mask") (roundrect_rratio 0.2)
      (net 627 "Net-(IC2-Pad3)") (pintype "passive"))
  )

  (footprint "data-center-rdimm-ddr4-tester-footprints:C_0201" (layer "B.Cu")
    (at 180.95 96.7 90)
    (descr "Capacitor SMD 0201")
    (tags "capacitor SMD 0201")
    (property "Author" "Antmicro")
    (property "Dielectric" "")
    (property "License" "Apache-2.0")
    (property "MPN" "CC0201KRX6S5BB104")
    (property "Manufacturer" "Yaego")
    (property "Sheetfile" "fpga-power.kicad_sch")
    (property "Sheetname" "FPGA power")
    (property "Val" "100n")
    (property "Voltage" "")
    (property "ki_description" " ")
    (attr smd)
    (fp_text reference "C82" (at 0.74 -0.46 270) (layer "B.SilkS")
        (effects (font (size 0.7 0.7) (thickness 0.15)) (justify left bottom mirror))
    )
    (fp_text value "C_100n_0201" (at 0 -1.4 270) (layer "B.Fab") hide
        (effects (font (size 0.7 0.7) (thickness 0.15)) (justify left bottom mirror))
    )
    (fp_text user "Author: Antmicro" (at -0.72 -5.4 270) (layer "B.Fab") hide
        (effects (font (size 0.7 0.7) (thickness 0.15)) (justify left bottom mirror))
    )
    (fp_text user "${REFERENCE}" (at -0.72 -3.4 270) (layer "B.Fab") hide
        (effects (font (size 0.7 0.7) (thickness 0.15)) (justify left bottom mirror))
    )
    (fp_text user "License: Apache-2.0" (at -0.72 -4.4 270) (layer "B.Fab") hide
        (effects (font (size 0.7 0.7) (thickness 0.15)) (justify left bottom mirror))
    )
    (fp_rect (start -0.72 0.38) (end 0.72 -0.38)
      (stroke (width 0.05) (type solid)) (fill none) (layer "B.CrtYd"))
    (fp_rect (start 0.3 -0.15) (end -0.301 0.149)
      (stroke (width 0.15) (type solid)) (fill none) (layer "B.Fab"))
    (pad "" smd roundrect (at -0.349 0.002 90) (size 0.318 0.36) (layers "B.Paste") (roundrect_rratio 0.25))
    (pad "" smd roundrect (at 0.341 0.002 90) (size 0.318 0.36) (layers "B.Paste") (roundrect_rratio 0.25))
    (pad "1" smd roundrect (at -0.321 0.002 90) (size 0.46 0.4) (layers "B.Cu" "B.Mask") (roundrect_rratio 0.25)
      (net 143 "3V3_SYS") (pintype "passive"))
    (pad "2" smd roundrect (at 0.32 0.002 90) (size 0.46 0.4) (layers "B.Cu" "B.Mask") (roundrect_rratio 0.25)
      (net 9 "GND") (pintype "passive"))
  )

  (footprint "data-center-rdimm-ddr4-tester-footprints:C_2220_5650Metric" (layer "B.Cu")
    (at 195.05 131.95)
    (descr "Capacitor SMD 2220")
    (tags "capacitor SMD 2220")
    (property "Author" "Antmicro")
    (property "Dielectric" "")
    (property "License" "Apache-2.0")
    (property "MPN" "C5750X7S2A226M280KB")
    (property "Manufacturer" "TDK")
    (property "Sheetfile" "ethernet.kicad_sch")
    (property "Sheetname" "Ethernet")
    (property "Val" "22u/100V")
    (property "Voltage" "")
    (property "ki_description" " ")
    (attr smd)
    (fp_text reference "C223" (at 4.58 -1.26 270) (layer "B.SilkS")
        (effects (font (size 0.7 0.7) (thickness 0.15)) (justify left bottom mirror))
    )
    (fp_text value "C_22u_100V_2220" (at 0 -3.9 180) (layer "B.Fab") hide
        (effects (font (size 0.7 0.7) (thickness 0.15)) (justify left bottom mirror))
    )
    (fp_text user "${REFERENCE}" (at -3.7 -5.9 180) (layer "B.Fab") hide
        (effects (font (size 0.7 0.7) (thickness 0.15)) (justify left bottom mirror))
    )
    (fp_text user "Author: Antmicro" (at -3.7 -7.9 180) (layer "B.Fab") hide
        (effects (font (size 0.7 0.7) (thickness 0.15)) (justify left bottom mirror))
    )
    (fp_text user "License: Apache-2.0" (at -3.7 -6.9 180) (layer "B.Fab") hide
        (effects (font (size 0.7 0.7) (thickness 0.15)) (justify left bottom mirror))
    )
    (fp_line (start -1.415 -2.61) (end 1.415 -2.61)
      (stroke (width 0.15) (type solid)) (layer "B.SilkS"))
    (fp_line (start -1.415 2.61) (end 1.415 2.61)
      (stroke (width 0.15) (type solid)) (layer "B.SilkS"))
    (fp_rect (start -3.7 2.95) (end 3.7 -2.95)
      (stroke (width 0.05) (type solid)) (fill none) (layer "B.CrtYd"))
    (fp_rect (start -2.85 2.5) (end 2.85 -2.5)
      (stroke (width 0.15) (type solid)) (fill none) (layer "B.Fab"))
    (pad "1" smd roundrect (at -2.55 0) (size 1.8 5.4) (layers "B.Cu" "B.Paste" "B.Mask") (roundrect_rratio 0.138889)
      (net 360 "/Ethernet/VDD") (pintype "passive"))
    (pad "2" smd roundrect (at 2.55 0) (size 1.8 5.4) (layers "B.Cu" "B.Paste" "B.Mask") (roundrect_rratio 0.138889)
      (net 604 "GNDD") (pintype "passive"))
  )

  (footprint "data-center-rdimm-ddr4-tester-footprints:R_0402_1005Metric" (layer "B.Cu")
    (at 122.26 89.9175 90)
    (descr "Resistor SMD 0402")
    (tags "resistor SMD 0402")
    (property "Author" "Antmicro")
    (property "License" "Apache-2.0")
    (property "MPN" "CR0402-FX-1002GLF")
    (property "Manufacturer" "Bourns")
    (property "Sheetfile" "supply.kicad_sch")
    (property "Sheetname" "Supply")
    (property "Tolerance" "1%")
    (property "Val" "10k")
    (property "ki_description" "10k resistor in 0402 package with 1% tolerance")
    (attr smd)
    (fp_text reference "R194" (at -1.7825 0.44 270) (layer "B.SilkS")
        (effects (font (size 0.7 0.7) (thickness 0.15)) (justify left bottom mirror))
    )
    (fp_text value "R_10k_0402" (at 0 -1.4 270) (layer "B.Fab") hide
        (effects (font (size 0.7 0.7) (thickness 0.15)) (justify left bottom mirror))
    )
    (fp_text user "License: Apache-2.0" (at -0.95 -5.169 270) (layer "B.Fab") hide
        (effects (font (size 0.7 0.7) (thickness 0.15)) (justify left bottom mirror))
    )
    (fp_text user "Author: Antmicro" (at -0.95 -4.169 270) (layer "B.Fab") hide
        (effects (font (size 0.7 0.7) (thickness 0.15)) (justify left bottom mirror))
    )
    (fp_text user "${REFERENCE}" (at -0.95 -3.168 270) (layer "B.Fab") hide
        (effects (font (size 0.7 0.7) (thickness 0.15)) (justify left bottom mirror))
    )
    (fp_rect (start -0.93 0.47) (end 0.93 -0.47)
      (stroke (width 0.05) (type solid)) (fill none) (layer "B.CrtYd"))
    (fp_rect (start -0.5 0.25) (end 0.5 -0.25)
      (stroke (width 0.15) (type solid)) (fill none) (layer "B.Fab"))
    (pad "1" smd roundrect (at -0.485 0 90) (size 0.59 0.64) (layers "B.Cu" "B.Paste" "B.Mask") (roundrect_rratio 0.25)
      (net 143 "3V3_SYS") (pintype "passive"))
    (pad "2" smd roundrect (at 0.485 0 90) (size 0.59 0.64) (layers "B.Cu" "B.Paste" "B.Mask") (roundrect_rratio 0.25)
      (net 660 "Net-(U19-~{PWRDN})") (pintype "passive"))
  )

  (footprint "data-center-rdimm-ddr4-tester-footprints:SOT-753" (layer "B.Cu")
    (at 128.74 105.19 90)
    (property "Author" "Antmicro")
    (property "License" "Apache-2.0")
    (property "MPN" "SN74AHCT1G125DBVR")
    (property "Manufacturer" "Texas Instruments")
    (property "Sheetfile" "supply.kicad_sch")
    (property "Sheetname" "Supply")
    (attr smd)
    (fp_text reference "U21" (at 1.5 -0.98) (layer "B.SilkS")
        (effects (font (size 0.7 0.7) (thickness 0.15)) (justify left bottom mirror))
    )
    (fp_text value "SN74AHCT1G125_SOT" (at 0 -2.9 270) (layer "B.Fab") hide
        (effects (font (size 0.7 0.7) (thickness 0.15)) (justify left bottom mirror))
    )
    (fp_text user "Author: Antmicro" (at -1.651 -7.225 270) (layer "B.Fab") hide
        (effects (font (size 0.7 0.7) (thickness 0.15)) (justify left bottom mirror))
    )
    (fp_text user "${REFERENCE}" (at -1.651 -6.025 270) (layer "B.Fab") hide
        (effects (font (size 0.7 0.7) (thickness 0.15)) (justify left bottom mirror))
    )
    (fp_text user "License: Apache-2.0" (at -1.651 -8.425 270) (layer "B.Fab") hide
        (effects (font (size 0.7 0.7) (thickness 0.15)) (justify left bottom mirror))
    )
    (fp_line (start -1.651 1) (end -1.651 0.701)
      (stroke (width 0.15) (type solid)) (layer "B.SilkS"))
    (fp_line (start -1.648 -1) (end -1.648 -0.677)
      (stroke (width 0.15) (type solid)) (layer "B.SilkS"))
    (fp_line (start -1.5 -1) (end -1.648 -1)
      (stroke (width 0.15) (type solid)) (layer "B.SilkS"))
    (fp_line (start -1.5 1) (end -1.651 1)
      (stroke (width 0.15) (type solid)) (layer "B.SilkS"))
    (fp_line (start 1.5 -0.998) (end 1.648 -0.998)
      (stroke (width 0.15) (type solid)) (layer "B.SilkS"))
    (fp_line (start 1.5 1) (end 1.648 1)
      (stroke (width 0.15) (type solid)) (layer "B.SilkS"))
    (fp_line (start 1.648 -0.998) (end 1.648 -0.699)
      (stroke (width 0.15) (type solid)) (layer "B.SilkS"))
    (fp_line (start 1.648 1) (end 1.648 0.677)
      (stroke (width 0.15) (type solid)) (layer "B.SilkS"))
    (fp_circle (center -1.5 -1.35) (end -1.46 -1.4)
      (stroke (width 0.15) (type solid)) (fill solid) (layer "B.SilkS"))
    (fp_rect (start -1.7 1.901) (end 1.699 -1.898)
      (stroke (width 0.05) (type solid)) (fill none) (layer "B.CrtYd"))
    (fp_line (start -1.526 -0.623) (end -1.526 0.875)
      (stroke (width 0.15) (type solid)) (layer "B.Fab"))
    (fp_line (start -1.526 -0.623) (end -1.351 -0.873)
      (stroke (width 0.15) (type solid)) (layer "B.Fab"))
    (fp_line (start -1.526 0.875) (end 1.523 0.875)
      (stroke (width 0.15) (type solid)) (layer "B.Fab"))
    (fp_line (start -1.351 -0.873) (end 1.523 -0.873)
      (stroke (width 0.15) (type solid)) (layer "B.Fab"))
    (fp_line (start 1.523 0.875) (end 1.523 -0.873)
      (stroke (width 0.15) (type solid)) (layer "B.Fab"))
    (pad "1" smd roundrect (at -0.951 -1.35 90) (size 0.6 1.05) (layers "B.Cu" "B.Paste" "B.Mask") (roundrect_rratio 0.25)
      (net 798 "/Supply/FPGA_PWR_DIS") (pinfunction "~{OE}") (pintype "input"))
    (pad "2" smd roundrect (at 0 -1.35 90) (size 0.6 1.05) (layers "B.Cu" "B.Paste" "B.Mask") (roundrect_rratio 0.25)
      (net 536 "/Supply/SYS_PWR_GOOD") (pinfunction "A") (pintype "input"))
    (pad "3" smd roundrect (at 0.949 -1.35 90) (size 0.6 1.05) (layers "B.Cu" "B.Paste" "B.Mask") (roundrect_rratio 0.25)
      (net 9 "GND") (pinfunction "GND") (pintype "power_in"))
    (pad "4" smd roundrect (at 0.949 1.351 90) (size 0.6 1.05) (layers "B.Cu" "B.Paste" "B.Mask") (roundrect_rratio 0.25)
      (net 790 "/Supply/PWR_SEQ_EN") (pinfunction "Y") (pintype "output"))
    (pad "5" smd roundrect (at -0.951 1.351 90) (size 0.6 1.05) (layers "B.Cu" "B.Paste" "B.Mask") (roundrect_rratio 0.25)
      (net 307 "5V0_SYS") (pinfunction "V_{CC}") (pintype "power_in"))
  )

  (footprint "data-center-rdimm-ddr4-tester-footprints:C_0201" (layer "B.Cu")
    (at 187.09 96.62 180)
    (descr "Capacitor SMD 0201")
    (tags "capacitor SMD 0201")
    (property "Author" "Antmicro")
    (property "Dielectric" "")
    (property "License" "Apache-2.0")
    (property "MPN" "CC0201KRX6S5BB104")
    (property "Manufacturer" "Yaego")
    (property "Sheetfile" "fpga-power.kicad_sch")
    (property "Sheetname" "FPGA power")
    (property "Val" "100n")
    (property "Voltage" "")
    (property "ki_description" " ")
    (attr smd)
    (fp_text reference "C303" (at -3.45 -0.29) (layer "B.SilkS")
        (effects (font (size 0.7 0.7) (thickness 0.15)) (justify left bottom mirror))
    )
    (fp_text value "C_100n_0201" (at 0 -1.4) (layer "B.Fab") hide
        (effects (font (size 0.7 0.7) (thickness 0.15)) (justify left bottom mirror))
    )
    (fp_text user "License: Apache-2.0" (at -0.72 -4.4) (layer "B.Fab") hide
        (effects (font (size 0.7 0.7) (thickness 0.15)) (justify left bottom mirror))
    )
    (fp_text user "${REFERENCE}" (at -0.72 -3.4) (layer "B.Fab") hide
        (effects (font (size 0.7 0.7) (thickness 0.15)) (justify left bottom mirror))
    )
    (fp_text user "Author: Antmicro" (at -0.72 -5.4) (layer "B.Fab") hide
        (effects (font (size 0.7 0.7) (thickness 0.15)) (justify left bottom mirror))
    )
    (fp_rect (start -0.72 0.38) (end 0.72 -0.38)
      (stroke (width 0.05) (type solid)) (fill none) (layer "B.CrtYd"))
    (fp_rect (start 0.3 -0.15) (end -0.301 0.149)
      (stroke (width 0.15) (type solid)) (fill none) (layer "B.Fab"))
    (pad "" smd roundrect (at -0.349 0.002 180) (size 0.318 0.36) (layers "B.Paste") (roundrect_rratio 0.25))
    (pad "" smd roundrect (at 0.341 0.002 180) (size 0.318 0.36) (layers "B.Paste") (roundrect_rratio 0.25))
    (pad "1" smd roundrect (at -0.321 0.002 180) (size 0.46 0.4) (layers "B.Cu" "B.Mask") (roundrect_rratio 0.25)
      (net 143 "3V3_SYS") (pintype "passive"))
    (pad "2" smd roundrect (at 0.32 0.002 180) (size 0.46 0.4) (layers "B.Cu" "B.Mask") (roundrect_rratio 0.25)
      (net 9 "GND") (pintype "passive"))
  )

  (footprint "data-center-rdimm-ddr4-tester-footprints:R_0402_1005Metric" (layer "B.Cu")
    (at 166.2 102.8 180)
    (descr "Resistor SMD 0402")
    (tags "resistor SMD 0402")
    (property "Author" "Antmicro")
    (property "Current" "1A")
    (property "License" "Apache-2.0")
    (property "MPN" "ERJ2GE0R00X")
    (property "Manufacturer" "Panasonic")
    (property "Sheetfile" "ethernet.kicad_sch")
    (property "Sheetname" "Ethernet")
    (property "Tolerance" "")
    (property "Val" "0R")
    (property "ki_description" "0R resistor in 0402 package with unspecified tolerance")
    (attr smd)
    (fp_text reference "R205" (at -1.91 -2.27) (layer "B.SilkS")
        (effects (font (size 0.7 0.7) (thickness 0.15)) (justify left bottom mirror))
    )
    (fp_text value "R_0R_0402" (at 0 -1.4) (layer "B.Fab") hide
        (effects (font (size 0.7 0.7) (thickness 0.15)) (justify left bottom mirror))
    )
    (fp_text user "${REFERENCE}" (at -0.95 -3.168) (layer "B.Fab") hide
        (effects (font (size 0.7 0.7) (thickness 0.15)) (justify left bottom mirror))
    )
    (fp_text user "Author: Antmicro" (at -0.95 -4.169) (layer "B.Fab") hide
        (effects (font (size 0.7 0.7) (thickness 0.15)) (justify left bottom mirror))
    )
    (fp_text user "License: Apache-2.0" (at -0.95 -5.169) (layer "B.Fab") hide
        (effects (font (size 0.7 0.7) (thickness 0.15)) (justify left bottom mirror))
    )
    (fp_rect (start -0.93 0.47) (end 0.93 -0.47)
      (stroke (width 0.05) (type solid)) (fill none) (layer "B.CrtYd"))
    (fp_rect (start -0.5 0.25) (end 0.5 -0.25)
      (stroke (width 0.15) (type solid)) (fill none) (layer "B.Fab"))
    (pad "1" smd roundrect (at -0.485 0 180) (size 0.59 0.64) (layers "B.Cu" "B.Paste" "B.Mask") (roundrect_rratio 0.25)
      (net 751 "PRSNT_M2C") (pintype "passive"))
    (pad "2" smd roundrect (at 0.485 0 180) (size 0.59 0.64) (layers "B.Cu" "B.Paste" "B.Mask") (roundrect_rratio 0.25)
      (net 662 "Net-(U16-SEL)") (pintype "passive"))
  )

  (footprint "data-center-rdimm-ddr4-tester-footprints:FB_0805_2012Metric" (layer "B.Cu")
    (at 177.65 123.6 -90)
    (property "Author" "Antmicro")
    (property "License" "Apache-2.0")
    (property "MPN" "BLM21PG221SN1D")
    (property "Manufacturer" "Murata")
    (property "Sheetfile" "ethernet.kicad_sch")
    (property "Sheetname" "Ethernet")
    (attr smd)
    (fp_text reference "FB9" (at -0.86 0.95 90) (layer "B.SilkS")
        (effects (font (size 0.7 0.7) (thickness 0.15)) (justify left bottom mirror))
    )
    (fp_text value "FB_220Z_2A_0603" (at 0 -1.8 90) (layer "B.Fab") hide
        (effects (font (size 0.7 0.7) (thickness 0.15)) (justify left bottom mirror))
    )
    (fp_text user "${REFERENCE}" (at -1.9 -3.1 90) (layer "B.Fab") hide
        (effects (font (size 0.7 0.7) (thickness 0.15)) (justify left bottom mirror))
    )
    (fp_text user "License: Apache-2.0" (at -1.9 -5.75 90) (layer "B.Fab") hide
        (effects (font (size 0.7 0.7) (thickness 0.15)) (justify left bottom mirror))
    )
    (fp_text user "Author: Antmicro" (at -1.9 -4.4 90) (layer "B.Fab") hide
        (effects (font (size 0.7 0.7) (thickness 0.15)) (justify left bottom mirror))
    )
    (fp_line (start -0.32 -0.699) (end 0.28 -0.699)
      (stroke (width 0.15) (type solid)) (layer "B.SilkS"))
    (fp_line (start -0.3 0.701) (end 0.298 0.701)
      (stroke (width 0.15) (type solid)) (layer "B.SilkS"))
    (fp_rect (start -1.75 0.85) (end 1.75 -0.85)
      (stroke (width 0.05) (type solid)) (fill none) (layer "B.CrtYd"))
    (fp_line (start -0.951 -0.68) (end 0.949 -0.68)
      (stroke (width 0.15) (type solid)) (layer "B.Fab"))
    (fp_line (start -0.951 0.677) (end -0.951 -0.675)
      (stroke (width 0.15) (type solid)) (layer "B.Fab"))
    (fp_line (start -0.951 0.682) (end 0.949 0.682)
      (stroke (width 0.15) (type solid)) (layer "B.Fab"))
    (fp_line (start 0.949 0.677) (end 0.949 -0.675)
      (stroke (width 0.15) (type solid)) (layer "B.Fab"))
    (pad "1" smd roundrect (at -1.1 0.001 270) (size 1 1.4) (layers "B.Cu" "B.Paste" "B.Mask") (roundrect_rratio 0.15)
      (net 808 "/Ethernet/VDD_RAW") (pintype "passive"))
    (pad "2" smd roundrect (at 1.1 0.001 270) (size 1 1.4) (layers "B.Cu" "B.Paste" "B.Mask") (roundrect_rratio 0.15)
      (net 360 "/Ethernet/VDD") (pintype "passive"))
  )

  (footprint "data-center-rdimm-ddr4-tester-footprints:R_0402_1005Metric" (layer "B.Cu")
    (at 134.98 102.59 -90)
    (descr "Resistor SMD 0402")
    (tags "resistor SMD 0402")
    (property "Author" "Antmicro")
    (property "License" "Apache-2.0")
    (property "MPN" "CR0402-FX-1002GLF")
    (property "Manufacturer" "Bourns")
    (property "Sheetfile" "supply.kicad_sch")
    (property "Sheetname" "Supply")
    (property "Tolerance" "1%")
    (property "Val" "10k")
    (property "ki_description" "10k resistor in 0402 package with 1% tolerance")
    (attr smd)
    (fp_text reference "R217" (at -0.95 0.59 90) (layer "B.SilkS")
        (effects (font (size 0.7 0.7) (thickness 0.15)) (justify left bottom mirror))
    )
    (fp_text value "R_10k_0402" (at 0 -1.4 90) (layer "B.Fab") hide
        (effects (font (size 0.7 0.7) (thickness 0.15)) (justify left bottom mirror))
    )
    (fp_text user "${REFERENCE}" (at -0.95 -3.168 90) (layer "B.Fab") hide
        (effects (font (size 0.7 0.7) (thickness 0.15)) (justify left bottom mirror))
    )
    (fp_text user "Author: Antmicro" (at -0.95 -4.169 90) (layer "B.Fab") hide
        (effects (font (size 0.7 0.7) (thickness 0.15)) (justify left bottom mirror))
    )
    (fp_text user "License: Apache-2.0" (at -0.95 -5.169 90) (layer "B.Fab") hide
        (effects (font (size 0.7 0.7) (thickness 0.15)) (justify left bottom mirror))
    )
    (fp_rect (start -0.93 0.47) (end 0.93 -0.47)
      (stroke (width 0.05) (type solid)) (fill none) (layer "B.CrtYd"))
    (fp_rect (start -0.5 0.25) (end 0.5 -0.25)
      (stroke (width 0.15) (type solid)) (fill none) (layer "B.Fab"))
    (pad "1" smd roundrect (at -0.485 0 270) (size 0.59 0.64) (layers "B.Cu" "B.Paste" "B.Mask") (roundrect_rratio 0.25)
      (net 793 "/Supply/VTT_CNTL") (pintype "passive"))
    (pad "2" smd roundrect (at 0.485 0 270) (size 0.59 0.64) (layers "B.Cu" "B.Paste" "B.Mask") (roundrect_rratio 0.25)
      (net 9 "GND") (pintype "passive"))
  )

  (footprint "data-center-rdimm-ddr4-tester-footprints:C_0201" (layer "B.Cu")
    (at 176 95.075 90)
    (descr "Capacitor SMD 0201")
    (tags "capacitor SMD 0201")
    (property "Author" "Antmicro")
    (property "Dielectric" "")
    (property "License" "Apache-2.0")
    (property "MPN" "CC0201KRX6S5BB104")
    (property "Manufacturer" "Yaego")
    (property "Sheetfile" "fpga-power.kicad_sch")
    (property "Sheetname" "FPGA power")
    (property "Val" "100n")
    (property "Voltage" "")
    (property "ki_description" " ")
    (attr smd)
    (fp_text reference "C88" (at 1.045 1.25 270) (layer "B.SilkS")
        (effects (font (size 0.7 0.7) (thickness 0.15)) (justify left bottom mirror))
    )
    (fp_text value "C_100n_0201" (at 0 -1.4 270) (layer "B.Fab") hide
        (effects (font (size 0.7 0.7) (thickness 0.15)) (justify left bottom mirror))
    )
    (fp_text user "License: Apache-2.0" (at -0.72 -4.4 270) (layer "B.Fab") hide
        (effects (font (size 0.7 0.7) (thickness 0.15)) (justify left bottom mirror))
    )
    (fp_text user "Author: Antmicro" (at -0.72 -5.4 270) (layer "B.Fab") hide
        (effects (font (size 0.7 0.7) (thickness 0.15)) (justify left bottom mirror))
    )
    (fp_text user "${REFERENCE}" (at -0.72 -3.4 270) (layer "B.Fab") hide
        (effects (font (size 0.7 0.7) (thickness 0.15)) (justify left bottom mirror))
    )
    (fp_rect (start -0.72 0.38) (end 0.72 -0.38)
      (stroke (width 0.05) (type solid)) (fill none) (layer "B.CrtYd"))
    (fp_rect (start 0.3 -0.15) (end -0.301 0.149)
      (stroke (width 0.15) (type solid)) (fill none) (layer "B.Fab"))
    (pad "" smd roundrect (at -0.349 0.002 90) (size 0.318 0.36) (layers "B.Paste") (roundrect_rratio 0.25))
    (pad "" smd roundrect (at 0.341 0.002 90) (size 0.318 0.36) (layers "B.Paste") (roundrect_rratio 0.25))
    (pad "1" smd roundrect (at -0.321 0.002 90) (size 0.46 0.4) (layers "B.Cu" "B.Mask") (roundrect_rratio 0.25)
      (net 143 "3V3_SYS") (pintype "passive"))
    (pad "2" smd roundrect (at 0.32 0.002 90) (size 0.46 0.4) (layers "B.Cu" "B.Mask") (roundrect_rratio 0.25)
      (net 9 "GND") (pintype "passive"))
  )

  (footprint "data-center-rdimm-ddr4-tester-footprints:C_0402_1005Metric" (layer "B.Cu")
    (at 247.173 47.676)
    (descr "Capacitor SMD 0402")
    (tags "capacitor SMD 0402")
    (property "Author" "Antmicro")
    (property "Dielectric" "X5R")
    (property "License" "Apache-2.0")
    (property "MPN" "GRM155R61H104KE14D")
    (property "Manufacturer" "Murata")
    (property "Sheetfile" "fpga-power.kicad_sch")
    (property "Sheetname" "FPGA power")
    (property "Val" "100n")
    (property "Voltage" "50V")
    (property "ki_description" " ")
    (attr smd)
    (fp_text reference "C313" (at 1.407 1.394 180) (layer "B.SilkS")
        (effects (font (size 0.7 0.7) (thickness 0.15)) (justify left bottom mirror))
    )
    (fp_text value "C_100n_0402" (at 0 -1.4 180) (layer "B.Fab") hide
        (effects (font (size 0.7 0.7) (thickness 0.15)) (justify left bottom mirror))
    )
    (fp_text user "License: Apache-2.0" (at -0.932 -5.17 180) (layer "B.Fab") hide
        (effects (font (size 0.7 0.7) (thickness 0.15)) (justify left bottom mirror))
    )
    (fp_text user "${REFERENCE}" (at -0.932 -3.168 180) (layer "B.Fab") hide
        (effects (font (size 0.7 0.7) (thickness 0.15)) (justify left bottom mirror))
    )
    (fp_text user "Author: Antmicro" (at -0.932 -4.17 180) (layer "B.Fab") hide
        (effects (font (size 0.7 0.7) (thickness 0.15)) (justify left bottom mirror))
    )
    (fp_rect (start -0.94 0.47) (end 0.94 -0.47)
      (stroke (width 0.05) (type solid)) (fill none) (layer "B.CrtYd"))
    (fp_rect (start -0.499 0.249) (end 0.499 -0.249)
      (stroke (width 0.15) (type solid)) (fill none) (layer "B.Fab"))
    (pad "1" smd roundrect (at -0.484 0) (size 0.59 0.64) (layers "B.Cu" "B.Paste" "B.Mask") (roundrect_rratio 0.25)
      (net 77 "VDDQ") (pintype "passive"))
    (pad "2" smd roundrect (at 0.484 0) (size 0.59 0.64) (layers "B.Cu" "B.Paste" "B.Mask") (roundrect_rratio 0.25)
      (net 9 "GND") (pintype "passive"))
  )

  (footprint "data-center-rdimm-ddr4-tester-footprints:C_0201" (layer "B.Cu")
    (at 189.7 78.7)
    (descr "Capacitor SMD 0201")
    (tags "capacitor SMD 0201")
    (property "Author" "Antmicro")
    (property "Dielectric" "")
    (property "License" "Apache-2.0")
    (property "MPN" "CC0201KRX6S5BB104")
    (property "Manufacturer" "Yaego")
    (property "Sheetfile" "fpga-power.kicad_sch")
    (property "Sheetname" "FPGA power")
    (property "Val" "100n")
    (property "Voltage" "")
    (property "ki_description" " ")
    (attr smd)
    (fp_text reference "C296" (at 1.26 -0.48 180) (layer "B.SilkS")
        (effects (font (size 0.7 0.7) (thickness 0.15)) (justify left bottom mirror))
    )
    (fp_text value "C_100n_0201" (at 0 -1.4 180) (layer "B.Fab") hide
        (effects (font (size 0.7 0.7) (thickness 0.15)) (justify left bottom mirror))
    )
    (fp_text user "License: Apache-2.0" (at -0.72 -4.4 180) (layer "B.Fab") hide
        (effects (font (size 0.7 0.7) (thickness 0.15)) (justify left bottom mirror))
    )
    (fp_text user "Author: Antmicro" (at -0.72 -5.4 180) (layer "B.Fab") hide
        (effects (font (size 0.7 0.7) (thickness 0.15)) (justify left bottom mirror))
    )
    (fp_text user "${REFERENCE}" (at -0.72 -3.4 180) (layer "B.Fab") hide
        (effects (font (size 0.7 0.7) (thickness 0.15)) (justify left bottom mirror))
    )
    (fp_rect (start -0.72 0.38) (end 0.72 -0.38)
      (stroke (width 0.05) (type solid)) (fill none) (layer "B.CrtYd"))
    (fp_rect (start 0.3 -0.15) (end -0.301 0.149)
      (stroke (width 0.15) (type solid)) (fill none) (layer "B.Fab"))
    (pad "" smd roundrect (at -0.349 0.002) (size 0.318 0.36) (layers "B.Paste") (roundrect_rratio 0.25))
    (pad "" smd roundrect (at 0.341 0.002) (size 0.318 0.36) (layers "B.Paste") (roundrect_rratio 0.25))
    (pad "1" smd roundrect (at -0.321 0.002) (size 0.46 0.4) (layers "B.Cu" "B.Mask") (roundrect_rratio 0.25)
      (net 77 "VDDQ") (pintype "passive"))
    (pad "2" smd roundrect (at 0.32 0.002) (size 0.46 0.4) (layers "B.Cu" "B.Mask") (roundrect_rratio 0.25)
      (net 9 "GND") (pintype "passive"))
  )

  (footprint "data-center-rdimm-ddr4-tester-footprints:R_0603_1608Metric" (layer "B.Cu")
    (at 136.35 79.55 180)
    (descr "Resistor SMD 0603")
    (tags "resistor SMD 0603")
    (property "Author" "Antmicro")
    (property "License" "Apache-2.0")
    (property "MPN" "ERJ-UP3F3300V")
    (property "Manufacturer" "Panasonic")
    (property "Sheetfile" "supply.kicad_sch")
    (property "Sheetname" "Supply")
    (property "Tolerance" "1%")
    (property "Val" "330R")
    (property "ki_description" "330R resistor in 0603 package with 1% tolerance")
    (attr smd)
    (fp_text reference "R17" (at -0.98 0.79) (layer "B.SilkS")
        (effects (font (size 0.7 0.7) (thickness 0.15)) (justify left bottom mirror))
    )
    (fp_text value "R_330R_0.25W_0603" (at 0 -1.6) (layer "B.Fab") hide
        (effects (font (size 0.7 0.7) (thickness 0.15)) (justify left bottom mirror))
    )
    (fp_text user "${REFERENCE}" (at -1.25 -3.898) (layer "B.Fab") hide
        (effects (font (size 0.7 0.7) (thickness 0.15)) (justify left bottom mirror))
    )
    (fp_text user "License: Apache-2.0" (at -1.25 -5.9) (layer "B.Fab") hide
        (effects (font (size 0.7 0.7) (thickness 0.15)) (justify left bottom mirror))
    )
    (fp_text user "Author: Antmicro" (at -1.25 -4.9) (layer "B.Fab") hide
        (effects (font (size 0.7 0.7) (thickness 0.15)) (justify left bottom mirror))
    )
    (fp_line (start -0.3 -0.3) (end 0.3 -0.3)
      (stroke (width 0.15) (type solid)) (layer "B.SilkS"))
    (fp_line (start -0.3 0.3) (end 0.3 0.3)
      (stroke (width 0.15) (type solid)) (layer "B.SilkS"))
    (fp_rect (start -1.25 0.7) (end 1.25 -0.7)
      (stroke (width 0.05) (type solid)) (fill none) (layer "B.CrtYd"))
    (fp_rect (start -0.8 0.4) (end 0.8 -0.4)
      (stroke (width 0.15) (type solid)) (fill none) (layer "B.Fab"))
    (pad "1" smd roundrect (at -0.7 0 180) (size 0.6 0.8) (layers "B.Cu" "B.Paste" "B.Mask") (roundrect_rratio 0.2)
      (net 854 "Net-(R17-Pad1)") (pintype "passive"))
    (pad "2" smd roundrect (at 0.7 0 180) (size 0.6 0.8) (layers "B.Cu" "B.Paste" "B.Mask") (roundrect_rratio 0.2)
      (net 144 "1V8_SYS") (pintype "passive"))
  )

  (footprint "data-center-rdimm-ddr4-tester-footprints:C_1206_3216Metric" (layer "B.Cu")
    (at 193.5 111.7 180)
    (descr "Capacitor SMD 1206")
    (tags "capacitor SMD 1206")
    (property "Author" "Antmicro")
    (property "Dielectric" "")
    (property "License" "Apache-2.0")
    (property "MPN" "C3216X5R1C476M160AB")
    (property "Manufacturer" "TDK")
    (property "Sheetfile" "ethernet.kicad_sch")
    (property "Sheetname" "Ethernet")
    (property "Val" "47u/16V")
    (property "Voltage" "")
    (property "ki_description" " ")
    (attr smd)
    (fp_text reference "C228" (at -1.38 1.28) (layer "B.SilkS")
        (effects (font (size 0.7 0.7) (thickness 0.15)) (justify left bottom mirror))
    )
    (fp_text value "C_47u_16V_1206" (at 0 -2.1) (layer "B.Fab") hide
        (effects (font (size 0.7 0.7) (thickness 0.15)) (justify left bottom mirror))
    )
    (fp_text user "Author: Antmicro" (at -2.8 -5.6) (layer "B.Fab") hide
        (effects (font (size 0.7 0.7) (thickness 0.15)) (justify left bottom mirror))
    )
    (fp_text user "License: Apache-2.0" (at -2.8 -6.6) (layer "B.Fab") hide
        (effects (font (size 0.7 0.7) (thickness 0.15)) (justify left bottom mirror))
    )
    (fp_text user "${REFERENCE}" (at -2.8 -4.6) (layer "B.Fab") hide
        (effects (font (size 0.7 0.7) (thickness 0.15)) (justify left bottom mirror))
    )
    (fp_line (start -2.625 0.3) (end -2.625 -0.3)
      (stroke (width 0.15) (type solid)) (layer "B.SilkS"))
    (fp_line (start 0.5 -0.9) (end -0.5 -0.9)
      (stroke (width 0.15) (type solid)) (layer "B.SilkS"))
    (fp_line (start 0.5 0.9) (end -0.5 0.9)
      (stroke (width 0.15) (type solid)) (layer "B.SilkS"))
    (fp_line (start 2.625 0.3) (end 2.625 -0.3)
      (stroke (width 0.15) (type solid)) (layer "B.SilkS"))
    (fp_rect (start -2.8 1.15) (end 2.8 -1.15)
      (stroke (width 0.05) (type solid)) (fill none) (layer "B.CrtYd"))
    (fp_rect (start -1.6 0.8) (end 1.6 -0.8)
      (stroke (width 0.15) (type solid)) (fill none) (layer "B.Fab"))
    (pad "1" smd rect (at -1.8 0 180) (size 1.5 1.8) (layers "B.Cu" "B.Paste" "B.Mask")
      (net 864 "VIN_POE") (pintype "passive"))
    (pad "2" smd rect (at 1.8 0 180) (size 1.5 1.8) (layers "B.Cu" "B.Paste" "B.Mask")
      (net 9 "GND") (pintype "passive"))
  )

  (footprint "data-center-rdimm-ddr4-tester-footprints:R_0402_1005Metric" (layer "B.Cu")
    (at 136.6 109.1 90)
    (descr "Resistor SMD 0402")
    (tags "resistor SMD 0402")
    (property "Author" "Antmicro")
    (property "License" "Apache-2.0")
    (property "MPN" "CR0402-FX-1003GLF")
    (property "Manufacturer" "Bourns")
    (property "Sheetfile" "supply.kicad_sch")
    (property "Sheetname" "Supply")
    (property "Tolerance" "1%")
    (property "Val" "100k")
    (property "ki_description" "100k resistor in 0402 package with 1% tolerance")
    (attr smd)
    (fp_text reference "R124" (at 1.32 1.28 270) (layer "B.SilkS")
        (effects (font (size 0.7 0.7) (thickness 0.15)) (justify left bottom mirror))
    )
    (fp_text value "R_100k_0402" (at 0 -1.4 270) (layer "B.Fab") hide
        (effects (font (size 0.7 0.7) (thickness 0.15)) (justify left bottom mirror))
    )
    (fp_text user "Author: Antmicro" (at -0.95 -4.169 270) (layer "B.Fab") hide
        (effects (font (size 0.7 0.7) (thickness 0.15)) (justify left bottom mirror))
    )
    (fp_text user "${REFERENCE}" (at -0.95 -3.168 270) (layer "B.Fab") hide
        (effects (font (size 0.7 0.7) (thickness 0.15)) (justify left bottom mirror))
    )
    (fp_text user "License: Apache-2.0" (at -0.95 -5.169 270) (layer "B.Fab") hide
        (effects (font (size 0.7 0.7) (thickness 0.15)) (justify left bottom mirror))
    )
    (fp_rect (start -0.93 0.47) (end 0.93 -0.47)
      (stroke (width 0.05) (type solid)) (fill none) (layer "B.CrtYd"))
    (fp_rect (start -0.5 0.25) (end 0.5 -0.25)
      (stroke (width 0.15) (type solid)) (fill none) (layer "B.Fab"))
    (pad "1" smd roundrect (at -0.485 0 90) (size 0.59 0.64) (layers "B.Cu" "B.Paste" "B.Mask") (roundrect_rratio 0.25)
      (net 9 "GND") (pintype "passive"))
    (pad "2" smd roundrect (at 0.485 0 90) (size 0.59 0.64) (layers "B.Cu" "B.Paste" "B.Mask") (roundrect_rratio 0.25)
      (net 804 "FPGA_POWER_CYCLE") (pintype "passive"))
  )

  (footprint "data-center-rdimm-ddr4-tester-footprints:PowerDI5" (layer "B.Cu")
    (at 209.6 132.3 180)
    (property "Author" "Antmicro")
    (property "License" "Apache-2.0")
    (property "MPN" "PDS760-13")
    (property "Manufacturer" "Diodes Incorporated")
    (property "Sheetfile" "fmc_hpc.kicad_sch")
    (property "Sheetname" "FMC HPC")
    (property "ki_description" "PDS760 Series 60 V 7 A Surface Mount Schottky Barrier Rectifier - PowerDI-5")
    (property "ki_keywords" "PDS760 Series 60 V 7 A Surface Mount Schottky Barrier Rectifier - PowerDI-5")
    (attr smd)
    (fp_text reference "D18" (at 2.77 -2.66) (layer "B.SilkS")
        (effects (font (size 0.7 0.7) (thickness 0.15)) (justify left bottom mirror))
    )
    (fp_text value "PDS760" (at 0 -3.4) (layer "B.Fab") hide
        (effects (font (size 0.7 0.7) (thickness 0.15)) (justify right bottom mirror))
    )
    (fp_text user "${REFERENCE}" (at -3.302 -18.527) (layer "B.Fab") hide
        (effects (font (size 0.7 0.7) (thickness 0.15)) (justify left bottom mirror))
    )
    (fp_text user "License: Apache-2.0" (at -3.302 -20.928) (layer "B.Fab") hide
        (effects (font (size 0.7 0.7) (thickness 0.15)) (justify left bottom mirror))
    )
    (fp_text user "Author: Antmicro" (at -3.302 -19.728) (layer "B.Fab") hide
        (effects (font (size 0.7 0.7) (thickness 0.15)) (justify left bottom mirror))
    )
    (fp_line (start -2.7 -2.023) (end -2.7 -1.823)
      (stroke (width 0.12) (type solid)) (layer "B.SilkS"))
    (fp_line (start -2.7 1.8) (end -2.7 2)
      (stroke (width 0.12) (type solid)) (layer "B.SilkS"))
    (fp_line (start -2.7 2) (end 2.7 2)
      (stroke (width 0.12) (type solid)) (layer "B.SilkS"))
    (fp_line (start 2.7 -2.023) (end -2.7 -2.023)
      (stroke (width 0.12) (type solid)) (layer "B.SilkS"))
    (fp_line (start 2.7 -1.823) (end 2.7 -2.023)
      (stroke (width 0.12) (type solid)) (layer "B.SilkS"))
    (fp_line (start 2.7 2) (end 2.7 1.8)
      (stroke (width 0.12) (type solid)) (layer "B.SilkS"))
    (fp_rect (start -3.702 2.3) (end 3.7 -2.3)
      (stroke (width 0.05) (type solid)) (fill none) (layer "B.CrtYd"))
    (pad "A" smd roundrect (at -2.862 -0.941 270) (size 1.39 1.4) (layers "B.Cu" "B.Paste" "B.Mask") (roundrect_rratio 0.25)
      (net 535 "12P0V") (pinfunction "A") (pintype "passive"))
    (pad "A" smd roundrect (at -2.862 0.94 90) (size 1.39 1.4) (layers "B.Cu" "B.Paste" "B.Mask") (roundrect_rratio 0.25)
      (net 535 "12P0V") (pinfunction "A") (pintype "passive"))
    (pad "C" smd roundrect (at 1.1 0 270) (size 3.36 4.86) (layers "B.Cu" "B.Paste" "B.Mask") (roundrect_rratio 0.05)
      (net 103 "VIN") (pinfunction "C") (pintype "passive"))
  )

  (footprint "data-center-rdimm-ddr4-tester-footprints:C_0201" (layer "B.Cu")
    (at 189.59 102.97 -90)
    (descr "Capacitor SMD 0201")
    (tags "capacitor SMD 0201")
    (property "Author" "Antmicro")
    (property "Dielectric" "")
    (property "License" "Apache-2.0")
    (property "MPN" "CC0201KRX6S5BB104")
    (property "Manufacturer" "Yaego")
    (property "Sheetfile" "fpga-power.kicad_sch")
    (property "Sheetname" "FPGA power")
    (property "Val" "100n")
    (property "Voltage" "")
    (property "ki_description" " ")
    (attr smd)
    (fp_text reference "C85" (at 0.45 -0.38 90) (layer "B.SilkS")
        (effects (font (size 0.7 0.7) (thickness 0.15)) (justify left bottom mirror))
    )
    (fp_text value "C_100n_0201" (at 0 -1.4 90) (layer "B.Fab") hide
        (effects (font (size 0.7 0.7) (thickness 0.15)) (justify left bottom mirror))
    )
    (fp_text user "${REFERENCE}" (at -0.72 -3.4 90) (layer "B.Fab") hide
        (effects (font (size 0.7 0.7) (thickness 0.15)) (justify left bottom mirror))
    )
    (fp_text user "License: Apache-2.0" (at -0.72 -4.4 90) (layer "B.Fab") hide
        (effects (font (size 0.7 0.7) (thickness 0.15)) (justify left bottom mirror))
    )
    (fp_text user "Author: Antmicro" (at -0.72 -5.4 90) (layer "B.Fab") hide
        (effects (font (size 0.7 0.7) (thickness 0.15)) (justify left bottom mirror))
    )
    (fp_rect (start -0.72 0.38) (end 0.72 -0.38)
      (stroke (width 0.05) (type solid)) (fill none) (layer "B.CrtYd"))
    (fp_rect (start 0.3 -0.15) (end -0.301 0.149)
      (stroke (width 0.15) (type solid)) (fill none) (layer "B.Fab"))
    (pad "" smd roundrect (at -0.349 0.002 270) (size 0.318 0.36) (layers "B.Paste") (roundrect_rratio 0.25))
    (pad "" smd roundrect (at 0.341 0.002 270) (size 0.318 0.36) (layers "B.Paste") (roundrect_rratio 0.25))
    (pad "1" smd roundrect (at -0.321 0.002 270) (size 0.46 0.4) (layers "B.Cu" "B.Mask") (roundrect_rratio 0.25)
      (net 143 "3V3_SYS") (pintype "passive"))
    (pad "2" smd roundrect (at 0.32 0.002 270) (size 0.46 0.4) (layers "B.Cu" "B.Mask") (roundrect_rratio 0.25)
      (net 9 "GND") (pintype "passive"))
  )

  (footprint "data-center-rdimm-ddr4-tester-footprints:C_0402_1005Metric" (layer "B.Cu")
    (at 125.8 88.1 180)
    (descr "Capacitor SMD 0402")
    (tags "capacitor SMD 0402")
    (property "Author" "Antmicro")
    (property "Dielectric" "X5R")
    (property "License" "Apache-2.0")
    (property "MPN" "GRM155R61H104KE14D")
    (property "Manufacturer" "Murata")
    (property "Sheetfile" "supply.kicad_sch")
    (property "Sheetname" "Supply")
    (property "Val" "100n")
    (property "Voltage" "50V")
    (property "ki_description" " ")
    (attr smd)
    (fp_text reference "C235" (at -1.31 0.61) (layer "B.SilkS")
        (effects (font (size 0.7 0.7) (thickness 0.15)) (justify left bottom mirror))
    )
    (fp_text value "C_100n_0402" (at 0 -1.4) (layer "B.Fab") hide
        (effects (font (size 0.7 0.7) (thickness 0.15)) (justify left bottom mirror))
    )
    (fp_text user "${REFERENCE}" (at -0.932 -3.168) (layer "B.Fab") hide
        (effects (font (size 0.7 0.7) (thickness 0.15)) (justify left bottom mirror))
    )
    (fp_text user "Author: Antmicro" (at -0.932 -4.17) (layer "B.Fab") hide
        (effects (font (size 0.7 0.7) (thickness 0.15)) (justify left bottom mirror))
    )
    (fp_text user "License: Apache-2.0" (at -0.932 -5.17) (layer "B.Fab") hide
        (effects (font (size 0.7 0.7) (thickness 0.15)) (justify left bottom mirror))
    )
    (fp_rect (start -0.94 0.47) (end 0.94 -0.47)
      (stroke (width 0.05) (type solid)) (fill none) (layer "B.CrtYd"))
    (fp_rect (start -0.499 0.249) (end 0.499 -0.249)
      (stroke (width 0.15) (type solid)) (fill none) (layer "B.Fab"))
    (pad "1" smd roundrect (at -0.484 0 180) (size 0.59 0.64) (layers "B.Cu" "B.Paste" "B.Mask") (roundrect_rratio 0.25)
      (net 143 "3V3_SYS") (pintype "passive"))
    (pad "2" smd roundrect (at 0.484 0 180) (size 0.59 0.64) (layers "B.Cu" "B.Paste" "B.Mask") (roundrect_rratio 0.25)
      (net 9 "GND") (pintype "passive"))
  )

  (footprint "data-center-rdimm-ddr4-tester-footprints:SC70-3" (layer "B.Cu")
    (at 238.9 77.7)
    (property "Author" "Antmicro")
    (property "License" "Apache-2.0")
    (property "MPN" "BSS138PW")
    (property "Manufacturer" "Nexperia")
    (property "Sheetfile" "interfaces.kicad_sch")
    (property "Sheetname" "Interfaces")
    (property "ki_description" "60 V, 320 mA N-channel enhancement mode Trench MOSFET, SC-70-3 aka SOT-323 package")
    (property "ki_keywords" "n-channel enhancement mosfet sc70 sc-70 sot-323 sot323")
    (attr smd)
    (fp_text reference "Q10" (at -1.35 0.41 180) (layer "B.SilkS")
        (effects (font (size 0.7 0.7) (thickness 0.15)) (justify left bottom mirror))
    )
    (fp_text value "BSS138PW" (at 0 -2.3 180) (layer "B.Fab") hide
        (effects (font (size 0.7 0.7) (thickness 0.15)) (justify left bottom mirror))
    )
    (fp_text user "License: Apache-2.0" (at -1.45 -6.782 180) (layer "B.Fab") hide
        (effects (font (size 0.7 0.7) (thickness 0.15)) (justify left bottom mirror))
    )
    (fp_text user "${REFERENCE}" (at -1.45 -4.783 180) (layer "B.Fab") hide
        (effects (font (size 0.7 0.7) (thickness 0.15)) (justify left bottom mirror))
    )
    (fp_text user "Author: Antmicro" (at -1.45 -5.782 180) (layer "B.Fab") hide
        (effects (font (size 0.7 0.7) (thickness 0.15)) (justify left bottom mirror))
    )
    (fp_line (start -0.3 -1) (end 0.627 -1.001)
      (stroke (width 0.15) (type solid)) (layer "B.SilkS"))
    (fp_line (start -0.3 1) (end 0.627 0.999)
      (stroke (width 0.15) (type solid)) (layer "B.SilkS"))
    (fp_line (start 0.627 -0.6) (end 0.627 -1.001)
      (stroke (width 0.15) (type solid)) (layer "B.SilkS"))
    (fp_line (start 0.627 0.6) (end 0.627 0.999)
      (stroke (width 0.15) (type solid)) (layer "B.SilkS"))
    (fp_rect (start 1.4 -1.3) (end -1.4 1.3)
      (stroke (width 0.05) (type solid)) (fill none) (layer "B.CrtYd"))
    (fp_rect (start -0.623 0.999) (end 0.627 -1.001)
      (stroke (width 0.15) (type solid)) (fill none) (layer "B.Fab"))
    (pad "1" smd rect (at -0.95 0.65 270) (size 0.6 0.8) (layers "B.Cu" "B.Paste" "B.Mask")
      (net 788 "HOT_SWAP_RED") (pinfunction "G") (pintype "bidirectional"))
    (pad "2" smd rect (at -0.95 -0.65 270) (size 0.6 0.8) (layers "B.Cu" "B.Paste" "B.Mask")
      (net 9 "GND") (pinfunction "S") (pintype "bidirectional"))
    (pad "3" smd rect (at 0.95 0 270) (size 0.6 0.8) (layers "B.Cu" "B.Paste" "B.Mask")
      (net 582 "Net-(Q10-D)") (pinfunction "D") (pintype "bidirectional"))
  )

  (footprint "data-center-rdimm-ddr4-tester-footprints:C_0201" (layer "B.Cu")
    (at 187.34 103.1)
    (descr "Capacitor SMD 0201")
    (tags "capacitor SMD 0201")
    (property "Author" "Antmicro")
    (property "Dielectric" "")
    (property "License" "Apache-2.0")
    (property "MPN" "CC0201KRX6S5BB104")
    (property "Manufacturer" "Yaego")
    (property "Sheetfile" "fpga-power.kicad_sch")
    (property "Sheetname" "FPGA power")
    (property "Val" "100n")
    (property "Voltage" "")
    (property "ki_description" " ")
    (attr smd)
    (fp_text reference "C305" (at 0.98 1.11 180) (layer "B.SilkS")
        (effects (font (size 0.7 0.7) (thickness 0.15)) (justify left bottom mirror))
    )
    (fp_text value "C_100n_0201" (at 0 -1.4 180) (layer "B.Fab") hide
        (effects (font (size 0.7 0.7) (thickness 0.15)) (justify left bottom mirror))
    )
    (fp_text user "${REFERENCE}" (at -0.72 -3.4 180) (layer "B.Fab") hide
        (effects (font (size 0.7 0.7) (thickness 0.15)) (justify left bottom mirror))
    )
    (fp_text user "License: Apache-2.0" (at -0.72 -4.4 180) (layer "B.Fab") hide
        (effects (font (size 0.7 0.7) (thickness 0.15)) (justify left bottom mirror))
    )
    (fp_text user "Author: Antmicro" (at -0.72 -5.4 180) (layer "B.Fab") hide
        (effects (font (size 0.7 0.7) (thickness 0.15)) (justify left bottom mirror))
    )
    (fp_rect (start -0.72 0.38) (end 0.72 -0.38)
      (stroke (width 0.05) (type solid)) (fill none) (layer "B.CrtYd"))
    (fp_rect (start 0.3 -0.15) (end -0.301 0.149)
      (stroke (width 0.15) (type solid)) (fill none) (layer "B.Fab"))
    (pad "" smd roundrect (at -0.349 0.002) (size 0.318 0.36) (layers "B.Paste") (roundrect_rratio 0.25))
    (pad "" smd roundrect (at 0.341 0.002) (size 0.318 0.36) (layers "B.Paste") (roundrect_rratio 0.25))
    (pad "1" smd roundrect (at -0.321 0.002) (size 0.46 0.4) (layers "B.Cu" "B.Mask") (roundrect_rratio 0.25)
      (net 143 "3V3_SYS") (pintype "passive"))
    (pad "2" smd roundrect (at 0.32 0.002) (size 0.46 0.4) (layers "B.Cu" "B.Mask") (roundrect_rratio 0.25)
      (net 9 "GND") (pintype "passive"))
  )

  (footprint "data-center-rdimm-ddr4-tester-footprints:C_0402_1005Metric" (layer "B.Cu")
    (at 163.1 122.25 180)
    (descr "Capacitor SMD 0402")
    (tags "capacitor SMD 0402")
    (property "Author" "Antmicro")
    (property "Dielectric" "")
    (property "License" "Apache-2.0")
    (property "MPN" "MC0402B104K160CT")
    (property "Manufacturer" "Multicomp")
    (property "Sheetfile" "ethernet.kicad_sch")
    (property "Sheetname" "Ethernet")
    (property "Val" "100n")
    (property "Voltage" "")
    (property "ki_description" " ")
    (attr smd)
    (fp_text reference "C221" (at -1.45 -1.28) (layer "B.SilkS")
        (effects (font (size 0.7 0.7) (thickness 0.15)) (justify left bottom mirror))
    )
    (fp_text value "C_100n_16V_0402" (at 0 -1.4) (layer "B.Fab") hide
        (effects (font (size 0.7 0.7) (thickness 0.15)) (justify left bottom mirror))
    )
    (fp_text user "${REFERENCE}" (at -0.932 -3.168) (layer "B.Fab") hide
        (effects (font (size 0.7 0.7) (thickness 0.15)) (justify left bottom mirror))
    )
    (fp_text user "License: Apache-2.0" (at -0.932 -5.17) (layer "B.Fab") hide
        (effects (font (size 0.7 0.7) (thickness 0.15)) (justify left bottom mirror))
    )
    (fp_text user "Author: Antmicro" (at -0.932 -4.17) (layer "B.Fab") hide
        (effects (font (size 0.7 0.7) (thickness 0.15)) (justify left bottom mirror))
    )
    (fp_rect (start -0.94 0.47) (end 0.94 -0.47)
      (stroke (width 0.05) (type solid)) (fill none) (layer "B.CrtYd"))
    (fp_rect (start -0.499 0.249) (end 0.499 -0.249)
      (stroke (width 0.15) (type solid)) (fill none) (layer "B.Fab"))
    (pad "1" smd roundrect (at -0.484 0 180) (size 0.59 0.64) (layers "B.Cu" "B.Paste" "B.Mask") (roundrect_rratio 0.25)
      (net 92 "Net-(J2-P4)") (pintype "passive"))
    (pad "2" smd roundrect (at 0.484 0 180) (size 0.59 0.64) (layers "B.Cu" "B.Paste" "B.Mask") (roundrect_rratio 0.25)
      (net 9 "GND") (pintype "passive"))
  )

  (footprint "data-center-rdimm-ddr4-tester-footprints:C_0201" (layer "B.Cu")
    (at 196.14 92.53 90)
    (descr "Capacitor SMD 0201")
    (tags "capacitor SMD 0201")
    (property "Author" "Antmicro")
    (property "Dielectric" "")
    (property "License" "Apache-2.0")
    (property "MPN" "CC0201KRX6S5BB104")
    (property "Manufacturer" "Yaego")
    (property "Sheetfile" "fpga-power.kicad_sch")
    (property "Sheetname" "FPGA power")
    (property "Val" "100n")
    (property "Voltage" "")
    (property "ki_description" " ")
    (attr smd)
    (fp_text reference "C253" (at 0.85 2.65 270) (layer "B.SilkS")
        (effects (font (size 0.7 0.7) (thickness 0.15)) (justify left bottom mirror))
    )
    (fp_text value "C_100n_0201" (at 0 -1.4 270) (layer "B.Fab") hide
        (effects (font (size 0.7 0.7) (thickness 0.15)) (justify left bottom mirror))
    )
    (fp_text user "Author: Antmicro" (at -0.72 -5.4 270) (layer "B.Fab") hide
        (effects (font (size 0.7 0.7) (thickness 0.15)) (justify left bottom mirror))
    )
    (fp_text user "${REFERENCE}" (at -0.72 -3.4 270) (layer "B.Fab") hide
        (effects (font (size 0.7 0.7) (thickness 0.15)) (justify left bottom mirror))
    )
    (fp_text user "License: Apache-2.0" (at -0.72 -4.4 270) (layer "B.Fab") hide
        (effects (font (size 0.7 0.7) (thickness 0.15)) (justify left bottom mirror))
    )
    (fp_rect (start -0.72 0.38) (end 0.72 -0.38)
      (stroke (width 0.05) (type solid)) (fill none) (layer "B.CrtYd"))
    (fp_rect (start 0.3 -0.15) (end -0.301 0.149)
      (stroke (width 0.15) (type solid)) (fill none) (layer "B.Fab"))
    (pad "" smd roundrect (at -0.349 0.002 90) (size 0.318 0.36) (layers "B.Paste") (roundrect_rratio 0.25))
    (pad "" smd roundrect (at 0.341 0.002 90) (size 0.318 0.36) (layers "B.Paste") (roundrect_rratio 0.25))
    (pad "1" smd roundrect (at -0.321 0.002 90) (size 0.46 0.4) (layers "B.Cu" "B.Mask") (roundrect_rratio 0.25)
      (net 306 "1V2_SYS") (pintype "passive"))
    (pad "2" smd roundrect (at 0.32 0.002 90) (size 0.46 0.4) (layers "B.Cu" "B.Mask") (roundrect_rratio 0.25)
      (net 9 "GND") (pintype "passive"))
  )

  (footprint "data-center-rdimm-ddr4-tester-footprints:TP_SMD_0.75mm" (layer "B.Cu")
    (at 243.5 127 180)
    (property "Author" "Antmicro")
    (property "License" "Apache-2.0")
    (property "MPN" "")
    (property "Manufacturer" "")
    (property "Sheetfile" "fmc_hpc.kicad_sch")
    (property "Sheetname" "FMC HPC")
    (property "ki_description" "Test Point 0.75mm")
    (attr exclude_from_pos_files)
    (fp_text reference "TP15" (at -0.45 -0.38 90) (layer "B.SilkS")
        (effects (font (size 0.7 0.7) (thickness 0.15)) (justify left bottom mirror))
    )
    (fp_text value "TP_0.75mm_SMD" (at 0 -1.2) (layer "B.Fab") hide
        (effects (font (size 0.7 0.7) (thickness 0.15)) (justify left bottom mirror))
    )
    (fp_text user "${REFERENCE}" (at -0.4 -2.7) (layer "B.Fab") hide
        (effects (font (size 0.7 0.7) (thickness 0.15)) (justify left bottom mirror))
    )
    (fp_text user "License: Apache-2.0" (at -0.4 -5.101) (layer "B.Fab") hide
        (effects (font (size 0.7 0.7) (thickness 0.15)) (justify left bottom mirror))
    )
    (fp_text user "Author: Antmicro" (at -0.4 -3.901) (layer "B.Fab") hide
        (effects (font (size 0.7 0.7) (thickness 0.15)) (justify left bottom mirror))
    )
    (pad "1" smd circle (at 0 0 180) (size 0.75 0.75) (layers "B.Cu" "B.Mask")
      (net 542 "Net-(J5A-VREF_{B_M2C})") (pinfunction "1") (pintype "passive"))
  )

  (footprint "data-center-rdimm-ddr4-tester-footprints:R_0402_1005Metric" (layer "B.Cu")
    (at 241.1 120.1 180)
    (descr "Resistor SMD 0402")
    (tags "resistor SMD 0402")
    (property "Author" "Antmicro")
    (property "License" "Apache-2.0")
    (property "MPN" "CR0402-FX-1002GLF")
    (property "Manufacturer" "Bourns")
    (property "Sheetfile" "fmc_hpc.kicad_sch")
    (property "Sheetname" "FMC HPC")
    (property "Tolerance" "1%")
    (property "Val" "10k")
    (property "ki_description" "10k resistor in 0402 package with 1% tolerance")
    (attr smd)
    (fp_text reference "R208" (at 0.87 -0.37) (layer "B.SilkS")
        (effects (font (size 0.7 0.7) (thickness 0.15)) (justify left bottom mirror))
    )
    (fp_text value "R_10k_0402" (at 0 -1.4) (layer "B.Fab") hide
        (effects (font (size 0.7 0.7) (thickness 0.15)) (justify left bottom mirror))
    )
    (fp_text user "${REFERENCE}" (at -0.95 -3.168) (layer "B.Fab") hide
        (effects (font (size 0.7 0.7) (thickness 0.15)) (justify left bottom mirror))
    )
    (fp_text user "License: Apache-2.0" (at -0.95 -5.169) (layer "B.Fab") hide
        (effects (font (size 0.7 0.7) (thickness 0.15)) (justify left bottom mirror))
    )
    (fp_text user "Author: Antmicro" (at -0.95 -4.169) (layer "B.Fab") hide
        (effects (font (size 0.7 0.7) (thickness 0.15)) (justify left bottom mirror))
    )
    (fp_rect (start -0.93 0.47) (end 0.93 -0.47)
      (stroke (width 0.05) (type solid)) (fill none) (layer "B.CrtYd"))
    (fp_rect (start -0.5 0.25) (end 0.5 -0.25)
      (stroke (width 0.15) (type solid)) (fill none) (layer "B.Fab"))
    (pad "1" smd roundrect (at -0.485 0 180) (size 0.59 0.64) (layers "B.Cu" "B.Paste" "B.Mask") (roundrect_rratio 0.25)
      (net 751 "PRSNT_M2C") (pintype "passive"))
    (pad "2" smd roundrect (at 0.485 0 180) (size 0.59 0.64) (layers "B.Cu" "B.Paste" "B.Mask") (roundrect_rratio 0.25)
      (net 143 "3V3_SYS") (pintype "passive"))
  )

  (footprint "data-center-rdimm-ddr4-tester-footprints:R_0603_1608Metric" (layer "B.Cu")
    (at 153.15 123.55)
    (descr "Resistor SMD 0603")
    (tags "resistor SMD 0603")
    (property "Author" "Antmicro")
    (property "License" "Apache-2.0")
    (property "MPN" "ERJ-UP3F3300V")
    (property "Manufacturer" "Panasonic")
    (property "Sheetfile" "supply.kicad_sch")
    (property "Sheetname" "Supply")
    (property "Tolerance" "1%")
    (property "Val" "330R")
    (property "ki_description" "330R resistor in 0603 package with 1% tolerance")
    (attr smd)
    (fp_text reference "R113" (at 1.48 1.32 180) (layer "B.SilkS")
        (effects (font (size 0.7 0.7) (thickness 0.15)) (justify left bottom mirror))
    )
    (fp_text value "R_330R_0.25W_0603" (at 0 -1.6 180) (layer "B.Fab") hide
        (effects (font (size 0.7 0.7) (thickness 0.15)) (justify left bottom mirror))
    )
    (fp_text user "License: Apache-2.0" (at -1.25 -5.9 180) (layer "B.Fab") hide
        (effects (font (size 0.7 0.7) (thickness 0.15)) (justify left bottom mirror))
    )
    (fp_text user "Author: Antmicro" (at -1.25 -4.9 180) (layer "B.Fab") hide
        (effects (font (size 0.7 0.7) (thickness 0.15)) (justify left bottom mirror))
    )
    (fp_text user "${REFERENCE}" (at -1.25 -3.898 180) (layer "B.Fab") hide
        (effects (font (size 0.7 0.7) (thickness 0.15)) (justify left bottom mirror))
    )
    (fp_line (start -0.3 -0.3) (end 0.3 -0.3)
      (stroke (width 0.15) (type solid)) (layer "B.SilkS"))
    (fp_line (start -0.3 0.3) (end 0.3 0.3)
      (stroke (width 0.15) (type solid)) (layer "B.SilkS"))
    (fp_rect (start -1.25 0.7) (end 1.25 -0.7)
      (stroke (width 0.05) (type solid)) (fill none) (layer "B.CrtYd"))
    (fp_rect (start -0.8 0.4) (end 0.8 -0.4)
      (stroke (width 0.15) (type solid)) (fill none) (layer "B.Fab"))
    (pad "1" smd roundrect (at -0.7 0) (size 0.6 0.8) (layers "B.Cu" "B.Paste" "B.Mask") (roundrect_rratio 0.2)
      (net 856 "Net-(R113-Pad1)") (pintype "passive"))
    (pad "2" smd roundrect (at 0.7 0) (size 0.6 0.8) (layers "B.Cu" "B.Paste" "B.Mask") (roundrect_rratio 0.2)
      (net 306 "1V2_SYS") (pintype "passive"))
  )

  (footprint "data-center-rdimm-ddr4-tester-footprints:SC-74-6_1.5x2.9mm_P0.95mm" (layer "B.Cu")
    (at 121.9 120.1 90)
    (descr "https://assets.nexperia.com/documents/data-sheet/IP4220CZ6.pdf")
    (tags "sc74 sc-74 sot23-6 sot457 tsop6 tsop-6")
    (property "Author" "Antmicro")
    (property "License" "Apache-2.0")
    (property "MPN" "74LVC2G07GV,125")
    (property "Manufacturer" "Nexperia")
    (property "Sheetfile" "supply.kicad_sch")
    (property "Sheetname" "Supply")
    (property "ki_description" "Dual Buffer w/ Open Drain, Low-Voltage CMOS, TSOP6 (SOT457/SC-74/SOT23-6) package 1.1mm height, Texas Instruments Equivalent: SN74LVC2G07DBVR")
    (property "ki_keywords" "Dual Gate Buffer Open Drain LVC CMOS")
    (attr smd)
    (fp_text reference "U24" (at -1.67 -1.28) (layer "B.SilkS")
        (effects (font (size 0.7 0.7) (thickness 0.15)) (justify left bottom mirror))
    )
    (fp_text value "74LVC2G07_SOT457" (at -2 -2.999 270) (layer "B.Fab") hide
        (effects (font (size 0.7 0.7) (thickness 0.15)) (justify left bottom mirror))
    )
    (fp_text user "Author: Antmicro" (at -2.12 -4.999 270) (layer "B.Fab") hide
        (effects (font (size 0.7 0.7) (thickness 0.15)) (justify left bottom mirror))
    )
    (fp_text user "License: Apache-2.0" (at -2.12 -6.199 270) (layer "B.Fab") hide
        (effects (font (size 0.7 0.7) (thickness 0.15)) (justify left bottom mirror))
    )
    (fp_text user "${REFERENCE}" (at -2.12 -7.399 270) (layer "B.Fab") hide
        (effects (font (size 0.7 0.7) (thickness 0.15)) (justify left bottom mirror))
    )
    (fp_circle (center -2.07 0.956) (end -2.02 0.956)
      (stroke (width 0.15) (type solid)) (fill solid) (layer "B.SilkS"))
    (fp_circle (center -2.069 0.956) (end -2.02 0.956)
      (stroke (width 0.15) (type solid)) (fill solid) (layer "B.SilkS"))
    (fp_rect (start -1.714 1.897) (end 1.711 -1.896)
      (stroke (width 0.05) (type solid)) (fill none) (layer "B.CrtYd"))
    (fp_line (start -1.27 -1.372) (end -1.168 -1.372)
      (stroke (width 0.15) (type solid)) (layer "B.Fab"))
    (fp_line (start -1.27 0.915) (end -1.27 -1.372)
      (stroke (width 0.15) (type solid)) (layer "B.Fab"))
    (fp_line (start -1.168 -1.372) (end 1.219 -1.372)
      (stroke (width 0.15) (type solid)) (layer "B.Fab"))
    (fp_line (start -0.761 1.422) (end -1.27 0.915)
      (stroke (width 0.15) (type solid)) (layer "B.Fab"))
    (fp_line (start 1.219 -1.372) (end 1.219 1.422)
      (stroke (width 0.15) (type solid)) (layer "B.Fab"))
    (fp_line (start 1.219 1.422) (end -0.761 1.422)
      (stroke (width 0.15) (type solid)) (layer "B.Fab"))
    (fp_circle (center -2.069 0.956) (end -2.02 0.956)
      (stroke (width 0.15) (type solid)) (fill solid) (layer "B.Fab"))
    (pad "1" smd roundrect (at -1.214 0.955 90) (size 0.8 0.55) (layers "B.Cu" "B.Paste" "B.Mask") (roundrect_rratio 0.15)
      (net 153 "/Supply/VCC_IO_EN") (pintype "input"))
    (pad "2" smd roundrect (at -1.214 0.003 90) (size 0.8 0.55) (layers "B.Cu" "B.Paste" "B.Mask") (roundrect_rratio 0.15)
      (net 9 "GND") (pinfunction "GND") (pintype "power_in"))
    (pad "3" smd roundrect (at -1.214 -0.947 90) (size 0.8 0.55) (layers "B.Cu" "B.Paste" "B.Mask") (roundrect_rratio 0.15)
      (net 153 "/Supply/VCC_IO_EN") (pintype "input"))
    (pad "4" smd roundrect (at 1.187 -0.947 90) (size 0.8 0.55) (layers "B.Cu" "B.Paste" "B.Mask") (roundrect_rratio 0.15)
      (net 857 "Net-(R114-Pad1)") (pintype "output"))
    (pad "5" smd roundrect (at 1.187 0.003 90) (size 0.8 0.55) (layers "B.Cu" "B.Paste" "B.Mask") (roundrect_rratio 0.15)
      (net 307 "5V0_SYS") (pinfunction "V_{CC}") (pintype "power_in"))
    (pad "6" smd roundrect (at 1.187 0.955 90) (size 0.8 0.55) (layers "B.Cu" "B.Paste" "B.Mask") (roundrect_rratio 0.15)
      (net 856 "Net-(R113-Pad1)") (pintype "output"))
  )

  (footprint "data-center-rdimm-ddr4-tester-footprints:R_0402_1005Metric" (layer "B.Cu")
    (at 136.47 102.12 180)
    (descr "Resistor SMD 0402")
    (tags "resistor SMD 0402")
    (property "Author" "Antmicro")
    (property "Current" "1A")
    (property "DNP" "DNP")
    (property "License" "Apache-2.0")
    (property "MPN" "ERJ2GE0R00X")
    (property "Manufacturer" "Panasonic")
    (property "Sheetfile" "supply.kicad_sch")
    (property "Sheetname" "Supply")
    (property "Tolerance" "")
    (property "Val" "0R")
    (property "dnp" "")
    (property "exclude_from_bom" "")
    (property "ki_description" "0R resistor in 0402 package with unspecified tolerance")
    (attr exclude_from_pos_files exclude_from_bom)
    (fp_text reference "R196" (at -1.81 -1.32) (layer "B.SilkS")
        (effects (font (size 0.7 0.7) (thickness 0.15)) (justify left bottom mirror))
    )
    (fp_text value "R_0R_0402" (at 0 -1.4) (layer "B.Fab") hide
        (effects (font (size 0.7 0.7) (thickness 0.15)) (justify left bottom mirror))
    )
    (fp_text user "Author: Antmicro" (at -0.95 -4.169) (layer "B.Fab") hide
        (effects (font (size 0.7 0.7) (thickness 0.15)) (justify left bottom mirror))
    )
    (fp_text user "${REFERENCE}" (at -0.95 -3.168) (layer "B.Fab") hide
        (effects (font (size 0.7 0.7) (thickness 0.15)) (justify left bottom mirror))
    )
    (fp_text user "License: Apache-2.0" (at -0.95 -5.169) (layer "B.Fab") hide
        (effects (font (size 0.7 0.7) (thickness 0.15)) (justify left bottom mirror))
    )
    (fp_rect (start -0.93 0.47) (end 0.93 -0.47)
      (stroke (width 0.05) (type solid)) (fill none) (layer "B.CrtYd"))
    (fp_rect (start -0.5 0.25) (end 0.5 -0.25)
      (stroke (width 0.15) (type solid)) (fill none) (layer "B.Fab"))
    (pad "1" smd roundrect (at -0.485 0 180) (size 0.59 0.64) (layers "B.Cu" "B.Paste" "B.Mask") (roundrect_rratio 0.25)
      (net 153 "/Supply/VCC_IO_EN") (pintype "passive"))
    (pad "2" smd roundrect (at 0.485 0 180) (size 0.59 0.64) (layers "B.Cu" "B.Paste" "B.Mask") (roundrect_rratio 0.25)
      (net 793 "/Supply/VTT_CNTL") (pintype "passive"))
  )

  (footprint "data-center-rdimm-ddr4-tester-footprints:VQFN-16-1EP_3x3mm_P0.5mm_EP1.1x1.1mm" (layer "B.Cu")
    (at 119.56 88.5175 90)
    (descr "VQFN, 16 Pin (https://ww1.microchip.com/downloads/en/DeviceDoc/16L_VQFN-WFS_3x3mm_4MX_C04-00508a.pdf), generated with kicad-footprint-generator ipc_noLead_generator.py")
    (tags "VQFN NoLead")
    (property "Author" "Antmicro")
    (property "License" "Apache-2.0")
    (property "MPN" "PAC1954T-E/4MX")
    (property "Manufacturer" "Microchip Technology")
    (property "Sheetfile" "supply.kicad_sch")
    (property "Sheetname" "Supply")
    (property "ki_description" "Current/Voltage Monitor Regulator High-Side 16-VQFN (3x3)")
    (property "ki_keywords" "MONITOR, VOLTAGE")
    (attr smd)
    (fp_text reference "U19" (at 1.8475 -0.83) (layer "B.SilkS")
        (effects (font (size 0.7 0.7) (thickness 0.15)) (justify left bottom mirror))
    )
    (fp_text value "PAC1954T-E_VQFN" (at 0 -2.797 270) (layer "B.Fab") hide
        (effects (font (size 0.7 0.7) (thickness 0.15)) (justify left bottom mirror))
    )
    (fp_text user "License: Apache-2.0" (at -2.35 -7.197 270) (layer "B.Fab") hide
        (effects (font (size 0.7 0.7) (thickness 0.15)) (justify left bottom mirror))
    )
    (fp_text user "${REFERENCE}" (at -2.35 -4.797 270) (layer "B.Fab") hide
        (effects (font (size 0.7 0.7) (thickness 0.15)) (justify left bottom mirror))
    )
    (fp_text user "Author: Antmicro" (at -2.35 -5.997 270) (layer "B.Fab") hide
        (effects (font (size 0.7 0.7) (thickness 0.15)) (justify left bottom mirror))
    )
    (fp_line (start -1.611 -1.61) (end -1.611 -1.134)
      (stroke (width 0.15) (type solid)) (layer "B.SilkS"))
    (fp_line (start -1.135 -1.61) (end -1.611 -1.61)
      (stroke (width 0.15) (type solid)) (layer "B.SilkS"))
    (fp_line (start -1.135 1.611) (end -1.611 1.611)
      (stroke (width 0.15) (type solid)) (layer "B.SilkS"))
    (fp_line (start 1.134 -1.61) (end 1.61 -1.61)
      (stroke (width 0.15) (type solid)) (layer "B.SilkS"))
    (fp_line (start 1.134 1.611) (end 1.61 1.611)
      (stroke (width 0.15) (type solid)) (layer "B.SilkS"))
    (fp_line (start 1.61 -1.61) (end 1.61 -1.134)
      (stroke (width 0.15) (type solid)) (layer "B.SilkS"))
    (fp_line (start 1.61 1.611) (end 1.61 1.135)
      (stroke (width 0.15) (type solid)) (layer "B.SilkS"))
    (fp_circle (center -2.3 0.75) (end -2.25 0.75)
      (stroke (width 0.15) (type solid)) (fill solid) (layer "B.SilkS"))
    (fp_rect (start -2 2) (end 1.999 -1.999)
      (stroke (width 0.05) (type solid)) (fill none) (layer "B.CrtYd"))
    (fp_line (start -1.5 -1.499) (end -1.5 0.75)
      (stroke (width 0.15) (type solid)) (layer "B.Fab"))
    (fp_line (start -1.5 0.75) (end -0.75 1.5)
      (stroke (width 0.15) (type solid)) (layer "B.Fab"))
    (fp_line (start -0.75 1.5) (end 1.499 1.5)
      (stroke (width 0.15) (type solid)) (layer "B.Fab"))
    (fp_line (start 1.499 -1.499) (end -1.5 -1.499)
      (stroke (width 0.15) (type solid)) (layer "B.Fab"))
    (fp_line (start 1.499 1.5) (end 1.499 -1.499)
      (stroke (width 0.15) (type solid)) (layer "B.Fab"))
    (fp_circle (center -2.3 0.75) (end -2.25 0.75)
      (stroke (width 0.15) (type solid)) (fill solid) (layer "B.Fab"))
    (pad "" smd roundrect (at 0 0 90) (size 0.89 0.89) (layers "B.Paste") (roundrect_rratio 0.25))
    (pad "1" smd roundrect (at -1.464 0.75 90) (size 0.775 0.25) (layers "B.Cu" "B.Paste" "B.Mask") (roundrect_rratio 0.25)
      (net 9 "GND") (pinfunction "SLOW/~{ALERT1}") (pintype "bidirectional"))
    (pad "2" smd roundrect (at -1.464 0.25 90) (size 0.775 0.25) (layers "B.Cu" "B.Paste" "B.Mask") (roundrect_rratio 0.25)
      (net 143 "3V3_SYS") (pinfunction "VDD") (pintype "power_in"))
    (pad "3" smd roundrect (at -1.464 -0.247 90) (size 0.775 0.25) (layers "B.Cu" "B.Paste" "B.Mask") (roundrect_rratio 0.25)
      (net 9 "GND") (pinfunction "GND") (pintype "power_in"))
    (pad "4" smd roundrect (at -1.464 -0.747 90) (size 0.775 0.25) (layers "B.Cu" "B.Paste" "B.Mask") (roundrect_rratio 0.25)
      (net 358 "SCL_3V3") (pinfunction "SCL") (pintype "input"))
    (pad "5" smd roundrect (at -0.75 -1.461 90) (size 0.25 0.775) (layers "B.Cu" "B.Paste" "B.Mask") (roundrect_rratio 0.25)
      (net 357 "SDA_3V3") (pinfunction "SDA") (pintype "bidirectional"))
    (pad "6" smd roundrect (at -0.25 -1.461 90) (size 0.25 0.775) (layers "B.Cu" "B.Paste" "B.Mask") (roundrect_rratio 0.25)
      (net 143 "3V3_SYS") (pinfunction "ADDRSEL") (pintype "bidirectional"))
    (pad "7" smd roundrect (at 0.247 -1.461 90) (size 0.25 0.775) (layers "B.Cu" "B.Paste" "B.Mask") (roundrect_rratio 0.25)
      (net 837 "/Supply/VTT_SEN_-") (pinfunction "IN3-") (pintype "input"))
    (pad "8" smd roundrect (at 0.747 -1.461 90) (size 0.25 0.775) (layers "B.Cu" "B.Paste" "B.Mask") (roundrect_rratio 0.25)
      (net 834 "/Supply/VTT_SEN_+") (pinfunction "IN3+") (pintype "input"))
    (pad "9" smd roundrect (at 1.461 -0.747 90) (size 0.775 0.25) (layers "B.Cu" "B.Paste" "B.Mask") (roundrect_rratio 0.25)
      (net 806 "/Supply/VCC1V2_SEN_-") (pinfunction "IN4-") (pintype "input"))
    (pad "10" smd roundrect (at 1.461 -0.247 90) (size 0.775 0.25) (layers "B.Cu" "B.Paste" "B.Mask") (roundrect_rratio 0.25)
      (net 805 "/Supply/VCC1V2_SEN_+") (pinfunction "IN4+") (pintype "input"))
    (pad "11" smd roundrect (at 1.461 0.25 90) (size 0.775 0.25) (layers "B.Cu" "B.Paste" "B.Mask") (roundrect_rratio 0.25)
      (net 833 "/Supply/VDDQ_SEN_+") (pinfunction "IN1+") (pintype "input"))
    (pad "12" smd roundrect (at 1.461 0.75 90) (size 0.775 0.25) (layers "B.Cu" "B.Paste" "B.Mask") (roundrect_rratio 0.25)
      (net 835 "/Supply/VDDQ_SEN_-") (pinfunction "IN1-") (pintype "input"))
    (pad "13" smd roundrect (at 0.747 1.464 90) (size 0.25 0.775) (layers "B.Cu" "B.Paste" "B.Mask") (roundrect_rratio 0.25)
      (net 832 "/Supply/VPP_SEN_+") (pinfunction "IN2+") (pintype "input"))
    (pad "14" smd roundrect (at 0.247 1.464 90) (size 0.25 0.775) (layers "B.Cu" "B.Paste" "B.Mask") (roundrect_rratio 0.25)
      (net 836 "/Supply/VPP_SEN_-") (pinfunction "IN2-") (pintype "input"))
    (pad "15" smd roundrect (at -0.25 1.464 90) (size 0.25 0.775) (layers "B.Cu" "B.Paste" "B.Mask") (roundrect_rratio 0.25)
      (net 9 "GND") (pinfunction "GPIO/~{ALERT2}") (pintype "bidirectional"))
    (pad "16" smd roundrect (at -0.75 1.464 90) (size 0.25 0.775) (layers "B.Cu" "B.Paste" "B.Mask") (roundrect_rratio 0.25)
      (net 660 "Net-(U19-~{PWRDN})") (pinfunction "~{PWRDN}") (pintype "input"))
    (pad "17" smd rect (at 0 0 90) (size 1.1 1.1) (layers "B.Cu" "B.Mask")
      (net 917 "unconnected-(U19-EP-Pad17)") (pinfunction "EP") (pintype "no_connect"))
  )

  (footprint "data-center-rdimm-ddr4-tester-footprints:R_0603_1608Metric" (layer "B.Cu")
    (at 144.1 80.4)
    (descr "Resistor SMD 0603")
    (tags "resistor SMD 0603")
    (property "Author" "Antmicro")
    (property "License" "Apache-2.0")
    (property "MPN" "ERJ-UP3F3300V")
    (property "Manufacturer" "Panasonic")
    (property "Sheetfile" "supply.kicad_sch")
    (property "Sheetname" "Supply")
    (property "Tolerance" "1%")
    (property "Val" "330R")
    (property "ki_description" "330R resistor in 0603 package with 1% tolerance")
    (attr smd)
    (fp_text reference "R29" (at 1.14 -0.52 180) (layer "B.SilkS")
        (effects (font (size 0.7 0.7) (thickness 0.15)) (justify left bottom mirror))
    )
    (fp_text value "R_330R_0.25W_0603" (at 0 -1.6 180) (layer "B.Fab") hide
        (effects (font (size 0.7 0.7) (thickness 0.15)) (justify left bottom mirror))
    )
    (fp_text user "${REFERENCE}" (at -1.25 -3.898 180) (layer "B.Fab") hide
        (effects (font (size 0.7 0.7) (thickness 0.15)) (justify left bottom mirror))
    )
    (fp_text user "Author: Antmicro" (at -1.25 -4.9 180) (layer "B.Fab") hide
        (effects (font (size 0.7 0.7) (thickness 0.15)) (justify left bottom mirror))
    )
    (fp_text user "License: Apache-2.0" (at -1.25 -5.9 180) (layer "B.Fab") hide
        (effects (font (size 0.7 0.7) (thickness 0.15)) (justify left bottom mirror))
    )
    (fp_line (start -0.3 -0.3) (end 0.3 -0.3)
      (stroke (width 0.15) (type solid)) (layer "B.SilkS"))
    (fp_line (start -0.3 0.3) (end 0.3 0.3)
      (stroke (width 0.15) (type solid)) (layer "B.SilkS"))
    (fp_rect (start -1.25 0.7) (end 1.25 -0.7)
      (stroke (width 0.05) (type solid)) (fill none) (layer "B.CrtYd"))
    (fp_rect (start -0.8 0.4) (end 0.8 -0.4)
      (stroke (width 0.15) (type solid)) (fill none) (layer "B.Fab"))
    (pad "1" smd roundrect (at -0.7 0) (size 0.6 0.8) (layers "B.Cu" "B.Paste" "B.Mask") (roundrect_rratio 0.2)
      (net 855 "Net-(R29-Pad1)") (pintype "passive"))
    (pad "2" smd roundrect (at 0.7 0) (size 0.6 0.8) (layers "B.Cu" "B.Paste" "B.Mask") (roundrect_rratio 0.2)
      (net 147 "1V0_SYS") (pintype "passive"))
  )

  (footprint "data-center-rdimm-ddr4-tester-footprints:C_0201" (layer "B.Cu")
    (at 192.09 96.6)
    (descr "Capacitor SMD 0201")
    (tags "capacitor SMD 0201")
    (property "Author" "Antmicro")
    (property "Dielectric" "")
    (property "License" "Apache-2.0")
    (property "MPN" "CC0201KRX6S5BB104")
    (property "Manufacturer" "Yaego")
    (property "Sheetfile" "fpga-power.kicad_sch")
    (property "Sheetname" "FPGA power")
    (property "Val" "100n")
    (property "Voltage" "")
    (property "ki_description" " ")
    (attr smd)
    (fp_text reference "C243" (at 3.39 0.54 180) (layer "B.SilkS")
        (effects (font (size 0.7 0.7) (thickness 0.15)) (justify left bottom mirror))
    )
    (fp_text value "C_100n_0201" (at 0 -1.4 180) (layer "B.Fab") hide
        (effects (font (size 0.7 0.7) (thickness 0.15)) (justify left bottom mirror))
    )
    (fp_text user "${REFERENCE}" (at -0.72 -3.4 180) (layer "B.Fab") hide
        (effects (font (size 0.7 0.7) (thickness 0.15)) (justify left bottom mirror))
    )
    (fp_text user "License: Apache-2.0" (at -0.72 -4.4 180) (layer "B.Fab") hide
        (effects (font (size 0.7 0.7) (thickness 0.15)) (justify left bottom mirror))
    )
    (fp_text user "Author: Antmicro" (at -0.72 -5.4 180) (layer "B.Fab") hide
        (effects (font (size 0.7 0.7) (thickness 0.15)) (justify left bottom mirror))
    )
    (fp_rect (start -0.72 0.38) (end 0.72 -0.38)
      (stroke (width 0.05) (type solid)) (fill none) (layer "B.CrtYd"))
    (fp_rect (start 0.3 -0.15) (end -0.301 0.149)
      (stroke (width 0.15) (type solid)) (fill none) (layer "B.Fab"))
    (pad "" smd roundrect (at -0.349 0.002) (size 0.318 0.36) (layers "B.Paste") (roundrect_rratio 0.25))
    (pad "" smd roundrect (at 0.341 0.002) (size 0.318 0.36) (layers "B.Paste") (roundrect_rratio 0.25))
    (pad "1" smd roundrect (at -0.321 0.002) (size 0.46 0.4) (layers "B.Cu" "B.Mask") (roundrect_rratio 0.25)
      (net 147 "1V0_SYS") (pintype "passive"))
    (pad "2" smd roundrect (at 0.32 0.002) (size 0.46 0.4) (layers "B.Cu" "B.Mask") (roundrect_rratio 0.25)
      (net 9 "GND") (pintype "passive"))
  )

  (footprint "data-center-rdimm-ddr4-tester-footprints:C_0201" (layer "B.Cu")
    (at 172.65 85.05 -90)
    (descr "Capacitor SMD 0201")
    (tags "capacitor SMD 0201")
    (property "Author" "Antmicro")
    (property "Dielectric" "")
    (property "License" "Apache-2.0")
    (property "MPN" "CC0201KRX6S5BB104")
    (property "Manufacturer" "Yaego")
    (property "Sheetfile" "fpga-power.kicad_sch")
    (property "Sheetname" "FPGA power")
    (property "Val" "100n")
    (property "Voltage" "")
    (property "ki_description" " ")
    (attr smd)
    (fp_text reference "C93" (at -1.07 0.49 90) (layer "B.SilkS")
        (effects (font (size 0.7 0.7) (thickness 0.15)) (justify left bottom mirror))
    )
    (fp_text value "C_100n_0201" (at 0 -1.4 90) (layer "B.Fab") hide
        (effects (font (size 0.7 0.7) (thickness 0.15)) (justify left bottom mirror))
    )
    (fp_text user "${REFERENCE}" (at -0.72 -3.4 90) (layer "B.Fab") hide
        (effects (font (size 0.7 0.7) (thickness 0.15)) (justify left bottom mirror))
    )
    (fp_text user "Author: Antmicro" (at -0.72 -5.4 90) (layer "B.Fab") hide
        (effects (font (size 0.7 0.7) (thickness 0.15)) (justify left bottom mirror))
    )
    (fp_text user "License: Apache-2.0" (at -0.72 -4.4 90) (layer "B.Fab") hide
        (effects (font (size 0.7 0.7) (thickness 0.15)) (justify left bottom mirror))
    )
    (fp_rect (start -0.72 0.38) (end 0.72 -0.38)
      (stroke (width 0.05) (type solid)) (fill none) (layer "B.CrtYd"))
    (fp_rect (start 0.3 -0.15) (end -0.301 0.149)
      (stroke (width 0.15) (type solid)) (fill none) (layer "B.Fab"))
    (pad "" smd roundrect (at -0.349 0.002 270) (size 0.318 0.36) (layers "B.Paste") (roundrect_rratio 0.25))
    (pad "" smd roundrect (at 0.341 0.002 270) (size 0.318 0.36) (layers "B.Paste") (roundrect_rratio 0.25))
    (pad "1" smd roundrect (at -0.321 0.002 270) (size 0.46 0.4) (layers "B.Cu" "B.Mask") (roundrect_rratio 0.25)
      (net 143 "3V3_SYS") (pintype "passive"))
    (pad "2" smd roundrect (at 0.32 0.002 270) (size 0.46 0.4) (layers "B.Cu" "B.Mask") (roundrect_rratio 0.25)
      (net 9 "GND") (pintype "passive"))
  )

  (footprint "data-center-rdimm-ddr4-tester-footprints:C_0201" (layer "B.Cu")
    (at 178.16 98.07 90)
    (descr "Capacitor SMD 0201")
    (tags "capacitor SMD 0201")
    (property "Author" "Antmicro")
    (property "Dielectric" "")
    (property "License" "Apache-2.0")
    (property "MPN" "CC0201KRX6S5BB104")
    (property "Manufacturer" "Yaego")
    (property "Sheetfile" "fpga-power.kicad_sch")
    (property "Sheetname" "FPGA power")
    (property "Val" "100n")
    (property "Voltage" "")
    (property "ki_description" " ")
    (attr smd)
    (fp_text reference "C307" (at 1.18 1.2 270) (layer "B.SilkS")
        (effects (font (size 0.7 0.7) (thickness 0.15)) (justify left bottom mirror))
    )
    (fp_text value "C_100n_0201" (at 0 -1.4 270) (layer "B.Fab") hide
        (effects (font (size 0.7 0.7) (thickness 0.15)) (justify left bottom mirror))
    )
    (fp_text user "Author: Antmicro" (at -0.72 -5.4 270) (layer "B.Fab") hide
        (effects (font (size 0.7 0.7) (thickness 0.15)) (justify left bottom mirror))
    )
    (fp_text user "License: Apache-2.0" (at -0.72 -4.4 270) (layer "B.Fab") hide
        (effects (font (size 0.7 0.7) (thickness 0.15)) (justify left bottom mirror))
    )
    (fp_text user "${REFERENCE}" (at -0.72 -3.4 270) (layer "B.Fab") hide
        (effects (font (size 0.7 0.7) (thickness 0.15)) (justify left bottom mirror))
    )
    (fp_rect (start -0.72 0.38) (end 0.72 -0.38)
      (stroke (width 0.05) (type solid)) (fill none) (layer "B.CrtYd"))
    (fp_rect (start 0.3 -0.15) (end -0.301 0.149)
      (stroke (width 0.15) (type solid)) (fill none) (layer "B.Fab"))
    (pad "" smd roundrect (at -0.349 0.002 90) (size 0.318 0.36) (layers "B.Paste") (roundrect_rratio 0.25))
    (pad "" smd roundrect (at 0.341 0.002 90) (size 0.318 0.36) (layers "B.Paste") (roundrect_rratio 0.25))
    (pad "1" smd roundrect (at -0.321 0.002 90) (size 0.46 0.4) (layers "B.Cu" "B.Mask") (roundrect_rratio 0.25)
      (net 143 "3V3_SYS") (pintype "passive"))
    (pad "2" smd roundrect (at 0.32 0.002 90) (size 0.46 0.4) (layers "B.Cu" "B.Mask") (roundrect_rratio 0.25)
      (net 9 "GND") (pintype "passive"))
  )

  (footprint "data-center-rdimm-ddr4-tester-footprints:C_2220_5650Metric" (layer "B.Cu")
    (at 195.05 126)
    (descr "Capacitor SMD 2220")
    (tags "capacitor SMD 2220")
    (property "Author" "Antmicro")
    (property "Dielectric" "")
    (property "License" "Apache-2.0")
    (property "MPN" "C5750X7S2A226M280KB")
    (property "Manufacturer" "TDK")
    (property "Sheetfile" "ethernet.kicad_sch")
    (property "Sheetname" "Ethernet")
    (property "Val" "22u/100V")
    (property "Voltage" "")
    (property "ki_description" " ")
    (attr smd)
    (fp_text reference "C225" (at 4.61 -1.59 270) (layer "B.SilkS")
        (effects (font (size 0.7 0.7) (thickness 0.15)) (justify left bottom mirror))
    )
    (fp_text value "C_22u_100V_2220" (at 0 -3.9 180) (layer "B.Fab") hide
        (effects (font (size 0.7 0.7) (thickness 0.15)) (justify left bottom mirror))
    )
    (fp_text user "${REFERENCE}" (at -3.7 -5.9 180) (layer "B.Fab") hide
        (effects (font (size 0.7 0.7) (thickness 0.15)) (justify left bottom mirror))
    )
    (fp_text user "License: Apache-2.0" (at -3.7 -6.9 180) (layer "B.Fab") hide
        (effects (font (size 0.7 0.7) (thickness 0.15)) (justify left bottom mirror))
    )
    (fp_text user "Author: Antmicro" (at -3.7 -7.9 180) (layer "B.Fab") hide
        (effects (font (size 0.7 0.7) (thickness 0.15)) (justify left bottom mirror))
    )
    (fp_line (start -1.415 -2.61) (end 1.415 -2.61)
      (stroke (width 0.15) (type solid)) (layer "B.SilkS"))
    (fp_line (start -1.415 2.61) (end 1.415 2.61)
      (stroke (width 0.15) (type solid)) (layer "B.SilkS"))
    (fp_rect (start -3.7 2.95) (end 3.7 -2.95)
      (stroke (width 0.05) (type solid)) (fill none) (layer "B.CrtYd"))
    (fp_rect (start -2.85 2.5) (end 2.85 -2.5)
      (stroke (width 0.15) (type solid)) (fill none) (layer "B.Fab"))
    (pad "1" smd roundrect (at -2.55 0) (size 1.8 5.4) (layers "B.Cu" "B.Paste" "B.Mask") (roundrect_rratio 0.138889)
      (net 360 "/Ethernet/VDD") (pintype "passive"))
    (pad "2" smd roundrect (at 2.55 0) (size 1.8 5.4) (layers "B.Cu" "B.Paste" "B.Mask") (roundrect_rratio 0.138889)
      (net 604 "GNDD") (pintype "passive"))
  )

  (footprint "data-center-rdimm-ddr4-tester-footprints:C_0402_1005Metric" (layer "B.Cu")
    (at 165.4 116.3)
    (descr "Capacitor SMD 0402")
    (tags "capacitor SMD 0402")
    (property "Author" "Antmicro")
    (property "Dielectric" "")
    (property "License" "Apache-2.0")
    (property "MPN" "MC0402B104K160CT")
    (property "Manufacturer" "Multicomp")
    (property "Sheetfile" "ethernet.kicad_sch")
    (property "Sheetname" "Ethernet")
    (property "Val" "100n")
    (property "Voltage" "")
    (property "ki_description" " ")
    (attr smd)
    (fp_text reference "C312" (at 1.48 -0.53 180) (layer "B.SilkS")
        (effects (font (size 0.7 0.7) (thickness 0.15)) (justify left bottom mirror))
    )
    (fp_text value "C_100n_16V_0402" (at 0 -1.4 180) (layer "B.Fab") hide
        (effects (font (size 0.7 0.7) (thickness 0.15)) (justify left bottom mirror))
    )
    (fp_text user "Author: Antmicro" (at -0.932 -4.17 180) (layer "B.Fab") hide
        (effects (font (size 0.7 0.7) (thickness 0.15)) (justify left bottom mirror))
    )
    (fp_text user "License: Apache-2.0" (at -0.932 -5.17 180) (layer "B.Fab") hide
        (effects (font (size 0.7 0.7) (thickness 0.15)) (justify left bottom mirror))
    )
    (fp_text user "${REFERENCE}" (at -0.932 -3.168 180) (layer "B.Fab") hide
        (effects (font (size 0.7 0.7) (thickness 0.15)) (justify left bottom mirror))
    )
    (fp_rect (start -0.94 0.47) (end 0.94 -0.47)
      (stroke (width 0.05) (type solid)) (fill none) (layer "B.CrtYd"))
    (fp_rect (start -0.499 0.249) (end 0.499 -0.249)
      (stroke (width 0.15) (type solid)) (fill none) (layer "B.Fab"))
    (pad "1" smd roundrect (at -0.484 0) (size 0.59 0.64) (layers "B.Cu" "B.Paste" "B.Mask") (roundrect_rratio 0.25)
      (net 94 "Net-(J2-P5)") (pintype "passive"))
    (pad "2" smd roundrect (at 0.484 0) (size 0.59 0.64) (layers "B.Cu" "B.Paste" "B.Mask") (roundrect_rratio 0.25)
      (net 9 "GND") (pintype "passive"))
  )

  (footprint "data-center-rdimm-ddr4-tester-footprints:C_0402_1005Metric" (layer "B.Cu")
    (at 134.875 105.675)
    (descr "Capacitor SMD 0402")
    (tags "capacitor SMD 0402")
    (property "Author" "Antmicro")
    (property "Dielectric" "X5R")
    (property "License" "Apache-2.0")
    (property "MPN" "GRM155R61H104KE14D")
    (property "Manufacturer" "Murata")
    (property "Sheetfile" "supply.kicad_sch")
    (property "Sheetname" "Supply")
    (property "Val" "100n")
    (property "Voltage" "50V")
    (property "ki_description" " ")
    (attr smd)
    (fp_text reference "C232" (at 3.645 0.375 180) (layer "B.SilkS")
        (effects (font (size 0.7 0.7) (thickness 0.15)) (justify left bottom mirror))
    )
    (fp_text value "C_100n_0402" (at 0 -1.4 180) (layer "B.Fab") hide
        (effects (font (size 0.7 0.7) (thickness 0.15)) (justify left bottom mirror))
    )
    (fp_text user "Author: Antmicro" (at -0.932 -4.17 180) (layer "B.Fab") hide
        (effects (font (size 0.7 0.7) (thickness 0.15)) (justify left bottom mirror))
    )
    (fp_text user "${REFERENCE}" (at -0.932 -3.168 180) (layer "B.Fab") hide
        (effects (font (size 0.7 0.7) (thickness 0.15)) (justify left bottom mirror))
    )
    (fp_text user "License: Apache-2.0" (at -0.932 -5.17 180) (layer "B.Fab") hide
        (effects (font (size 0.7 0.7) (thickness 0.15)) (justify left bottom mirror))
    )
    (fp_rect (start -0.94 0.47) (end 0.94 -0.47)
      (stroke (width 0.05) (type solid)) (fill none) (layer "B.CrtYd"))
    (fp_rect (start -0.499 0.249) (end 0.499 -0.249)
      (stroke (width 0.15) (type solid)) (fill none) (layer "B.Fab"))
    (pad "1" smd roundrect (at -0.484 0) (size 0.59 0.64) (layers "B.Cu" "B.Paste" "B.Mask") (roundrect_rratio 0.25)
      (net 307 "5V0_SYS") (pintype "passive"))
    (pad "2" smd roundrect (at 0.484 0) (size 0.59 0.64) (layers "B.Cu" "B.Paste" "B.Mask") (roundrect_rratio 0.25)
      (net 9 "GND") (pintype "passive"))
  )

  (footprint "data-center-rdimm-ddr4-tester-footprints:R_0402_1005Metric" (layer "B.Cu")
    (at 179.51 124.8 180)
    (descr "Resistor SMD 0402")
    (tags "resistor SMD 0402")
    (property "Author" "Antmicro")
    (property "License" "Apache-2.0")
    (property "MPN" "CR0402-FX-2492GLF")
    (property "Manufacturer" "Bourns")
    (property "Sheetfile" "ethernet.kicad_sch")
    (property "Sheetname" "Ethernet")
    (property "Tolerance" "1%")
    (property "Val" "24k9")
    (property "ki_description" "24k9 resistor in 0402 package with 1% tolerance")
    (attr smd)
    (fp_text reference "R175" (at -8.74 4.01) (layer "B.SilkS")
        (effects (font (size 0.7 0.7) (thickness 0.15)) (justify left bottom mirror))
    )
    (fp_text value "R_24k9_0402" (at 0 -1.4) (layer "B.Fab") hide
        (effects (font (size 0.7 0.7) (thickness 0.15)) (justify left bottom mirror))
    )
    (fp_text user "License: Apache-2.0" (at -0.95 -5.169) (layer "B.Fab") hide
        (effects (font (size 0.7 0.7) (thickness 0.15)) (justify left bottom mirror))
    )
    (fp_text user "${REFERENCE}" (at -0.95 -3.168) (layer "B.Fab") hide
        (effects (font (size 0.7 0.7) (thickness 0.15)) (justify left bottom mirror))
    )
    (fp_text user "Author: Antmicro" (at -0.95 -4.169) (layer "B.Fab") hide
        (effects (font (size 0.7 0.7) (thickness 0.15)) (justify left bottom mirror))
    )
    (fp_rect (start -0.93 0.47) (end 0.93 -0.47)
      (stroke (width 0.05) (type solid)) (fill none) (layer "B.CrtYd"))
    (fp_rect (start -0.5 0.25) (end 0.5 -0.25)
      (stroke (width 0.15) (type solid)) (fill none) (layer "B.Fab"))
    (pad "1" smd roundrect (at -0.485 0 180) (size 0.59 0.64) (layers "B.Cu" "B.Paste" "B.Mask") (roundrect_rratio 0.25)
      (net 610 "/Ethernet/DEN") (pintype "passive"))
    (pad "2" smd roundrect (at 0.485 0 180) (size 0.59 0.64) (layers "B.Cu" "B.Paste" "B.Mask") (roundrect_rratio 0.25)
      (net 360 "/Ethernet/VDD") (pintype "passive"))
  )

  (footprint "data-center-rdimm-ddr4-tester-footprints:R_0402_1005Metric" (layer "B.Cu")
    (at 176.25 128.105 180)
    (descr "Resistor SMD 0402")
    (tags "resistor SMD 0402")
    (property "Author" "Antmicro")
    (property "DNP" "DNP")
    (property "License" "Apache-2.0")
    (property "MPN" "CR0402-FX-1002GLF")
    (property "Manufacturer" "Bourns")
    (property "Sheetfile" "ethernet.kicad_sch")
    (property "Sheetname" "Ethernet")
    (property "Tolerance" "1%")
    (property "Val" "10k")
    (property "dnp" "")
    (property "exclude_from_bom" "")
    (property "ki_description" "10k resistor in 0402 package with 1% tolerance")
    (attr exclude_from_pos_files exclude_from_bom)
    (fp_text reference "R177" (at 0.73 -0.445) (layer "B.SilkS")
        (effects (font (size 0.7 0.7) (thickness 0.15)) (justify left bottom mirror))
    )
    (fp_text value "R_10k_0402" (at 0 -1.4) (layer "B.Fab") hide
        (effects (font (size 0.7 0.7) (thickness 0.15)) (justify left bottom mirror))
    )
    (fp_text user "Author: Antmicro" (at -0.95 -4.169) (layer "B.Fab") hide
        (effects (font (size 0.7 0.7) (thickness 0.15)) (justify left bottom mirror))
    )
    (fp_text user "License: Apache-2.0" (at -0.95 -5.169) (layer "B.Fab") hide
        (effects (font (size 0.7 0.7) (thickness 0.15)) (justify left bottom mirror))
    )
    (fp_text user "${REFERENCE}" (at -0.95 -3.168) (layer "B.Fab") hide
        (effects (font (size 0.7 0.7) (thickness 0.15)) (justify left bottom mirror))
    )
    (fp_rect (start -0.93 0.47) (end 0.93 -0.47)
      (stroke (width 0.05) (type solid)) (fill none) (layer "B.CrtYd"))
    (fp_rect (start -0.5 0.25) (end 0.5 -0.25)
      (stroke (width 0.15) (type solid)) (fill none) (layer "B.Fab"))
    (pad "1" smd roundrect (at -0.485 0 180) (size 0.59 0.64) (layers "B.Cu" "B.Paste" "B.Mask") (roundrect_rratio 0.25)
      (net 619 "/Ethernet/TPH") (pintype "passive"))
    (pad "2" smd roundrect (at 0.485 0 180) (size 0.59 0.64) (layers "B.Cu" "B.Paste" "B.Mask") (roundrect_rratio 0.25)
      (net 360 "/Ethernet/VDD") (pintype "passive"))
  )

  (footprint "data-center-rdimm-ddr4-tester-footprints:C_0201" (layer "B.Cu")
    (at 196.2 96.55)
    (descr "Capacitor SMD 0201")
    (tags "capacitor SMD 0201")
    (property "Author" "Antmicro")
    (property "Dielectric" "")
    (property "License" "Apache-2.0")
    (property "MPN" "CC0201KRX6S5BB104")
    (property "Manufacturer" "Yaego")
    (property "Sheetfile" "fpga-power.kicad_sch")
    (property "Sheetname" "FPGA power")
    (property "Val" "100n")
    (property "Voltage" "")
    (property "ki_description" " ")
    (attr smd)
    (fp_text reference "C250" (at 3.5 0.38 180) (layer "B.SilkS")
        (effects (font (size 0.7 0.7) (thickness 0.15)) (justify left bottom mirror))
    )
    (fp_text value "C_100n_0201" (at 0 -1.4 180) (layer "B.Fab") hide
        (effects (font (size 0.7 0.7) (thickness 0.15)) (justify left bottom mirror))
    )
    (fp_text user "Author: Antmicro" (at -0.72 -5.4 180) (layer "B.Fab") hide
        (effects (font (size 0.7 0.7) (thickness 0.15)) (justify left bottom mirror))
    )
    (fp_text user "License: Apache-2.0" (at -0.72 -4.4 180) (layer "B.Fab") hide
        (effects (font (size 0.7 0.7) (thickness 0.15)) (justify left bottom mirror))
    )
    (fp_text user "${REFERENCE}" (at -0.72 -3.4 180) (layer "B.Fab") hide
        (effects (font (size 0.7 0.7) (thickness 0.15)) (justify left bottom mirror))
    )
    (fp_rect (start -0.72 0.38) (end 0.72 -0.38)
      (stroke (width 0.05) (type solid)) (fill none) (layer "B.CrtYd"))
    (fp_rect (start 0.3 -0.15) (end -0.301 0.149)
      (stroke (width 0.15) (type solid)) (fill none) (layer "B.Fab"))
    (pad "" smd roundrect (at -0.349 0.002) (size 0.318 0.36) (layers "B.Paste") (roundrect_rratio 0.25))
    (pad "" smd roundrect (at 0.341 0.002) (size 0.318 0.36) (layers "B.Paste") (roundrect_rratio 0.25))
    (pad "1" smd roundrect (at -0.321 0.002) (size 0.46 0.4) (layers "B.Cu" "B.Mask") (roundrect_rratio 0.25)
      (net 306 "1V2_SYS") (pintype "passive"))
    (pad "2" smd roundrect (at 0.32 0.002) (size 0.46 0.4) (layers "B.Cu" "B.Mask") (roundrect_rratio 0.25)
      (net 9 "GND") (pintype "passive"))
  )

  (footprint "data-center-rdimm-ddr4-tester-footprints:C_0402_1005Metric" (layer "B.Cu")
    (at 165.9 108.75 -90)
    (descr "Capacitor SMD 0402")
    (tags "capacitor SMD 0402")
    (property "Author" "Antmicro")
    (property "DNP" "DNP")
    (property "Dielectric" "X5R")
    (property "License" "Apache-2.0")
    (property "MPN" "GRM155R61H104KE14D")
    (property "Manufacturer" "Murata")
    (property "Sheetfile" "ethernet.kicad_sch")
    (property "Sheetname" "Ethernet")
    (property "Val" "100n")
    (property "Voltage" "50V")
    (property "dnp" "")
    (property "exclude_from_bom" "")
    (property "ki_description" " ")
    (attr exclude_from_pos_files exclude_from_bom)
    (fp_text reference "C292" (at -1.38 -1.42 90) (layer "B.SilkS")
        (effects (font (size 0.7 0.7) (thickness 0.15)) (justify left bottom mirror))
    )
    (fp_text value "C_100n_0402" (at 0 -1.4 90) (layer "B.Fab") hide
        (effects (font (size 0.7 0.7) (thickness 0.15)) (justify left bottom mirror))
    )
    (fp_text user "${REFERENCE}" (at -0.932 -3.168 90) (layer "B.Fab") hide
        (effects (font (size 0.7 0.7) (thickness 0.15)) (justify left bottom mirror))
    )
    (fp_text user "Author: Antmicro" (at -0.932 -4.17 90) (layer "B.Fab") hide
        (effects (font (size 0.7 0.7) (thickness 0.15)) (justify left bottom mirror))
    )
    (fp_text user "License: Apache-2.0" (at -0.932 -5.17 90) (layer "B.Fab") hide
        (effects (font (size 0.7 0.7) (thickness 0.15)) (justify left bottom mirror))
    )
    (fp_rect (start -0.94 0.47) (end 0.94 -0.47)
      (stroke (width 0.05) (type solid)) (fill none) (layer "B.CrtYd"))
    (fp_rect (start -0.499 0.249) (end 0.499 -0.249)
      (stroke (width 0.15) (type solid)) (fill none) (layer "B.Fab"))
    (pad "1" smd roundrect (at -0.484 0 270) (size 0.59 0.64) (layers "B.Cu" "B.Paste" "B.Mask") (roundrect_rratio 0.25)
      (net 143 "3V3_SYS") (pintype "passive"))
    (pad "2" smd roundrect (at 0.484 0 270) (size 0.59 0.64) (layers "B.Cu" "B.Paste" "B.Mask") (roundrect_rratio 0.25)
      (net 9 "GND") (pintype "passive"))
  )

  (footprint "data-center-rdimm-ddr4-tester-footprints:R_0402_1005Metric" (layer "B.Cu")
    (at 180.075 133.1 180)
    (descr "Resistor SMD 0402")
    (tags "resistor SMD 0402")
    (property "Author" "Antmicro")
    (property "Current" "1A")
    (property "License" "Apache-2.0")
    (property "MPN" "ERJ2GE0R00X")
    (property "Manufacturer" "Panasonic")
    (property "Sheetfile" "ethernet.kicad_sch")
    (property "Sheetname" "Ethernet")
    (property "Tolerance" "")
    (property "Val" "0R")
    (property "ki_description" "0R resistor in 0402 package with unspecified tolerance")
    (attr smd)
    (fp_text reference "R178" (at -1.385 0.48) (layer "B.SilkS")
        (effects (font (size 0.7 0.7) (thickness 0.15)) (justify left bottom mirror))
    )
    (fp_text value "R_0R_0402" (at 0 -1.4) (layer "B.Fab") hide
        (effects (font (size 0.7 0.7) (thickness 0.15)) (justify left bottom mirror))
    )
    (fp_text user "${REFERENCE}" (at -0.95 -3.168) (layer "B.Fab") hide
        (effects (font (size 0.7 0.7) (thickness 0.15)) (justify left bottom mirror))
    )
    (fp_text user "License: Apache-2.0" (at -0.95 -5.169) (layer "B.Fab") hide
        (effects (font (size 0.7 0.7) (thickness 0.15)) (justify left bottom mirror))
    )
    (fp_text user "Author: Antmicro" (at -0.95 -4.169) (layer "B.Fab") hide
        (effects (font (size 0.7 0.7) (thickness 0.15)) (justify left bottom mirror))
    )
    (fp_rect (start -0.93 0.47) (end 0.93 -0.47)
      (stroke (width 0.05) (type solid)) (fill none) (layer "B.CrtYd"))
    (fp_rect (start -0.5 0.25) (end 0.5 -0.25)
      (stroke (width 0.15) (type solid)) (fill none) (layer "B.Fab"))
    (pad "1" smd roundrect (at -0.485 0 180) (size 0.59 0.64) (layers "B.Cu" "B.Paste" "B.Mask") (roundrect_rratio 0.25)
      (net 620 "/Ethernet/PG") (pintype "passive"))
    (pad "2" smd roundrect (at 0.485 0 180) (size 0.59 0.64) (layers "B.Cu" "B.Paste" "B.Mask") (roundrect_rratio 0.25)
      (net 615 "/Ethernet/POE_ACTIVE") (pintype "passive"))
  )

  (footprint "data-center-rdimm-ddr4-tester-footprints:C_0201" (layer "B.Cu")
    (at 173.15 86.65 180)
    (descr "Capacitor SMD 0201")
    (tags "capacitor SMD 0201")
    (property "Author" "Antmicro")
    (property "Dielectric" "")
    (property "License" "Apache-2.0")
    (property "MPN" "CC0201KRX6S5BB104")
    (property "Manufacturer" "Yaego")
    (property "Sheetfile" "fpga-power.kicad_sch")
    (property "Sheetname" "FPGA power")
    (property "Val" "100n")
    (property "Voltage" "")
    (property "ki_description" " ")
    (attr smd)
    (fp_text reference "C94" (at -1.05 -1.11) (layer "B.SilkS")
        (effects (font (size 0.7 0.7) (thickness 0.15)) (justify left bottom mirror))
    )
    (fp_text value "C_100n_0201" (at 0 -1.4) (layer "B.Fab") hide
        (effects (font (size 0.7 0.7) (thickness 0.15)) (justify left bottom mirror))
    )
    (fp_text user "License: Apache-2.0" (at -0.72 -4.4) (layer "B.Fab") hide
        (effects (font (size 0.7 0.7) (thickness 0.15)) (justify left bottom mirror))
    )
    (fp_text user "${REFERENCE}" (at -0.72 -3.4) (layer "B.Fab") hide
        (effects (font (size 0.7 0.7) (thickness 0.15)) (justify left bottom mirror))
    )
    (fp_text user "Author: Antmicro" (at -0.72 -5.4) (layer "B.Fab") hide
        (effects (font (size 0.7 0.7) (thickness 0.15)) (justify left bottom mirror))
    )
    (fp_rect (start -0.72 0.38) (end 0.72 -0.38)
      (stroke (width 0.05) (type solid)) (fill none) (layer "B.CrtYd"))
    (fp_rect (start 0.3 -0.15) (end -0.301 0.149)
      (stroke (width 0.15) (type solid)) (fill none) (layer "B.Fab"))
    (pad "" smd roundrect (at -0.349 0.002 180) (size 0.318 0.36) (layers "B.Paste") (roundrect_rratio 0.25))
    (pad "" smd roundrect (at 0.341 0.002 180) (size 0.318 0.36) (layers "B.Paste") (roundrect_rratio 0.25))
    (pad "1" smd roundrect (at -0.321 0.002 180) (size 0.46 0.4) (layers "B.Cu" "B.Mask") (roundrect_rratio 0.25)
      (net 143 "3V3_SYS") (pintype "passive"))
    (pad "2" smd roundrect (at 0.32 0.002 180) (size 0.46 0.4) (layers "B.Cu" "B.Mask") (roundrect_rratio 0.25)
      (net 9 "GND") (pintype "passive"))
  )

  (footprint "data-center-rdimm-ddr4-tester-footprints:C_0402_1005Metric" (layer "B.Cu")
    (at 193.1 90.83 90)
    (descr "Capacitor SMD 0402")
    (tags "capacitor SMD 0402")
    (property "Author" "Antmicro")
    (property "Dielectric" "")
    (property "License" "Apache-2.0")
    (property "MPN" "GRM155R61A475MEAAD")
    (property "Manufacturer" "Murata")
    (property "Sheetfile" "fpga-power.kicad_sch")
    (property "Sheetname" "FPGA power")
    (property "Val" "4u7")
    (property "Voltage" "")
    (property "ki_description" " ")
    (attr smd)
    (fp_text reference "C239" (at 1.72 2.79 90) (layer "B.SilkS")
        (effects (font (size 0.7 0.7) (thickness 0.15)) (justify left bottom mirror))
    )
    (fp_text value "C_4u7_0402" (at 0 -1.4 270) (layer "B.Fab") hide
        (effects (font (size 0.7 0.7) (thickness 0.15)) (justify left bottom mirror))
    )
    (fp_text user "${REFERENCE}" (at -0.932 -3.168 270) (layer "B.Fab") hide
        (effects (font (size 0.7 0.7) (thickness 0.15)) (justify left bottom mirror))
    )
    (fp_text user "License: Apache-2.0" (at -0.932 -5.17 270) (layer "B.Fab") hide
        (effects (font (size 0.7 0.7) (thickness 0.15)) (justify left bottom mirror))
    )
    (fp_text user "Author: Antmicro" (at -0.932 -4.17 270) (layer "B.Fab") hide
        (effects (font (size 0.7 0.7) (thickness 0.15)) (justify left bottom mirror))
    )
    (fp_rect (start -0.94 0.47) (end 0.94 -0.47)
      (stroke (width 0.05) (type solid)) (fill none) (layer "B.CrtYd"))
    (fp_rect (start -0.499 0.249) (end 0.499 -0.249)
      (stroke (width 0.15) (type solid)) (fill none) (layer "B.Fab"))
    (pad "1" smd roundrect (at -0.484 0 90) (size 0.59 0.64) (layers "B.Cu" "B.Paste" "B.Mask") (roundrect_rratio 0.25)
      (net 144 "1V8_SYS") (pintype "passive"))
    (pad "2" smd roundrect (at 0.484 0 90) (size 0.59 0.64) (layers "B.Cu" "B.Paste" "B.Mask") (roundrect_rratio 0.25)
      (net 9 "GND") (pintype "passive"))
  )

  (footprint "data-center-rdimm-ddr4-tester-footprints:C_0201" (layer "B.Cu")
    (at 176.075 90.45)
    (descr "Capacitor SMD 0201")
    (tags "capacitor SMD 0201")
    (property "Author" "Antmicro")
    (property "Dielectric" "")
    (property "License" "Apache-2.0")
    (property "MPN" "CC0201KRX6S5BB104")
    (property "Manufacturer" "Yaego")
    (property "Sheetfile" "fpga-power.kicad_sch")
    (property "Sheetname" "FPGA power")
    (property "Val" "100n")
    (property "Voltage" "")
    (property "ki_description" " ")
    (attr smd)
    (fp_text reference "C277" (at 1.345 -0.35 180) (layer "B.SilkS")
        (effects (font (size 0.7 0.7) (thickness 0.15)) (justify left bottom mirror))
    )
    (fp_text value "C_100n_0201" (at 0 -1.4 180) (layer "B.Fab") hide
        (effects (font (size 0.7 0.7) (thickness 0.15)) (justify left bottom mirror))
    )
    (fp_text user "Author: Antmicro" (at -0.72 -5.4 180) (layer "B.Fab") hide
        (effects (font (size 0.7 0.7) (thickness 0.15)) (justify left bottom mirror))
    )
    (fp_text user "${REFERENCE}" (at -0.72 -3.4 180) (layer "B.Fab") hide
        (effects (font (size 0.7 0.7) (thickness 0.15)) (justify left bottom mirror))
    )
    (fp_text user "License: Apache-2.0" (at -0.72 -4.4 180) (layer "B.Fab") hide
        (effects (font (size 0.7 0.7) (thickness 0.15)) (justify left bottom mirror))
    )
    (fp_rect (start -0.72 0.38) (end 0.72 -0.38)
      (stroke (width 0.05) (type solid)) (fill none) (layer "B.CrtYd"))
    (fp_rect (start 0.3 -0.15) (end -0.301 0.149)
      (stroke (width 0.15) (type solid)) (fill none) (layer "B.Fab"))
    (pad "" smd roundrect (at -0.349 0.002) (size 0.318 0.36) (layers "B.Paste") (roundrect_rratio 0.25))
    (pad "" smd roundrect (at 0.341 0.002) (size 0.318 0.36) (layers "B.Paste") (roundrect_rratio 0.25))
    (pad "1" smd roundrect (at -0.321 0.002) (size 0.46 0.4) (layers "B.Cu" "B.Mask") (roundrect_rratio 0.25)
      (net 77 "VDDQ") (pintype "passive"))
    (pad "2" smd roundrect (at 0.32 0.002) (size 0.46 0.4) (layers "B.Cu" "B.Mask") (roundrect_rratio 0.25)
      (net 9 "GND") (pintype "passive"))
  )

  (footprint "data-center-rdimm-ddr4-tester-footprints:R_0402_1005Metric" (layer "B.Cu")
    (at 176.25 130.125)
    (descr "Resistor SMD 0402")
    (tags "resistor SMD 0402")
    (property "Author" "Antmicro")
    (property "Current" "1A")
    (property "DNP" "DNP")
    (property "License" "Apache-2.0")
    (property "MPN" "ERJ2GE0R00X")
    (property "Manufacturer" "Panasonic")
    (property "Sheetfile" "ethernet.kicad_sch")
    (property "Sheetname" "Ethernet")
    (property "Tolerance" "")
    (property "Val" "0R")
    (property "dnp" "")
    (property "exclude_from_bom" "")
    (property "ki_description" "0R resistor in 0402 package with unspecified tolerance")
    (attr exclude_from_pos_files exclude_from_bom)
    (fp_text reference "R179" (at -0.71 0.355 180) (layer "B.SilkS")
        (effects (font (size 0.7 0.7) (thickness 0.15)) (justify left bottom mirror))
    )
    (fp_text value "R_0R_0402" (at 0 -1.4 180) (layer "B.Fab") hide
        (effects (font (size 0.7 0.7) (thickness 0.15)) (justify left bottom mirror))
    )
    (fp_text user "${REFERENCE}" (at -0.95 -3.168 180) (layer "B.Fab") hide
        (effects (font (size 0.7 0.7) (thickness 0.15)) (justify left bottom mirror))
    )
    (fp_text user "License: Apache-2.0" (at -0.95 -5.169 180) (layer "B.Fab") hide
        (effects (font (size 0.7 0.7) (thickness 0.15)) (justify left bottom mirror))
    )
    (fp_text user "Author: Antmicro" (at -0.95 -4.169 180) (layer "B.Fab") hide
        (effects (font (size 0.7 0.7) (thickness 0.15)) (justify left bottom mirror))
    )
    (fp_rect (start -0.93 0.47) (end 0.93 -0.47)
      (stroke (width 0.05) (type solid)) (fill none) (layer "B.CrtYd"))
    (fp_rect (start -0.5 0.25) (end 0.5 -0.25)
      (stroke (width 0.15) (type solid)) (fill none) (layer "B.Fab"))
    (pad "1" smd roundrect (at -0.485 0) (size 0.59 0.64) (layers "B.Cu" "B.Paste" "B.Mask") (roundrect_rratio 0.25)
      (net 604 "GNDD") (pintype "passive"))
    (pad "2" smd roundrect (at 0.485 0) (size 0.59 0.64) (layers "B.Cu" "B.Paste" "B.Mask") (roundrect_rratio 0.25)
      (net 621 "/Ethernet/IRSHDL_EN") (pintype "passive"))
  )

  (footprint "data-center-rdimm-ddr4-tester-footprints:C_0201" (layer "B.Cu")
    (at 192.2 90.54 90)
    (descr "Capacitor SMD 0201")
    (tags "capacitor SMD 0201")
    (property "Author" "Antmicro")
    (property "Dielectric" "")
    (property "License" "Apache-2.0")
    (property "MPN" "CC0201KRX6S5BB104")
    (property "Manufacturer" "Yaego")
    (property "Sheetfile" "fpga-power.kicad_sch")
    (property "Sheetname" "FPGA power")
    (property "Val" "100n")
    (property "Voltage" "")
    (property "ki_description" " ")
    (attr smd)
    (fp_text reference "C238" (at 1.17 -0.47 270) (layer "B.SilkS")
        (effects (font (size 0.7 0.7) (thickness 0.15)) (justify left bottom mirror))
    )
    (fp_text value "C_100n_0201" (at 0 -1.4 270) (layer "B.Fab") hide
        (effects (font (size 0.7 0.7) (thickness 0.15)) (justify left bottom mirror))
    )
    (fp_text user "Author: Antmicro" (at -0.72 -5.4 270) (layer "B.Fab") hide
        (effects (font (size 0.7 0.7) (thickness 0.15)) (justify left bottom mirror))
    )
    (fp_text user "License: Apache-2.0" (at -0.72 -4.4 270) (layer "B.Fab") hide
        (effects (font (size 0.7 0.7) (thickness 0.15)) (justify left bottom mirror))
    )
    (fp_text user "${REFERENCE}" (at -0.72 -3.4 270) (layer "B.Fab") hide
        (effects (font (size 0.7 0.7) (thickness 0.15)) (justify left bottom mirror))
    )
    (fp_rect (start -0.72 0.38) (end 0.72 -0.38)
      (stroke (width 0.05) (type solid)) (fill none) (layer "B.CrtYd"))
    (fp_rect (start 0.3 -0.15) (end -0.301 0.149)
      (stroke (width 0.15) (type solid)) (fill none) (layer "B.Fab"))
    (pad "" smd roundrect (at -0.349 0.002 90) (size 0.318 0.36) (layers "B.Paste") (roundrect_rratio 0.25))
    (pad "" smd roundrect (at 0.341 0.002 90) (size 0.318 0.36) (layers "B.Paste") (roundrect_rratio 0.25))
    (pad "1" smd roundrect (at -0.321 0.002 90) (size 0.46 0.4) (layers "B.Cu" "B.Mask") (roundrect_rratio 0.25)
      (net 144 "1V8_SYS") (pintype "passive"))
    (pad "2" smd roundrect (at 0.32 0.002 90) (size 0.46 0.4) (layers "B.Cu" "B.Mask") (roundrect_rratio 0.25)
      (net 9 "GND") (pintype "passive"))
  )

  (footprint "data-center-rdimm-ddr4-tester-footprints:R_0402_1005Metric" (layer "B.Cu")
    (at 171.9 76.2 180)
    (descr "Resistor SMD 0402")
    (tags "resistor SMD 0402")
    (property "Author" "Antmicro")
    (property "License" "Apache-2.0")
    (property "MPN" "CR0402-FX-1003GLF")
    (property "Manufacturer" "Bourns")
    (property "Sheetfile" "DDR4.kicad_sch")
    (property "Sheetname" "DDR4")
    (property "Tolerance" "1%")
    (property "Val" "100k")
    (property "ki_description" "100k resistor in 0402 package with 1% tolerance")
    (attr smd)
    (fp_text reference "R186" (at -1.45 0.55) (layer "B.SilkS")
        (effects (font (size 0.7 0.7) (thickness 0.15)) (justify left bottom mirror))
    )
    (fp_text value "R_100k_0402" (at 0 -1.4) (layer "B.Fab") hide
        (effects (font (size 0.7 0.7) (thickness 0.15)) (justify left bottom mirror))
    )
    (fp_text user "License: Apache-2.0" (at -0.95 -5.169) (layer "B.Fab") hide
        (effects (font (size 0.7 0.7) (thickness 0.15)) (justify left bottom mirror))
    )
    (fp_text user "${REFERENCE}" (at -0.95 -3.168) (layer "B.Fab") hide
        (effects (font (size 0.7 0.7) (thickness 0.15)) (justify left bottom mirror))
    )
    (fp_text user "Author: Antmicro" (at -0.95 -4.169) (layer "B.Fab") hide
        (effects (font (size 0.7 0.7) (thickness 0.15)) (justify left bottom mirror))
    )
    (fp_rect (start -0.93 0.47) (end 0.93 -0.47)
      (stroke (width 0.05) (type solid)) (fill none) (layer "B.CrtYd"))
    (fp_rect (start -0.5 0.25) (end 0.5 -0.25)
      (stroke (width 0.15) (type solid)) (fill none) (layer "B.Fab"))
    (pad "1" smd roundrect (at -0.485 0 180) (size 0.59 0.64) (layers "B.Cu" "B.Paste" "B.Mask") (roundrect_rratio 0.25)
      (net 789 "DDR_PRESENCE") (pintype "passive"))
    (pad "2" smd roundrect (at 0.485 0 180) (size 0.59 0.64) (layers "B.Cu" "B.Paste" "B.Mask") (roundrect_rratio 0.25)
      (net 143 "3V3_SYS") (pintype "passive"))
  )

  (footprint "data-center-rdimm-ddr4-tester-footprints:C_0201" (layer "B.Cu")
    (at 172.2 88.65)
    (descr "Capacitor SMD 0201")
    (tags "capacitor SMD 0201")
    (property "Author" "Antmicro")
    (property "Dielectric" "")
    (property "License" "Apache-2.0")
    (property "MPN" "CC0201KRX6S5BB104")
    (property "Manufacturer" "Yaego")
    (property "Sheetfile" "fpga-power.kicad_sch")
    (property "Sheetname" "FPGA power")
    (property "Val" "100n")
    (property "Voltage" "")
    (property "ki_description" " ")
    (attr smd)
    (fp_text reference "C276" (at 1.37 1.08 180) (layer "B.SilkS")
        (effects (font (size 0.7 0.7) (thickness 0.15)) (justify left bottom mirror))
    )
    (fp_text value "C_100n_0201" (at 0 -1.4 180) (layer "B.Fab") hide
        (effects (font (size 0.7 0.7) (thickness 0.15)) (justify left bottom mirror))
    )
    (fp_text user "License: Apache-2.0" (at -0.72 -4.4 180) (layer "B.Fab") hide
        (effects (font (size 0.7 0.7) (thickness 0.15)) (justify left bottom mirror))
    )
    (fp_text user "Author: Antmicro" (at -0.72 -5.4 180) (layer "B.Fab") hide
        (effects (font (size 0.7 0.7) (thickness 0.15)) (justify left bottom mirror))
    )
    (fp_text user "${REFERENCE}" (at -0.72 -3.4 180) (layer "B.Fab") hide
        (effects (font (size 0.7 0.7) (thickness 0.15)) (justify left bottom mirror))
    )
    (fp_rect (start -0.72 0.38) (end 0.72 -0.38)
      (stroke (width 0.05) (type solid)) (fill none) (layer "B.CrtYd"))
    (fp_rect (start 0.3 -0.15) (end -0.301 0.149)
      (stroke (width 0.15) (type solid)) (fill none) (layer "B.Fab"))
    (pad "" smd roundrect (at -0.349 0.002) (size 0.318 0.36) (layers "B.Paste") (roundrect_rratio 0.25))
    (pad "" smd roundrect (at 0.341 0.002) (size 0.318 0.36) (layers "B.Paste") (roundrect_rratio 0.25))
    (pad "1" smd roundrect (at -0.321 0.002) (size 0.46 0.4) (layers "B.Cu" "B.Mask") (roundrect_rratio 0.25)
      (net 77 "VDDQ") (pintype "passive"))
    (pad "2" smd roundrect (at 0.32 0.002) (size 0.46 0.4) (layers "B.Cu" "B.Mask") (roundrect_rratio 0.25)
      (net 9 "GND") (pintype "passive"))
  )
  (gr_line (start 259.886328 46) (end 259.886328 74.820008)
    (stroke (width 0.12) (type solid)) (layer "Edge.Cuts"))
  (gr_line (start 259.886328 74.820008) (end 259.886328 136)
    (stroke (width 0.12) (type solid)) (layer "Edge.Cuts"))
  (gr_line (start 107 46) (end 259.886328 46)
    (stroke (width 0.12) (type solid)) (layer "Edge.Cuts"))
  (gr_line (start 107 136) (end 107 46)
    (stroke (width 0.12) (type solid)) (layer "Edge.Cuts"))
  (gr_line (start 259.886328 136) (end 107 136)
    (stroke (width 0.12) (type solid)) (layer "Edge.Cuts"))

  (segment (start 119.604 98.69) (end 119.604 96.827336) (width 0.15) (layer "F.Cu") (net 1))
  (segment (start 120.476328 93.247157) (end 120.476328 95.665008) (width 0.1) (layer "F.Cu") (net 1))
  (segment (start 119.604 96.827336) (end 120.621328 95.810008) (width 0.15) (layer "F.Cu") (net 1))
  (segment (start 140.225857 96.475) (end 140.225857 98.224143) (width 0.2) (layer "F.Cu") (net 4))
  (segment (start 149.671328 95.874306) (end 149.671328 97.209306) (width 0.15) (layer "F.Cu") (net 5))
  (segment (start 151.586328 96.989306) (end 150.351328 96.989306) (width 0.15) (layer "F.Cu") (net 5))
  (segment (start 155.009179 97.297157) (end 152.523477 97.297157) (width 0.15) (layer "F.Cu") (net 5))
  (segment (start 152.523477 97.297157) (end 152.215626 96.989306) (width 0.15) (layer "F.Cu") (net 5))
  (segment (start 152.215626 96.989306) (end 151.586328 96.989306) (width 0.15) (layer "F.Cu") (net 5))
  (segment (start 147.486328 99.124306) (end 147.486328 100.659306) (width 0.15) (layer "F.Cu") (net 6))
  (segment (start 151.586328 97.959306) (end 150.901328 97.959306) (width 0.15) (layer "F.Cu") (net 6))
  (segment (start 150.901328 97.959306) (end 150.586328 98.274306) (width 0.15) (layer "F.Cu") (net 6))
  (segment (start 148.336328 98.274306) (end 150.586328 98.274306) (width 0.15) (layer "F.Cu") (net 6))
  (segment (start 148.336328 98.274306) (end 147.486328 99.124306) (width 0.15) (layer "F.Cu") (net 6))
  (segment (start 152.28703 97.959306) (end 152.449179 97.797157) (width 0.15) (layer "F.Cu") (net 6))
  (segment (start 152.449179 97.797157) (end 155.009179 97.797157) (width 0.15) (layer "F.Cu") (net 6))
  (segment (start 151.586328 97.959306) (end 152.28703 97.959306) (width 0.15) (layer "F.Cu") (net 6))
  (segment (start 151.799328 115.202008) (end 151.549328 115.452008) (width 0.2) (layer "F.Cu") (net 7))
  (segment (start 151.799328 114.837008) (end 151.799328 115.202008) (width 0.2) (layer "F.Cu") (net 7))
  (segment (start 152.084328 114.552008) (end 151.799328 114.837008) (width 0.2) (layer "F.Cu") (net 7))
  (segment (start 133.451328 104.812157) (end 132.741328 104.812157) (width 0.15) (layer "F.Cu") (net 9))
  (segment (start 163.486328 99.659306) (end 163.486328 100.220008) (width 0.2) (layer "F.Cu") (net 9))
  (segment (start 163.486328 96.289306) (end 164.586328 96.289306) (width 0.2) (layer "F.Cu") (net 9))
  (segment (start 149.386328 93.889306) (end 150.486328 93.889306) (width 0.2) (layer "F.Cu") (net 9))
  (segment (start 151.586328 93.889306) (end 150.486328 93.889306) (width 0.2) (layer "F.Cu") (net 9))
  (segment (start 148.701328 95.874306) (end 147.836328 95.874306) (width 0.2) (layer "F.Cu") (net 9))
  (segment (start 147.836328 95.874306) (end 147.486328 96.224306) (width 0.2) (layer "F.Cu") (net 9))
  (segment (start 147.486328 97.324306) (end 147.486328 96.224306) (width 0.2) (layer "F.Cu") (net 9))
  (segment (start 148.471328 101.305008) (end 148.486328 101.320008) (width 0.2) (layer "F.Cu") (net 9))
  (segment (start 148.471328 100.674306) (end 148.471328 101.305008) (width 0.2) (layer "F.Cu") (net 9))
  (segment (start 149.786328 99.124306) (end 149.786328 100.320008) (width 0.2) (layer "F.Cu") (net 9))
  (segment (start 151.586328 99.959306) (end 151.586328 100.620008) (width 0.2) (layer "F.Cu") (net 9))
  (segment (start 213.6485 117.648485) (end 213.649828 117.647157) (width 0.2) (layer "F.Cu") (net 9))
  (segment (start 213.6485 118.68) (end 213.6485 117.648485) (width 0.2) (layer "F.Cu") (net 9))
  (segment (start 212.1485 117.618485) (end 212.159828 117.607157) (width 0.2) (layer "F.Cu") (net 9))
  (segment (start 212.1485 118.68) (end 212.1485 117.618485) (width 0.2) (layer "F.Cu") (net 9))
  (segment (start 210.6485 117.568485) (end 210.649828 117.567157) (width 0.2) (layer "F.Cu") (net 9))
  (segment (start 210.6485 118.68) (end 210.6485 117.568485) (width 0.2) (layer "F.Cu") (net 9))
  (segment (start 209.1485 117.578485) (end 209.159828 117.567157) (width 0.2) (layer "F.Cu") (net 9))
  (segment (start 209.1485 118.68) (end 209.1485 117.578485) (width 0.2) (layer "F.Cu") (net 9))
  (segment (start 213.6785 124.88) (end 213.689828 124.891328) (width 0.2) (layer "F.Cu") (net 9))
  (segment (start 213.6785 124.88) (end 213.6785 126.675829) (width 0.2) (layer "F.Cu") (net 9))
  (segment (start 212.1785 124.89) (end 212.179828 124.891328) (width 0.2) (layer "F.Cu") (net 9))
  (segment (start 212.1785 124.88) (end 212.1785 126.685829) (width 0.2) (layer "F.Cu") (net 9))
  (segment (start 210.6785 124.89) (end 210.679828 124.891328) (width 0.2) (layer "F.Cu") (net 9))
  (segment (start 210.6785 124.88) (end 210.6785 126.685829) (width 0.2) (layer "F.Cu") (net 9))
  (segment (start 209.1785 124.882656) (end 209.169828 124.891328) (width 0.2) (layer "F.Cu") (net 9))
  (segment (start 209.1785 124.88) (end 209.1785 126.678485) (width 0.2) (layer "F.Cu") (net 9))
  (segment (start 206.1785 124.9) (end 206.199828 124.921328) (width 0.2) (layer "F.Cu") (net 9))
  (segment (start 206.1785 124.88) (end 206.1785 126.695829) (width 0.2) (layer "F.Cu") (net 9))
  (segment (start 171.136328 102.560008) (end 170.636328 103.060008) (width 0.2) (layer "F.Cu") (net 9))
  (segment (start 185.136328 94.560008) (end 185.636328 95.060008) (width 0.2) (layer "F.Cu") (net 9))
  (segment (start 184.136328 101.560008) (end 183.636328 101.060008) (width 0.2) (layer "F.Cu") (net 9))
  (segment (start 193.136328 91.560008) (end 193.636328 92.060008) (width 0.2) (layer "F.Cu") (net 9))
  (segment (start 194.136328 87.560008) (end 194.636328 88.060008) (width 0.2) (layer "F.Cu") (net 9))
  (segment (start 155.466558 82.595073) (end 155.966557 82.095073) (width 0.2) (layer "F.Cu") (net 9))
  (segment (start 154.477599 80.555201) (end 154.977599 81.0552) (width 0.2) (layer "F.Cu") (net 9))
  (segment (start 181.136328 92.560008) (end 180.636328 93.060008) (width 0.2) (layer "F.Cu") (net 9))
  (segment (start 123.917728 69.355808) (end 123.917728 68.710008) (width 0.4) (layer "F.Cu") (net 9))
  (segment (start 155.549328 113.152008) (end 155.549328 112.977007) (width 0.2) (layer "F.Cu") (net 9))
  (segment (start 155.374328 113.327008) (end 155.549328 113.152008) (width 0.2) (layer "F.Cu") (net 9))
  (segment (start 155.374328 113.392008) (end 155.374328 113.327008) (width 0.2) (layer "F.Cu") (net 9))
  (segment (start 155.149328 113.617008) (end 155.374328 113.392008) (width 0.2) (layer "F.Cu") (net 9))
  (segment (start 209.7 58.35) (end 209.236328 58.813672) (width 0.2) (layer "F.Cu") (net 9))
  (segment (start 183.136328 88.560008) (end 182.636328 88.060008) (width 0.2) (layer "F.Cu") (net 9))
  (segment (start 202.436328 55.060008) (end 202.436328 53.813672) (width 0.2) (layer "F.Cu") (net 9))
  (segment (start 226.236328 58.913672) (end 226.236328 59.660008) (width 0.2) (layer "F.Cu") (net 9))
  (segment (start 149.736328 56.263672) (end 149.4 56.6) (width 0.2) (layer "F.Cu") (net 9))
  (segment (start 140.161328 99.727157) (end 139.556328 99.727157) (width 0.15) (layer "F.Cu") (net 9))
  (segment (start 119.9 67.2) (end 120.1 67) (width 0.4) (layer "F.Cu") (net 9))
  (segment (start 253.03 80) (end 252.85 80.18) (width 0.4) (layer "F.Cu") (net 9))
  (segment (start 238.963 119.375) (end 239.728 119.375) (width 0.1) (layer "F.Cu") (net 9))
  (segment (start 153.585 108.54) (end 153.66 108.615) (width 0.15) (layer "F.Cu") (net 9))
  (segment (start 156.55 53.8) (end 156.55 55.046336) (width 0.2) (layer "F.Cu") (net 9))
  (segment (start 201.515 123.3) (end 201.515 122.415) (width 0.4) (layer "F.Cu") (net 9))
  (segment (start 132.736328 53.813672) (end 132.736328 55.060008) (width 0.2) (layer "F.Cu") (net 9))
  (segment (start 210.936328 59.660008) (end 211.05 59.77368) (width 0.2) (layer "F.Cu") (net 9))
  (segment (start 137.05 95.825) (end 137.5 95.375) (width 0.2) (layer "F.Cu") (net 9))
  (segment (start 238.986328 59.013672) (end 238.986328 59.660008) (width 0.2) (layer "F.Cu") (net 9))
  (segment (start 206.7 53.8) (end 206.7 55.046336) (width 0.2) (layer "F.Cu") (net 9))
  (segment (start 195.636328 95.060008) (end 195.136328 94.560008) (width 0.127) (layer "F.Cu") (net 9))
  (segment (start 187.136328 86.560008) (end 186.636328 87.060008) (width 0.2) (layer "F.Cu") (net 9))
  (segment (start 111.851328 65.160008) (end 111.179992 65.160008) (width 0.4) (layer "F.Cu") (net 9))
  (segment (start 242.261 75.451) (end 242.77 75.96) (width 0.4) (layer "F.Cu") (net 9))
  (segment (start 159.086328 55.060008) (end 159.086328 56.427648) (width 0.2) (layer "F.Cu") (net 9))
  (segment (start 207.536328 61.136328) (end 207.55 61.15) (width 0.2) (layer "F.Cu") (net 9))
  (segment (start 237.808 85.45) (end 242.725 85.45) (width 0.4) (layer "F.Cu") (net 9))
  (segment (start 138.8 98.25) (end 138.8 97.55) (width 0.2) (layer "F.Cu") (net 9))
  (segment (start 126.8 55.046336) (end 126.786328 55.060008) (width 0.2) (layer "F.Cu") (net 9))
  (segment (start 126.55 58.35) (end 126.55 58.4) (width 0.2) (layer "F.Cu") (net 9))
  (segment (start 221.136328 53.813672) (end 221.136328 55.060008) (width 0.2) (layer "F.Cu") (net 9))
  (segment (start 242.386328 55.060008) (end 242.372656 55.07368) (width 0.2) (layer "F.Cu") (net 9))
  (segment (start 140.1 58.4) (end 139.536328 58.963672) (width 0.2) (layer "F.Cu") (net 9))
  (segment (start 175.63 80.06) (end 176.63632 80.06) (width 0.2) (layer "F.Cu") (net 9))
  (segment (start 226.8 58.35) (end 226.236328 58.913672) (width 0.2) (layer "F.Cu") (net 9))
  (segment (start 154.2 127.03) (end 154.2 126.4) (width 0.4) (layer "F.Cu") (net 9))
  (segment (start 158.219179 78.577157) (end 158.236328 78.560008) (width 0.1) (layer "F.Cu") (net 9))
  (segment (start 227.1 53.8) (end 227.1 55.046336) (width 0.2) (layer "F.Cu") (net 9))
  (segment (start 147.2 53.8) (end 147.2 55.046336) (width 0.2) (layer "F.Cu") (net 9))
  (segment (start 159.1 55.046336) (end 159.086328 55.060008) (width 0.2) (layer "F.Cu") (net 9))
  (segment (start 135.286328 61.0275) (end 135.708828 61.45) (width 0.2) (layer "F.Cu") (net 9))
  (segment (start 137.801328 115.108157) (end 137.300328 115.108157) (width 0.2) (layer "F.Cu") (net 9))
  (segment (start 133.461328 107.407157) (end 132.836328 107.407157) (width 0.15) (layer "F.Cu") (net 9))
  (segment (start 211.05 59.77368) (end 211.05 61.2) (width 0.2) (layer "F.Cu") (net 9))
  (segment (start 124.85 58.35) (end 124.85 58.4) (width 0.2) (layer "F.Cu") (net 9))
  (segment (start 225.885 122.315) (end 226.15 122.05) (width 0.2) (layer "F.Cu") (net 9))
  (segment (start 211.786328 53.813672) (end 211.786328 55.060008) (width 0.2) (layer "F.Cu") (net 9))
  (segment (start 136.986328 61.036328) (end 136.986328 59.660008) (width 0.2) (layer "F.Cu") (net 9))
  (segment (start 223.686328 55.060008) (end 223.55 55.196336) (width 0.2) (layer "F.Cu") (net 9))
  (segment (start 231.64 80.43) (end 231.162 79.952) (width 0.12) (layer "F.Cu") (net 9))
  (segment (start 166.215626 92.889306) (end 166.236328 92.910008) (width 0.2) (layer "F.Cu") (net 9))
  (segment (start 174.136328 91.560008) (end 173.636328 92.060008) (width 0.2) (layer "F.Cu") (net 9))
  (segment (start 162.7 104.995) (end 162.7 105.7) (width 0.15) (layer "F.Cu") (net 9))
  (segment (start 202.55 55.17368) (end 202.55 56.45) (width 0.2) (layer "F.Cu") (net 9))
  (segment (start 212.545984 57.203492) (end 211.95 56.607508) (width 0.2) (layer "F.Cu") (net 9))
  (segment (start 141.85 58.4) (end 141.236328 59.013672) (width 0.2) (layer "F.Cu") (net 9))
  (segment (start 217.736328 53.813672) (end 217.736328 55.060008) (width 0.2) (layer "F.Cu") (net 9))
  (segment (start 196.61 90.060008) (end 196.11 90.560008) (width 0.2) (layer "F.Cu") (net 9))
  (segment (start 159.086328 56.427648) (end 158.303139 57.210837) (width 0.2) (layer "F.Cu") (net 9))
  (segment (start 244.086328 55.060008) (end 244.086328 56.55) (width 0.2) (layer "F.Cu") (net 9))
  (segment (start 143.45 58.4) (end 143.45 58.45) (width 0.2) (layer "F.Cu") (net 9))
  (segment (start 209.236328 58.813672) (end 209.236328 59.660008) (width 0.2) (layer "F.Cu") (net 9))
  (segment (start 174.6 84.05) (end 174.6 84.07368) (width 0.1) (layer "F.Cu") (net 9))
  (segment (start 137.836328 55.060008) (end 138 55.22368) (width 0.2) (layer "F.Cu") (net 9))
  (segment (start 239.1 59.77368) (end 238.986328 59.660008) (width 0.2) (layer "F.Cu") (net 9))
  (segment (start 232.8 58.4) (end 232.751334 58.4) (width 0.2) (layer "F.Cu") (net 9))
  (segment (start 207.536328 59.660008) (end 207.536328 61.136328) (width 0.2) (layer "F.Cu") (net 9))
  (segment (start 195.136328 84.560008) (end 195.636328 84.060008) (width 0.2) (layer "F.Cu") (net 9))
  (segment (start 133 116.484) (end 132.484 116.484) (width 0.2) (layer "F.Cu") (net 9))
  (segment (start 220.62 87.85) (end 220.62 88.734904) (width 0.12) (layer "F.Cu") (net 9))
  (segment (start 220.286328 58.913672) (end 220.286328 59.660008) (width 0.2) (layer "F.Cu") (net 9))
  (segment (start 149.6 58.5) (end 149.75 58.35) (width 0.2) (layer "F.Cu") (net 9))
  (segment (start 237.808 77.451) (end 242.761 77.451) (width 0.4) (layer "F.Cu") (net 9))
  (segment (start 173.136328 88.560008) (end 172.636328 88.060009) (width 0.2) (layer "F.Cu") (net 9))
  (segment (start 184.636328 84.060008) (end 184.636328 84.0405) (width 0.127) (layer "F.Cu") (net 9))
  (segment (start 178.136328 93.560008) (end 177.636328 94.060008) (width 0.2) (layer "F.Cu") (net 9))
  (segment (start 204.85 55.196336) (end 204.986328 55.060008) (width 0.2) (layer "F.Cu") (net 9))
  (segment (start 135.85 58.45) (end 135.286328 59.013672) (width 0.2) (layer "F.Cu") (net 9))
  (segment (start 205.836328 58.913215) (end 205.836328 59.660008) (width 0.2) (layer "F.Cu") (net 9))
  (segment (start 132.736328 55.060008) (end 132.736328 56.5) (width 0.2) (layer "F.Cu") (net 9))
  (segment (start 134.133485 117.9) (end 134.211328 117.822157) (width 0.2) (layer "F.Cu") (net 9))
  (segment (start 223.8 122.315) (end 223.8 121.5) (width 0.2) (layer "F.Cu") (net 9))
  (segment (start 189.136328 88.560008) (end 189.636328 88.060008) (width 0.2) (layer "F.Cu") (net 9))
  (segment (start 140.1 56.6) (end 140.25 56.45) (width 0.2) (layer "F.Cu") (net 9))
  (segment (start 196.136328 92.560008) (end 195.636328 92.060008) (width 0.2) (layer "F.Cu") (net 9))
  (segment (start 194.636328 81.060008) (end 194.655836 81.060008) (width 0.127) (layer "F.Cu") (net 9))
  (segment (start 140.386328 53.813672) (end 140.386328 55.060008) (width 0.2) (layer "F.Cu") (net 9))
  (segment (start 174.136328 101.560008) (end 173.636328 102.060008) (width 0.2) (layer "F.Cu") (net 9))
  (segment (start 191.136328 102.560008) (end 191.636328 103.060008) (width 0.2) (layer "F.Cu") (net 9))
  (segment (start 153.136328 55.060008) (end 153.136328 56.7) (width 0.2) (layer "F.Cu") (net 9))
  (segment (start 147.2 55.046336) (end 147.186328 55.060008) (width 0.2) (layer "F.Cu") (net 9))
  (segment (start 185.779682 76.510582) (end 186.136328 76.867228) (width 0.2) (layer "F.Cu") (net 9))
  (segment (start 237.85 58.35) (end 237.286328 58.913672) (width 0.2) (layer "F.Cu") (net 9))
  (segment (start 181.136328 82.560008) (end 180.636328 82.060008) (width 0.2) (layer "F.Cu") (net 9))
  (segment (start 150.6 127.015) (end 149.815 127.015) (width 0.1) (layer "F.Cu") (net 9))
  (segment (start 225.885 124.6) (end 225.885 122.315) (width 0.2) (layer "F.Cu") (net 9))
  (segment (start 192.614011 101.037691) (end 192.687691 101.037691) (width 0.1) (layer "F.Cu") (net 9))
  (segment (start 170.5 82.6445) (end 170.584492 82.560008) (width 0.1) (layer "F.Cu") (net 9))
  (segment (start 158.7 58.501334) (end 158.236328 58.965006) (width 0.2) (layer "F.Cu") (net 9))
  (segment (start 210.086328 55.060008) (end 210.086328 57.010008) (width 0.2) (layer "F.Cu") (net 9))
  (segment (start 180.136328 79.560008) (end 179.636328 79.060008) (width 0.2) (layer "F.Cu") (net 9))
  (segment (start 253.55 80) (end 253.03 80) (width 0.4) (layer "F.Cu") (net 9))
  (segment (start 131.886328 58.963672) (end 131.886328 59.660008) (width 0.2) (layer "F.Cu") (net 9))
  (segment (start 137.300328 115.108157) (end 137.286328 115.122157) (width 0.2) (layer "F.Cu") (net 9))
  (segment (start 117.301328 114.512157) (end 117.286328 114.497157) (width 0.15) (layer "F.Cu") (net 9))
  (segment (start 132.484 116.484) (end 132 116) (width 0.2) (layer "F.Cu") (net 9))
  (segment (start 202.1 58.4) (end 201.586328 58.913672) (width 0.2) (layer "F.Cu") (net 9))
  (segment (start 190.136328 100.560008) (end 190.6235 101.04718) (width 0.2) (layer "F.Cu") (net 9))
  (segment (start 211.45 58.45) (end 210.936328 58.963672) (width 0.2) (layer "F.Cu") (net 9))
  (segment (start 142.1 56.7) (end 142.086328 56.686328) (width 0.2) (layer "F.Cu") (net 9))
  (segment (start 144.286328 99.727157) (end 144.296328 99.737157) (width 0.15) (layer "F.Cu") (net 9))
  (segment (start 126.8 53.8) (end 126.8 55.046336) (width 0.2) (layer "F.Cu") (net 9))
  (segment (start 226.236328 59.660008) (end 226.236328 61.686328) (width 0.2) (layer "F.Cu") (net 9))
  (segment (start 164.586328 92.889306) (end 166.215626 92.889306) (width 0.2) (layer "F.Cu") (net 9))
  (segment (start 158.236328 58.965006) (end 158.236328 59.660008) (width 0.2) (layer "F.Cu") (net 9))
  (segment (start 187.78 80.06) (end 187.77488 80.06512) (width 0.127) (layer "F.Cu") (net 9))
  (segment (start 143.106328 115.237157) (end 143.116328 115.227157) (width 0.15) (layer "F.Cu") (net 9))
  (segment (start 223.7 53.8) (end 223.7 55.046336) (width 0.2) (layer "F.Cu") (net 9))
  (segment (start 190.636328 79.060008) (end 190.655836 79.060008) (width 0.127) (layer "F.Cu") (net 9))
  (segment (start 226.1785 119.541) (end 224.972 119.541) (width 0.1) (layer "F.Cu") (net 9))
  (segment (start 146.336328 59.013672) (end 146.336328 59.660008) (width 0.2) (layer "F.Cu") (net 9))
  (segment (start 206.686328 55.060008) (end 206.686328 57.010008) (width 0.2) (layer "F.Cu") (net 9))
  (segment (start 227.936328 59.660008) (end 227.936328 61.610008) (width 0.2) (layer "F.Cu") (net 9))
  (segment (start 211.95 55.22368) (end 211.786328 55.060008) (width 0.2) (layer "F.Cu") (net 9))
  (segment (start 244.936328 59.013672) (end 244.936328 59.660008) (width 0.2) (layer "F.Cu") (net 9))
  (segment (start 219.45 55.046336) (end 219.436328 55.060008) (width 0.2) (layer "F.Cu") (net 9))
  (segment (start 141.236328 59.013672) (end 141.236328 59.660008) (width 0.2) (layer "F.Cu") (net 9))
  (segment (start 134.236328 112.382157) (end 134.821328 112.382157) (width 0.15) (layer "F.Cu") (net 9))
  (segment (start 128.199831 58.450169) (end 127.636328 59.013672) (width 0.2) (layer "F.Cu") (net 9))
  (segment (start 135.913485 104.87) (end 135.911328 104.872157) (width 0.127) (layer "F.Cu") (net 9))
  (segment (start 156.16 105.7695) (end 156.175 105.7545) (width 0.15) (layer "F.Cu") (net 9))
  (segment (start 176.63632 80.06) (end 177.136328 80.560008) (width 0.2) (layer "F.Cu") (net 9))
  (segment (start 242.1 58.35) (end 242.1 58.401334) (width 0.2) (layer "F.Cu") (net 9))
  (segment (start 183.136328 78.560008) (end 182.636328 78.060008) (width 0.2) (layer "F.Cu") (net 9))
  (segment (start 145.52 107.37) (end 145.65 107.5) (width 0.127) (layer "F.Cu") (net 9))
  (segment (start 185.136328 86.560008) (end 184.636328 86.060008) (width 0.2) (layer "F.Cu") (net 9))
  (segment (start 187.136328 90.560008) (end 187.636328 91.060008) (width 0.2) (layer "F.Cu") (net 9))
  (segment (start 192.546336 85.15) (end 192.136328 85.560008) (width 0.2) (layer "F.Cu") (net 9))
  (segment (start 193.459548 78.081816) (end 193.459548 78.160452) (width 0.2) (layer "F.Cu") (net 9))
  (segment (start 245.786328 55.060008) (end 245.786328 56.6) (width 0.2) (layer "F.Cu") (net 9))
  (segment (start 148.4 61.5) (end 148.886328 61.013672) (width 0.2) (layer "F.Cu") (net 9))
  (segment (start 204.986328 55.060008) (end 204.972656 55.07368) (width 0.2) (layer "F.Cu") (net 9))
  (segment (start 179.136328 86.560008) (end 179.039992 86.560008) (width 0.2) (layer "F.Cu") (net 9))
  (segment (start 236.15 58.4) (end 235.586328 58.963672) (width 0.2) (layer "F.Cu") (net 9))
  (segment (start 179.410008 109.210008) (end 179.4 109.2) (width 0.2) (layer "F.Cu") (net 9))
  (segment (start 186.136328 89.560008) (end 186.636328 89.060008) (width 0.2) (layer "F.Cu") (net 9))
  (segment (start 243.25 61.25) (end 243.236328 61.236328) (width 0.2) (layer "F.Cu") (net 9))
  (segment (start 196.6 95.02368) (end 196.6 95.0505) (width 0.127) (layer "F.Cu") (net 9))
  (segment (start 150.586328 61.830737) (end 151.029439 62.273848) (width 0.2) (layer "F.Cu") (net 9))
  (segment (start 188.136328 87.560008) (end 187.636328 88.060008) (width 0.2) (layer "F.Cu") (net 9))
  (segment (start 152.286328 61.543355) (end 152.286328 59.660008) (width 0.2) (layer "F.Cu") (net 9))
  (segment (start 237.808 83.45) (end 242.725 83.45) (width 0.4) (layer "F.Cu") (net 9))
  (segment (start 130.6 58.523835) (end 130.186328 58.937507) (width 0.2) (layer "F.Cu") (net 9))
  (segment (start 133.451328 103.752157) (end 132.741328 103.752157) (width 0.15) (layer "F.Cu") (net 9))
  (segment (start 124.236328 61.236328) (end 124.25 61.25) (width 0.2) (layer "F.Cu") (net 9))
  (segment (start 199.886328 59.660008) (end 199.886328 61.3) (width 0.2) (layer "F.Cu") (net 9))
  (segment (start 159.186328 92.620008) (end 159.186328 91.610008) (width 0.15) (layer "F.Cu") (net 9))
  (segment (start 130.9 56.45) (end 130.7 56.65) (width 0.2) (layer "F.Cu") (net 9))
  (segment (start 222.71 87.85) (end 222.71 88.677629) (width 0.12) (layer "F.Cu") (net 9))
  (segment (start 190.136328 99.560008) (end 190.636328 99.060008) (width 0.2) (layer "F.Cu") (net 9))
  (segment (start 201.75 59.82368) (end 201.75 61.25) (width 0.2) (layer "F.Cu") (net 9))
  (segment (start 233.886328 59.660008) (end 233.886328 61.4) (width 0.2) (layer "F.Cu") (net 9))
  (segment (start 243.799831 58.410509) (end 243.236328 58.974012) (width 0.2) (layer "F.Cu") (net 9))
  (segment (start 242.1 58.401334) (end 241.536328 58.965006) (width 0.2) (layer "F.Cu") (net 9))
  (segment (start 237.808 79.45) (end 242.76 79.45) (width 0.4) (layer "F.Cu") (net 9))
  (segment (start 196.136328 94.560008) (end 196.6 95.02368) (width 0.127) (layer "F.Cu") (net 9))
  (segment (start 120.236328 101.272157) (end 120.236328 102.497157) (width 0.3) (layer "F.Cu") (net 9))
  (segment (start 235.586328 58.963672) (end 235.586328 59.660008) (width 0.2) (layer "F.Cu") (net 9))
  (segment (start 159.936328 59.660008) (end 159.936328 61.336328) (width 0.2) (layer "F.Cu") (net 9))
  (segment (start 145.5 53.8) (end 145.5 55.046336) (width 0.2) (layer "F.Cu") (net 9))
  (segment (start 236.45 53.8) (end 236.45 55.046336) (width 0.2) (layer "F.Cu") (net 9))
  (segment (start 182.136328 85.560008) (end 181.636328 85.060008) (width 0.127) (layer "F.Cu") (net 9))
  (segment (start 191.136328 82.560008) (end 191.636328 82.060008) (width 0.2) (layer "F.Cu") (net 9))
  (segment (start 156.536328 56.429783) (end 156.536328 55.060008) (width 0.2) (layer "F.Cu") (net 9))
  (segment (start 130.186328 61.063672) (end 129.65 61.6) (width 0.2) (layer "F.Cu") (net 9))
  (segment (start 225.1 58.4) (end 224.536328 58.963672) (width 0.2) (layer "F.Cu") (net 9))
  (segment (start 223.7 55.046336) (end 223.686328 55.060008) (width 0.2) (layer "F.Cu") (net 9))
  (segment (start 124.85 58.4) (end 124.236328 59.013672) (width 0.2) (layer "F.Cu") (net 9))
  (segment (start 184.136328 81.560008) (end 183.636328 81.060008) (width 0.2) (layer "F.Cu") (net 9))
  (segment (start 192.136328 92.560008) (end 192.636328 93.060008) (width 0.2) (layer "F.Cu") (net 9))
  (segment (start 118.896328 119.496328) (end 119 119.6) (width 0.15) (layer "F.Cu") (net 9))
  (segment (start 196.636328 77.060008) (end 196.655836 77.060008) (width 0.127) (layer "F.Cu") (net 9))
  (segment (start 235.586328 59.660008) (end 235.586328 61.336328) (width 0.2) (layer "F.Cu") (net 9))
  (segment (start 196.839992 88.560008) (end 196.136328 88.560008) (width 0.2) (layer "F.Cu") (net 9))
  (segment (start 183.136328 86.560008) (end 182.636328 86.060008) (width 0.2) (layer "F.Cu") (net 9))
  (segment (start 217.45 58.4) (end 216.886328 58.963672) (width 0.2) (layer "F.Cu") (net 9))
  (segment (start 215.186328 58.963672) (end 215.186328 59.660008) (width 0.2) (layer "F.Cu") (net 9))
  (segment (start 192.67632 97.1) (end 192.136328 96.560008) (width 0.2) (layer "F.Cu") (net 9))
  (segment (start 223.55 55.196336) (end 223.55 56.436565) (width 0.2) (layer "F.Cu") (net 9))
  (segment (start 139.776328 115.112157) (end 139.776328 115.797157) (width 0.15) (layer "F.Cu") (net 9))
  (segment (start 198.551328 58.698672) (end 198.186328 59.063672) (width 0.2) (layer "F.Cu") (net 9))
  (segment (start 198.7 58.3) (end 198.551328 58.448672) (width 0.2) (layer "F.Cu") (net 9))
  (segment (start 220.7 126.4) (end 220.675 126.375) (width 0.2) (layer "F.Cu") (net 9))
  (segment (start 144.636328 58.963672) (end 144.636328 59.660008) (width 0.2) (layer "F.Cu") (net 9))
  (segment (start 120.054 98.704) (end 120.054 99.86268) (width 0.2) (layer "F.Cu") (net 9))
  (segment (start 143.786328 53.813672) (end 143.786328 55.060008) (width 0.2) (layer "F.Cu") (net 9))
  (segment (start 234.736328 56.436328) (end 234.736328 55.060008) (width 0.2) (layer "F.Cu") (net 9))
  (segment (start 152.849831 58.410509) (end 152.849831 58.450169) (width 0.2) (layer "F.Cu") (net 9))
  (segment (start 151.436328 56.713672) (end 151.4 56.75) (width 0.2) (layer "F.Cu") (net 9))
  (segment (start 153.2 127.03) (end 154.2 127.03) (width 0.4) (layer "F.Cu") (net 9))
  (segment (start 209.236328 59.660008) (end 209.236328 61.15) (width 0.2) (layer "F.Cu") (net 9))
  (segment (start 230.5 53.8) (end 230.5 55.046336) (width 0.2) (layer "F.Cu") (net 9))
  (segment (start 193.136328 78.483672) (end 193.136328 78.560008) (width 0.2) (layer "F.Cu") (net 9))
  (segment (start 109.801328 115.997157) (end 109.036328 115.997157) (width 0.3) (layer "F.Cu") (net 9))
  (segment (start 210.1 53.8) (end 210.1 55.046336) (width 0.2) (layer "F.Cu") (net 9))
  (segment (start 192.136328 100.560008) (end 192.614011 101.037691) (width 0.2) (layer "F.Cu") (net 9))
  (segment (start 178.136328 83.560008) (end 177.636327 83.060007) (width 0.2) (layer "F.Cu") (net 9))
  (segment (start 237.286328 58.913672) (end 237.286328 59.660008) (width 0.2) (layer "F.Cu") (net 9))
  (segment (start 152.8755 105.495) (end 152.8305 105.54) (width 0.15) (layer "F.Cu") (net 9))
  (segment (start 138 55.22368) (end 138 56.45) (width 0.2) (layer "F.Cu") (net 9))
  (segment (start 232.785 122.885) (end 232.8 122.9) (width 0.2) (layer "F.Cu") (net 9))
  (segment (start 156.503 77.648808) (end 156.5142 77.660008) (width 0.15) (layer "F.Cu") (net 9))
  (segment (start 210.1 55.046336) (end 210.086328 55.060008) (width 0.2) (layer "F.Cu") (net 9))
  (segment (start 230.25 58.4) (end 229.636328 59.013672) (width 0.2) (layer "F.Cu") (net 9))
  (segment (start 145.65 128.273829) (end 145.644328 128.268157) (width 0.2) (layer "F.Cu") (net 9))
  (segment (start 243.236328 58.974012) (end 243.236328 59.660008) (width 0.2) (layer "F.Cu") (net 9))
  (segment (start 182.136328 95.560008) (end 181.636328 96.060008) (width 0.2) (layer "F.Cu") (net 9))
  (segment (start 133.586328 59.660008) (end 133.586328 61) (width 0.2) (layer "F.Cu") (net 9))
  (segment (start 192.67632 97.08832) (end 192.67632 97.1) (width 0.1) (layer "F.Cu") (net 9))
  (segment (start 204.986328 53.813672) (end 204.986328 55.060008) (width 0.2) (layer "F.Cu") (net 9))
  (segment (start 137.589828 97.7) (end 137.535 97.7) (width 0.2) (layer "F.Cu") (net 9))
  (segment (start 242.25 56.5) (end 242.1 56.65) (width 0.2) (layer "F.Cu") (net 9))
  (segment (start 127.636328 61.096336) (end 128.15 61.610008) (width 0.2) (layer "F.Cu") (net 9))
  (segment (start 214.049831 58.410509) (end 214.040825 58.410509) (width 0.2) (layer "F.Cu") (net 9))
  (segment (start 148.52 108.8) (end 149.5 108.8) (width 0.3) (layer "F.Cu") (net 9))
  (segment (start 187.631216 80.06512) (end 187.136328 80.560008) (width 0.2) (layer "F.Cu") (net 9))
  (segment (start 225.4 56.6) (end 225.386328 56.586328) (width 0.2) (layer "F.Cu") (net 9))
  (segment (start 183.136328 98.560008) (end 182.636328 99.060008) (width 0.2) (layer "F.Cu") (net 9))
  (segment (start 151.919672 61.910011) (end 152.286328 61.543355) (width 0.2) (layer "F.Cu") (net 9))
  (segment (start 225.944989 124.659989) (end 225.885 124.6) (width 0.2) (layer "F.Cu") (net 9))
  (segment (start 196.136328 96.560008) (end 196.636328 97.060008) (width 0.2) (layer "F.Cu") (net 9))
  (segment (start 155.686328 59.660008) (end 155.686328 60.063672) (width 0.2) (layer "F.Cu") (net 9))
  (segment (start 241.762 73.452) (end 242.77 74.46) (width 0.4) (layer "F.Cu") (net 9))
  (segment (start 236.25 58.4) (end 236.15 58.4) (width 0.2) (layer "F.Cu") (net 9))
  (segment (start 175.94 107.594) (end 175.734 107.8) (width 0.2) (layer "F.Cu") (net 9))
  (segment (start 142.086328 53.813672) (end 142.086328 55.060008) (width 0.2) (layer "F.Cu") (net 9))
  (segment (start 202.436328 55.060008) (end 202.55 55.17368) (width 0.2) (layer "F.Cu") (net 9))
  (segment (start 179.636328 79.060008) (end 179.636328 79.0405) (width 0.127) (layer "F.Cu") (net 9))
  (segment (start 186.136328 91.560008) (end 186.636328 92.060008) (width 0.2) (layer "F.Cu") (net 9))
  (segment (start 172.136328 85.560008) (end 172.636328 86.060008) (width 0.2) (layer "F.Cu") (net 9))
  (segment (start 193.636328 94.060008) (end 193.136328 93.560008) (width 0.2) (layer "F.Cu") (net 9))
  (segment (start 220.286328 59.660008) (end 220.4 59.77368) (width 0.2) (layer "F.Cu") (net 9))
  (segment (start 201.586328 58.913672) (end 201.586328 59.660008) (width 0.2) (layer "F.Cu") (net 9))
  (segment (start 196.136328 102.560008) (end 196.636328 103.060008) (width 0.2) (layer "F.Cu") (net 9))
  (segment (start 232.05 61.1) (end 231.6 61.55) (width 0.2) (layer "F.Cu") (net 9))
  (segment (start 190.607338 102.031018) (end 190.607338 102.060008) (width 0.1) (layer "F.Cu") (net 9))
  (segment (start 137.5 93.23868) (end 137.271328 93.010008) (width 0.2) (layer "F.Cu") (net 9))
  (segment (start 133 117.9) (end 134.133485 117.9) (width 0.2) (layer "F.Cu") (net 9))
  (segment (start 190.136328 100.560008) (end 190.136328 99.560008) (width 0.2) (layer "F.Cu") (net 9))
  (segment (start 140.25 55.196336) (end 140.386328 55.060008) (width 0.2) (layer "F.Cu") (net 9))
  (segment (start 158.7 105.76) (end 158.7 104.96) (width 0.15) (layer "F.Cu") (net 9))
  (segment (start 222.71 88.677629) (end 222.932371 88.9) (width 0.12) (layer "F.Cu") (net 9))
  (segment (start 132.4 58.45) (end 131.886328 58.963672) (width 0.2) (layer "F.Cu") (net 9))
  (segment (start 192.658 97.07) (end 192.67632 97.08832) (width 0.1) (layer "F.Cu") (net 9))
  (segment (start 204.635517 56.654381) (end 204.85 56.439898) (width 0.2) (layer "F.Cu") (net 9))
  (segment (start 158.236328 61.063672) (end 158.236328 59.660008) (width 0.2) (layer "F.Cu") (net 9))
  (segment (start 161.636328 59.660008) (end 161.636328 61.35) (width 0.2) (layer "F.Cu") (net 9))
  (segment (start 208.386328 53.813672) (end 208.386328 55.060008) (width 0.2) (layer "F.Cu") (net 9))
  (segment (start 219.45 53.8) (end 219.45 55.046336) (width 0.2) (layer "F.Cu") (net 9))
  (segment (start 233.65 122.35) (end 233.6 122.3) (width 0.2) (layer "F.Cu") (net 9))
  (segment (start 182.136328 91.560008) (end 181.636328 92.060008) (width 0.2) (layer "F.Cu") (net 9))
  (segment (start 242.386328 55.060008) (end 242.25 55.196336) (width 0.2) (layer "F.Cu") (net 9))
  (segment (start 185.136328 89.560008) (end 184.636328 89.060008) (width 0.2) (layer "F.Cu") (net 9))
  (segment (start 127.636328 59.660008) (end 127.636328 61.096336) (width 0.2) (layer "F.Cu") (net 9))
  (segment (start 110.365 110.6) (end 109.85 110.6) (width 0.2) (layer "F.Cu") (net 9))
  (segment (start 192.687691 101.037691) (end 192.7 101.05) (width 0.1) (layer "F.Cu") (net 9))
  (segment (start 230.75 122.9) (end 232.085 122.9) (width 0.2) (layer "F.Cu") (net 9))
  (segment (start 223.15 122.05) (end 223.415 122.315) (width 0.2) (layer "F.Cu") (net 9))
  (segment (start 213.486328 59.660008) (end 213.35 59.796336) (width 0.2) (layer "F.Cu") (net 9))
  (segment (start 111.851328 63.160008) (end 111.280008 63.160008) (width 0.4) (layer "F.Cu") (net 9))
  (segment (start 221.136328 55.060008) (end 221.3 55.22368) (width 0.2) (layer "F.Cu") (net 9))
  (segment (start 202.55 56.45) (end 202.75 56.65) (width 0.2) (layer "F.Cu") (net 9))
  (segment (start 214.336328 55.060008) (end 214.2 55.196336) (width 0.2) (layer "F.Cu") (net 9))
  (segment (start 175.136328 94.560008) (end 174.636328 95.060008) (width 0.2) (layer "F.Cu") (net 9))
  (segment (start 120.256328 98.402157) (end 120.256328 97.880008) (width 0.2) (layer "F.Cu") (net 9))
  (segment (start 140.386328 55.060008) (end 140.372656 55.07368) (width 0.2) (layer "F.Cu") (net 9))
  (segment (start 195.136328 88.560008) (end 194.636328 88.060008) (width 0.2) (layer "F.Cu") (net 9))
  (segment (start 186.136328 93.560008) (end 186.636328 94.060008) (width 0.2) (layer "F.Cu") (net 9))
  (segment (start 214.2 56.6) (end 213.6 57.2) (width 0.2) (layer "F.Cu") (net 9))
  (segment (start 145.2 58.35) (end 145.2 58.4) (width 0.2) (layer "F.Cu") (net 9))
  (segment (start 222.7 59.796336) (end 222.7 61.1) (width 0.2) (layer "F.Cu") (net 9))
  (segment (start 144.7175 107.37) (end 145.52 107.37) (width 0.127) (layer "F.Cu") (net 9))
  (segment (start 135.286328 59.013672) (end 135.286328 59.660008) (width 0.2) (layer "F.Cu") (net 9))
  (segment (start 215.75 58.4) (end 215.186328 58.963672) (width 0.2) (layer "F.Cu") (net 9))
  (segment (start 199.886328 58.963672) (end 199.886328 59.660008) (width 0.2) (layer "F.Cu") (net 9))
  (segment (start 223.4 58.401334) (end 222.836328 58.965006) (width 0.2) (layer "F.Cu") (net 9))
  (segment (start 120.054 101.089829) (end 120.236328 101.272157) (width 0.3) (layer "F.Cu") (net 9))
  (segment (start 215.186328 59.660008) (end 215.186328 61.3) (width 0.2) (layer "F.Cu") (net 9))
  (segment (start 154.85 55.046336) (end 154.836328 55.060008) (width 0.2) (layer "F.Cu") (net 9))
  (segment (start 234.65 122.35) (end 233.65 122.35) (width 0.2) (layer "F.Cu") (net 9))
  (segment (start 187.136328 88.560008) (end 187.636328 88.060008) (width 0.2) (layer "F.Cu") (net 9))
  (segment (start 134.15 58.4) (end 133.586328 58.963672) (width 0.2) (layer "F.Cu") (net 9))
  (segment (start 154.85 53.8) (end 154.85 55.046336) (width 0.2) (layer "F.Cu") (net 9))
  (segment (start 160.65 58.25) (end 160.65 58.3) (width 0.2) (layer "F.Cu") (net 9))
  (segment (start 196.9 88.5) (end 196.839992 88.560008) (width 0.1) (layer "F.Cu") (net 9))
  (segment (start 229.8 61.2) (end 230.15 61.55) (width 0.2) (layer "F.Cu") (net 9))
  (segment (start 139.536328 61.007172) (end 139.536328 59.660008) (width 0.2) (layer "F.Cu") (net 9))
  (segment (start 194.6 94.02368) (end 194.6 94.0505) (width 0.127) (layer "F.Cu") (net 9))
  (segment (start 192.57632 99) (end 192.7 99) (width 0.1) (layer "F.Cu") (net 9))
  (segment (start 159.186328 91.610008) (end 159.286328 91.510008) (width 0.15) (layer "F.Cu") (net 9))
  (segment (start 142.551328 115.237157) (end 143.106328 115.237157) (width 0.15) (layer "F.Cu") (net 9))
  (segment (start 222.75 122.05) (end 223.15 122.05) (width 0.2) (layer "F.Cu") (net 9))
  (segment (start 173.136328 98.560008) (end 172.636328 99.060008) (width 0.2) (layer "F.Cu") (net 9))
  (segment (start 176.136328 97.560008) (end 175.636328 98.060008) (width 0.2) (layer "F.Cu") (net 9))
  (segment (start 160.8 53.8) (end 160.8 55.046336) (width 0.2) (layer "F.Cu") (net 9))
  (segment (start 152.875 110.875) (end 153.1 111.1) (width 0.15) (layer "F.Cu") (net 9))
  (segment (start 225.386328 53.813672) (end 225.386328 55.060008) (width 0.2) (layer "F.Cu") (net 9))
  (segment (start 216.05 55.046336) (end 216.036328 55.060008) (width 0.2) (layer "F.Cu") (net 9))
  (segment (start 232.751334 58.4) (end 232.186328 58.965006) (width 0.2) (layer "F.Cu") (net 9))
  (segment (start 158.68 105.78) (end 158.7 105.76) (width 0.15) (layer "F.Cu") (net 9))
  (segment (start 211.95 56.607508) (end 211.95 55.22368) (width 0.2) (layer "F.Cu") (net 9))
  (segment (start 236.45 55.046336) (end 236.436328 55.060008) (width 0.2) (layer "F.Cu") (net 9))
  (segment (start 147.186328 56.282548) (end 147.186328 55.060008) (width 0.2) (layer "F.Cu") (net 9))
  (segment (start 195.61 90.060008) (end 195.11 90.560008) (width 0.2) (layer "F.Cu") (net 9))
  (segment (start 198.186328 59.660008) (end 198.186328 61.386328) (width 0.2) (layer "F.Cu") (net 9))
  (segment (start 123.917728 70.524208) (end 123.917728 71.170008) (width 0.4) (layer "F.Cu") (net 9))
  (segment (start 177.136328 100.560008) (end 176.636328 101.060008) (width 0.2) (layer "F.Cu") (net 9))
  (segment (start 150.586328 59.660008) (end 150.586328 61.830737) (width 0.2) (layer "F.Cu") (net 9))
  (segment (start 219.15 58.35) (end 218.586328 58.913672) (width 0.2) (layer "F.Cu") (net 9))
  (segment (start 177.636327 83.060007) (end 177.615828 83.060007) (width 0.127) (layer "F.Cu") (net 9))
  (segment (start 242.761 77.451) (end 242.77 77.46) (width 0.4) (layer "F.Cu") (net 9))
  (segment (start 126.786328 55.060008) (end 126.786328 56.7) (width 0.2) (layer "F.Cu") (net 9))
  (segment (start 233.036328 53.813672) (end 233.036328 55.060008) (width 0.2) (layer "F.Cu") (net 9))
  (segment (start 180.136328 89.560008) (end 179.636328 90.060008) (width 0.2) (layer "F.Cu") (net 9))
  (segment (start 179.039992 86.560008) (end 178.539992 87.060008) (width 0.2) (layer "F.Cu") (net 9))
  (segment (start 143.786328 55.060008) (end 143.786328 56.75) (width 0.2) (layer "F.Cu") (net 9))
  (segment (start 193.636328 90.060008) (end 193.136328 89.560008) (width 0.2) (layer "F.Cu") (net 9))
  (segment (start 148.85 127.15) (end 148.85 126.562) (width 0.2) (layer "F.Cu") (net 9))
  (segment (start 180.636328 82.060008) (end 180.636328 82.0405) (width 0.127) (layer "F.Cu") (net 9))
  (segment (start 130.9 55.196336) (end 130.9 56.45) (width 0.2) (layer "F.Cu") (net 9))
  (segment (start 146.9 127.015) (end 146.115 127.015) (width 0.1) (layer "F.Cu") (net 9))
  (segment (start 208.1 58.361336) (end 207.536328 58.925008) (width 0.2) (layer "F.Cu") (net 9))
  (segment (start 120.054 98.604485) (end 120.256328 98.402157) (width 0.2) (layer "F.Cu") (net 9))
  (segment (start 198.551328 58.448672) (end 198.551328 58.698672) (width 0.2) (layer "F.Cu") (net 9))
  (segment (start 176.136328 87.560008) (end 175.636328 88.060008) (width 0.2) (layer "F.Cu") (net 9))
  (segment (start 141.236328 59.660008) (end 141.236328 61.610008) (width 0.2) (layer "F.Cu") (net 9))
  (segment (start 145.2 58.4) (end 144.636328 58.963672) (width 0.2) (layer "F.Cu") (net 9))
  (segment (start 193.459548 78.160452) (end 193.136328 78.483672) (width 0.2) (layer "F.Cu") (net 9))
  (segment (start 153.986328 59.013672) (end 153.986328 59.660008) (width 0.2) (layer "F.Cu") (net 9))
  (segment (start 142.936328 61.413672) (end 142.7 61.65) (width 0.2) (layer "F.Cu") (net 9))
  (segment (start 132.741328 103.752157) (end 132.736328 103.757157) (width 0.15) (layer "F.Cu") (net 9))
  (segment (start 160.8 55.046336) (end 160.786328 55.060008) (width 0.2) (layer "F.Cu") (net 9))
  (segment (start 159.1 53.8) (end 159.1 55.046336) (width 0.2) (layer "F.Cu") (net 9))
  (segment (start 187.136328 92.560008) (end 187.636328 93.060008) (width 0.2) (layer "F.Cu") (net 9))
  (segment (start 172.63632 78.06) (end 172.61 78.06) (width 0.127) (layer "F.Cu") (net 9))
  (segment (start 232.1 122.885) (end 232.785 122.885) (width 0.2) (layer "F.Cu") (net 9))
  (segment (start 227.1 55.046336) (end 227.086328 55.060008) (width 0.2) (layer "F.Cu") (net 9))
  (segment (start 239.95 55.17368) (end 239.95 56.45) (width 0.2) (layer "F.Cu") (net 9))
  (segment (start 214.2 55.196336) (end 214.2 56.6) (width 0.2) (layer "F.Cu") (net 9))
  (segment (start 140.1 58.35) (end 140.1 58.4) (width 0.2) (layer "F.Cu") (net 9))
  (segment (start 239.6 58.4) (end 238.986328 59.013672) (width 0.2) (layer "F.Cu") (net 9))
  (segment (start 189.136328 86.560008) (end 189.636328 86.060008) (width 0.2) (layer "F.Cu") (net 9))
  (segment (start 223.4 58.35) (end 223.4 58.401334) (width 0.2) (layer "F.Cu") (net 9))
  (segment (start 134.436328 55.060008) (end 134.436328 56.486328) (width 0.2) (layer "F.Cu") (net 9))
  (segment (start 136.8425 104.87) (end 135.913485 104.87) (width 0.2) (layer "F.Cu") (net 9))
  (segment (start 162.486328 55.060008) (end 162.486328 56.55) (width 0.2) (layer "F.Cu") (net 9))
  (segment (start 206.7 55.046336) (end 206.686328 55.060008) (width 0.2) (layer "F.Cu") (net 9))
  (segment (start 224.536328 58.963672) (end 224.536328 59.660008) (width 0.2) (layer "F.Cu") (net 9))
  (segment (start 185.136328 90.560008) (end 184.636328 91.060008) (width 0.2) (layer "F.Cu") (net 9))
  (segment (start 233.036328 55.060008) (end 233.036328 56.300237) (width 0.2) (layer "F.Cu") (net 9))
  (segment (start 208.386328 55.060008) (end 208.386328 57.010008) (width 0.2) (layer "F.Cu") (net 9))
  (segment (start 226.15 122.05) (end 226.7 122.05) (width 0.2) (layer "F.Cu") (net 9))
  (segment (start 192.136328 90.560008) (end 191.636328 90.060008) (width 0.2) (layer "F.Cu") (net 9))
  (segment (start 216.886328 58.963672) (end 216.886328 59.660008) (width 0.2) (layer "F.Cu") (net 9))
  (segment (start 172.136328 95.560008) (end 171.636328 96.060008) (width 0.2) (layer "F.Cu") (net 9))
  (segment (start 230.5 55.046336) (end 230.486328 55.060008) (width 0.2) (layer "F.Cu") (net 9))
  (segment (start 149.736328 55.060008) (end 149.736328 56.263672) (width 0.2) (layer "F.Cu") (net 9))
  (segment (start 180.136328 99.560008) (end 179.636328 100.060008) (width 0.2) (layer "F.Cu") (net 9))
  (segment (start 190.136328 79.560008) (end 190.636328 79.060008) (width 0.2) (layer "F.Cu") (net 9))
  (segment (start 128.65 55.22368) (end 128.65 56.5) (width 0.2) (layer "F.Cu") (net 9))
  (segment (start 117.303485 99.03) (end 117.286328 99.047157) (width 0.25) (layer "F.Cu") (net 9))
  (segment (start 187.77488 80.06512) (end 187.631216 80.06512) (width 0.127) (layer "F.Cu") (net 9))
  (segment (start 245.5 58.45) (end 244.936328 59.013672) (width 0.2) (layer "F.Cu") (net 9))
  (segment (start 118.896328 117.747157) (end 118.896328 119.496328) (width 0.15) (layer "F.Cu") (net 9))
  (segment (start 231.162 79.952) (end 229.993 79.952) (width 0.12) (layer "F.Cu") (net 9))
  (segment (start 217.736328 55.060008) (end 217.736328 56.586328) (width 0.2) (layer "F.Cu") (net 9))
  (segment (start 206.399543 58.35) (end 205.836328 58.913215) (width 0.2) (layer "F.Cu") (net 9))
  (segment (start 118.204 99.03) (end 117.303485 99.03) (width 0.25) (layer "F.Cu") (net 9))
  (segment (start 125.1 55.046336) (end 125.086328 55.060008) (width 0.2) (layer "F.Cu") (net 9))
  (segment (start 239.6 61.6) (end 239.1 61.1) (width 0.2) (layer "F.Cu") (net 9))
  (segment (start 151.45 55.046336) (end 151.436328 55.060008) (width 0.2) (layer "F.Cu") (net 9))
  (segment (start 149.35 58.5) (end 149.6 58.5) (width 0.2) (layer "F.Cu") (net 9))
  (segment (start 153.67 105.495) (end 152.8755 105.495) (width 0.15) (layer "F.Cu") (net 9))
  (segment (start 237.808 73.452) (end 241.762 73.452) (width 0.4) (layer "F.Cu") (net 9))
  (segment (start 215.8 58.4) (end 215.75 58.4) (width 0.2) (layer "F.Cu") (net 9))
  (segment (start 130.186328 59.660008) (end 130.186328 61.063672) (width 0.2) (layer "F.Cu") (net 9))
  (segment (start 236.436328 55.060008) (end 236.436328 56.5) (width 0.2) (layer "F.Cu") (net 9))
  (segment (start 183.136328 92.560008) (end 182.636328 93.060008) (width 0.2) (layer "F.Cu") (net 9))
  (segment (start 146.336328 60.986328) (end 146.85 61.5) (width 0.2) (layer "F.Cu") (net 9))
  (segment (start 142.936328 58.963672) (end 142.936328 59.660008) (width 0.2) (layer "F.Cu") (net 9))
  (segment (start 141.85 58.35) (end 141.85 58.4) (width 0.2) (layer "F.Cu") (net 9))
  (segment (start 208.1 58.35) (end 208.1 58.361336) (width 0.2) (layer "F.Cu") (net 9))
  (segment (start 232.186328 59.660008) (end 232.05 59.796336) (width 0.2) (layer "F.Cu") (net 9))
  (segment (start 214.336328 53.813672) (end 214.336328 55.060008) (width 0.2) (layer "F.Cu") (net 9))
  (segment (start 137.5 61.55) (end 136.986328 61.036328) (width 0.2) (layer "F.Cu") (net 9))
  (segment (start 218.586328 58.913672) (end 218.586328 59.660008) (width 0.2) (layer "F.Cu") (net 9))
  (segment (start 184.136328 93.560008) (end 183.636328 94.060008) (width 0.2) (layer "F.Cu") (net 9))
  (segment (start 120.054 101.089829) (end 120.054 98.704) (width 0.3) (layer "F.Cu") (net 9))
  (segment (start 124.236328 59.013672) (end 124.236328 59.660008) (width 0.2) (layer "F.Cu") (net 9))
  (segment (start 195.636328 84.060008) (end 195.655836 84.060008) (width 0.127) (layer "F.Cu") (net 9))
  (segment (start 194.136328 97.560008) (end 194.636328 98.060008) (width 0.2) (layer "F.Cu") (net 9))
  (segment (start 152.05 129.41) (end 152.05 128.273829) (width 0.2) (layer "F.Cu") (net 9))
  (segment (start 239.3 123.3) (end 239.9 122.7) (width 0.2) (layer "F.Cu") (net 9))
  (segment (start 131.886328 59.660008) (end 131.886328 60.986328) (width 0.2) (layer "F.Cu") (net 9))
  (segment (start 154.836328 55.060008) (end 154.836328 56.686328) (width 0.2) (layer "F.Cu") (net 9))
  (segment (start 190.136328 95.560008) (end 190.636328 96.060008) (width 0.2) (layer "F.Cu") (net 9))
  (segment (start 186.136328 97.560008) (end 186.636328 98.060008) (width 0.2) (layer "F.Cu") (net 9))
  (segment (start 234.75 56.45) (end 234.736328 56.436328) (width 0.2) (layer "F.Cu") (net 9))
  (segment (start 142.086328 56.686328) (end 142.086328 55.060008) (width 0.2) (layer "F.Cu") (net 9))
  (segment (start 211.05 61.2) (end 211.45 61.6) (width 0.2) (layer "F.Cu") (net 9))
  (segment (start 223.415 122.315) (end 223.8 122.315) (width 0.2) (layer "F.Cu") (net 9))
  (segment (start 149.815 127.015) (end 149.8 127) (width 0.1) (layer "F.Cu") (net 9))
  (segment (start 137.536328 116.887157) (end 137.536328 116.247157) (width 0.2) (layer "F.Cu") (net 9))
  (segment (start 195.136328 102.560008) (end 195.636328 103.060008) (width 0.2) (layer "F.Cu") (net 9))
  (segment (start 234.5 58.410506) (end 233.886328 59.024178) (width 0.2) (layer "F.Cu") (net 9))
  (segment (start 192.136328 88.560008) (end 192.636328 89.060008) (width 0.2) (layer "F.Cu") (net 9))
  (segment (start 138.8 97.55) (end 138.75 97.5) (width 0.2) (layer "F.Cu") (net 9))
  (segment (start 198.186328 61.386328) (end 198.4 61.6) (width 0.2) (layer "F.Cu") (net 9))
  (segment (start 154.836328 56.686328) (end 154.85 56.7) (width 0.2) (layer "F.Cu") (net 9))
  (segment (start 175.313 76.741046) (end 175.317366 76.741046) (width 0.127) (layer "F.Cu") (net 9))
  (segment (start 211.45 58.35) (end 211.45 58.45) (width 0.2) (layer "F.Cu") (net 9))
  (segment (start 200.45 58.4) (end 199.886328 58.963672) (width 0.2) (layer "F.Cu") (net 9))
  (segment (start 120.555128 67.155128) (end 120.555128 67.740008) (width 0.4) (layer "F.Cu") (net 9))
  (segment (start 152.35 110.875) (end 152.875 110.875) (width 0.15) (layer "F.Cu") (net 9))
  (segment (start 234.736328 53.813672) (end 234.736328 55.060008) (width 0.2) (layer "F.Cu") (net 9))
  (segment (start 184.136328 87.560008) (end 183.636328 87.060008) (width 0.2) (layer "F.Cu") (net 9))
  (segment (start 136.136328 56.486328) (end 136.15 56.5) (width 0.1) (layer "F.Cu") (net 9))
  (segment (start 245.5 58.4) (end 245.5 58.45) (width 0.2) (layer "F.Cu") (net 9))
  (segment (start 237.808 81.45) (end 242.75 81.45) (width 0.4) (layer "F.Cu") (net 9))
  (segment (start 214.040825 58.410509) (end 213.486328 58.965006) (width 0.2) (layer "F.Cu") (net 9))
  (segment (start 157.75 61.55) (end 158.236328 61.063672) (width 0.2) (layer "F.Cu") (net 9))
  (segment (start 124.236328 59.660008) (end 124.236328 61.236328) (width 0.2) (layer "F.Cu") (net 9))
  (segment (start 139.556328 99.727157) (end 139.526328 99.757157) (width 0.15) (layer "F.Cu") (net 9))
  (segment (start 170.584492 82.560008) (end 171.136328 82.560008) (width 0.2) (layer "F.Cu") (net 9))
  (segment (start 239.85 55.046336) (end 239.836328 55.060008) (width 0.2) (layer "F.Cu") (net 9))
  (segment (start 243.236328 61.236328) (end 243.236328 59.660008) (width 0.2) (layer "F.Cu") (net 9))
  (segment (start 142.551328 114.157157) (end 143.116328 114.157157) (width 0.15) (layer "F.Cu") (net 9))
  (segment (start 192.136328 102.560008) (end 192.636328 103.060008) (width 0.2) (layer "F.Cu") (net 9))
  (segment (start 156.25 58.4) (end 155.686328 58.963672) (width 0.2) (layer "F.Cu") (net 9))
  (segment (start 155.686328 60.063672) (end 155.686328 61.036328) (width 0.2) (layer "F.Cu") (net 9))
  (segment (start 207.536328 58.925008) (end 207.536328 59.660008) (width 0.2) (layer "F.Cu") (net 9))
  (segment (start 151.45 53.8) (end 151.45 55.046336) (width 0.2) (layer "F.Cu") (net 9))
  (segment (start 190.136328 101.560008) (end 190.607338 102.031018) (width 0.2) (layer "F.Cu") (net 9))
  (segment (start 145.65 129.41) (end 145.65 128.273829) (width 0.2) (layer "F.Cu") (net 9))
  (segment (start 131.886328 60.986328) (end 132.35 61.45) (width 0.2) (layer "F.Cu") (net 9))
  (segment (start 205.836328 59.660008) (end 205.836328 61.2) (width 0.2) (layer "F.Cu") (net 9))
  (segment (start 134.436328 56.486328) (end 134.45 56.5) (width 0.2) (layer "F.Cu") (net 9))
  (segment (start 226.5243 124.659989) (end 225.944989 124.659989) (width 0.2) (layer "F.Cu") (net 9))
  (segment (start 193.136328 87.560008) (end 193.636328 88.060008) (width 0.2) (layer "F.Cu") (net 9))
  (segment (start 138.03 103.1825) (end 138.03 102.33) (width 0.2) (layer "F.Cu") (net 9))
  (segment (start 137.314328 113.969157) (end 137.286328 113.997157) (width 0.2) (layer "F.Cu") (net 9))
  (segment (start 178.539992 87.060008) (end 178.467089 87.060008) (width 0.2) (layer "F.Cu") (net 9))
  (segment (start 143.116328 114.157157) (end 143.136328 114.137157) (width 0.15) (layer "F.Cu") (net 9))
  (segment (start 118.926328 114.497157) (end 117.926328 114.497157) (width 0.15) (layer "F.Cu") (net 9))
  (segment (start 193.136328 97.560008) (end 193.636328 98.060008) (width 0.2) (layer "F.Cu") (net 9))
  (segment (start 183.636328 81.060008) (end 183.636328 81.0405) (width 0.127) (layer "F.Cu") (net 9))
  (segment (start 151.2 58.4) (end 150.586328 59.013672) (width 0.2) (layer "F.Cu") (net 9))
  (segment (start 236.252 115.731) (end 237.037 115.731) (width 0.1) (layer "F.Cu") (net 9))
  (segment (start 136.136328 55.060008) (end 136.136328 56.486328) (width 0.2) (layer "F.Cu") (net 9))
  (segment (start 204 59.796336) (end 204.136328 59.660008) (width 0.2) (layer "F.Cu") (net 9))
  (segment (start 142.03 111.0575) (end 142.03 111.93) (width 0.127) (layer "F.Cu") (net 9))
  (segment (start 195.136328 98.560008) (end 195.636328 99.060008) (width 0.2) (layer "F.Cu") (net 9))
  (segment (start 137.535 97.7) (end 136.985 98.25) (width 0.2) (layer "F.Cu") (net 9))
  (segment (start 153.2 127.03) (end 153.2 126.4) (width 0.4) (layer "F.Cu") (net 9))
  (segment (start 233.036328 56.300237) (end 232.685618 56.650947) (width 0.2) (layer "F.Cu") (net 9))
  (segment (start 156.503 75.756) (end 156.503 77.648808) (width 0.3) (layer "F.Cu") (net 9))
  (segment (start 217.736328 56.586328) (end 217.75 56.6) (width 0.2) (layer "F.Cu") (net 9))
  (segment (start 125.936328 61.236328) (end 125.936328 59.660008) (width 0.2) (layer "F.Cu") (net 9))
  (segment (start 131.576328 95.650008) (end 131.446328 95.650008) (width 0.2) (layer "F.Cu") (net 9))
  (segment (start 214.336328 55.060008) (end 214.322656 55.07368) (width 0.2) (layer "F.Cu") (net 9))
  (segment (start 213.35 61.1) (end 212.85 61.6) (width 0.2) (layer "F.Cu") (net 9))
  (segment (start 196.9 87.5) (end 196.839992 87.560008) (width 0.1) (layer "F.Cu") (net 9))
  (segment (start 130.186328 58.937507) (end 130.186328 59.660008) (width 0.2) (layer "F.Cu") (net 9))
  (segment (start 152.05 128.273829) (end 152.044328 128.268157) (width 0.2) (layer "F.Cu") (net 9))
  (segment (start 151.2 58.35) (end 151.2 58.4) (width 0.2) (layer "F.Cu") (net 9))
  (segment (start 181.136328 102.560008) (end 180.636328 103.060008) (width 0.2) (layer "F.Cu") (net 9))
  (segment (start 137.836328 53.813672) (end 137.836328 55.060008) (width 0.2) (layer "F.Cu") (net 9))
  (segment (start 190.136328 97.560008) (end 190.636328 98.060008) (width 0.1) (layer "F.Cu") (net 9))
  (segment (start 226.236328 61.686328) (end 227.1 62.55) (width 0.2) (layer "F.Cu") (net 9))
  (segment (start 182.136328 89.560008) (end 181.636328 89.060008) (width 0.2) (layer "F.Cu") (net 9))
  (segment (start 203.5 61.6) (end 204 61.1) (width 0.2) (layer "F.Cu") (net 9))
  (segment (start 146.115 127.015) (end 146.1 127) (width 0.1) (layer "F.Cu") (net 9))
  (segment (start 229.8 59.82368) (end 229.8 61.2) (width 0.2) (layer "F.Cu") (net 9))
  (segment (start 146.9 58.35) (end 146.9 58.45) (width 0.2) (layer "F.Cu") (net 9))
  (segment (start 147.536831 56.633051) (end 147.186328 56.282548) (width 0.2) (layer "F.Cu") (net 9))
  (segment (start 132.836328 107.407157) (end 132.826328 107.397157) (width 0.15) (layer "F.Cu") (net 9))
  (segment (start 194.136328 81.560008) (end 194.636328 81.060008) (width 0.2) (layer "F.Cu") (net 9))
  (segment (start 241.4 61.032829) (end 241.4 59.796336) (width 0.2) (layer "F.Cu") (net 9))
  (segment (start 152.286328 59.013672) (end 152.286328 59.660008) (width 0.2) (layer "F.Cu") (net 9))
  (segment (start 196.839992 87.560008) (end 196.136328 87.560008) (width 0.2) (layer "F.Cu") (net 9))
  (segment (start 125.936328 59.013672) (end 125.936328 59.660008) (width 0.2) (layer "F.Cu") (net 9))
  (segment (start 196.59582 99.0195) (end 196.636328 99.0195) (width 0.1) (layer "F.Cu") (net 9))
  (segment (start 188.136328 83.560008) (end 188.636328 83.060008) (width 0.2) (layer "F.Cu") (net 9))
  (segment (start 220.4 59.77368) (end 220.4 61.15) (width 0.2) (layer "F.Cu") (net 9))
  (segment (start 154.549831 58.410509) (end 154.549831 58.450169) (width 0.2) (layer "F.Cu") (net 9))
  (segment (start 244.936328 59.660008) (end 244.936328 61.3) (width 0.2) (layer "F.Cu") (net 9))
  (segment (start 136.024143 95.825) (end 137.05 95.825) (width 0.2) (layer "F.Cu") (net 9))
  (segment (start 228.786328 55.060008) (end 228.786328 56.65) (width 0.2) (layer "F.Cu") (net 9))
  (segment (start 189.136328 96.560008) (end 189.636328 97.060008) (width 0.2) (layer "F.Cu") (net 9))
  (segment (start 140.25 56.45) (end 140.25 55.196336) (width 0.2) (layer "F.Cu") (net 9))
  (segment (start 120.1 67) (end 120.4 67) (width 0.4) (layer "F.Cu") (net 9))
  (segment (start 133.586328 58.963672) (end 133.586328 59.660008) (width 0.2) (layer "F.Cu") (net 9))
  (segment (start 190.136328 93.560008) (end 190.636328 94.060008) (width 0.2) (layer "F.Cu") (net 9))
  (segment (start 221.3 56.5) (end 221.45 56.65) (width 0.2) (layer "F.Cu") (net 9))
  (segment (start 222.7 61.1) (end 222.2 61.6) (width 0.2) (layer "F.Cu") (net 9))
  (segment (start 150.586328 59.013672) (end 150.586328 59.660008) (width 0.2) (layer "F.Cu") (net 9))
  (segment (start 136.011328 114.397157) (end 136.036328 114.372157) (width 0.2) (layer "F.Cu") (net 9))
  (segment (start 227.086328 55.060008) (end 227.086328 56.65) (width 0.2) (layer "F.Cu") (net 9))
  (segment (start 180.406328 109.210008) (end 179.410008 109.210008) (width 0.2) (layer "F.Cu") (net 9))
  (segment (start 242.386328 53.813672) (end 242.386328 55.060008) (width 0.2) (layer "F.Cu") (net 9))
  (segment (start 152.8305 108.54) (end 153.585 108.54) (width 0.15) (layer "F.Cu") (net 9))
  (segment (start 218.119872 61.856972) (end 218.586328 61.390516) (width 0.2) (layer "F.Cu") (net 9))
  (segment (start 192.136328 94.560008) (end 192.636328 95.060008) (width 0.2) (layer "F.Cu") (net 9))
  (segment (start 155.686328 61.036328) (end 156.2 61.55) (width 0.2) (layer "F.Cu") (net 9))
  (segment (start 193.136328 101.560008) (end 193.636328 102.060008) (width 0.2) (layer "F.Cu") (net 9))
  (segment (start 185.136328 84.560008) (end 184.636328 84.060008) (width 0.2) (layer "F.Cu") (net 9))
  (segment (start 120.054 99.86268) (end 120.056328 99.865008) (width 0.2) (layer "F.Cu") (net 9))
  (segment (start 128.486328 53.813672) (end 128.486328 55.060008) (width 0.2) (layer "F.Cu") (net 9))
  (segment (start 137.5 95.375) (end 137.5 93.23868) (width 0.2) (layer "F.Cu") (net 9))
  (segment (start 127.636328 59.013672) (end 127.636328 59.660008) (width 0.2) (layer "F.Cu") (net 9))
  (segment (start 136.986328 58.913672) (end 136.986328 59.660008) (width 0.2) (layer "F.Cu") (net 9))
  (segment (start 196.136328 98.560008) (end 196.59582 99.0195) (width 0.2) (layer "F.Cu") (net 9))
  (segment (start 131.05 53.8) (end 131.05 55.046336) (width 0.2) (layer "F.Cu") (net 9))
  (segment (start 188.136328 93.560008) (end 188.636328 94.060008) (width 0.2) (layer "F.Cu") (net 9))
  (segment (start 242.76 79.45) (end 242.77 79.46) (width 0.4) (layer "F.Cu") (net 9))
  (segment (start 194.636328 90.060008) (end 194.136328 89.560008) (width 0.2) (layer "F.Cu") (net 9))
  (segment (start 139.536328 58.963672) (end 139.536328 59.660008) (width 0.2) (layer "F.Cu") (net 9))
  (segment (start 216.05 53.8) (end 216.05 55.046336) (width 0.2) (layer "F.Cu") (net 9))
  (segment (start 187.136328 100.560008) (end 187.636328 101.060008) (width 0.2) (layer "F.Cu") (net 9))
  (segment (start 135.85 58.4) (end 135.85 58.45) (width 0.2) (layer "F.Cu") (net 9))
  (segment (start 198.186328 59.063672) (end 198.186328 59.660008) (width 0.2) (layer "F.Cu") (net 9))
  (segment (start 229.636328 59.013672) (end 229.636328 59.660008) (width 0.2) (layer "F.Cu") (net 9))
  (segment (start 159.936328 59.013672) (end 159.936328 59.660008) (width 0.2) (layer "F.Cu") (net 9))
  (segment (start 142.03 111.93) (end 142.1 112) (width 0.127) (layer "F.Cu") (net 9))
  (segment (start 177.136328 90.560008) (end 176.636328 91.060008) (width 0.2) (layer "F.Cu") (net 9))
  (segment (start 210.936328 58.963672) (end 210.936328 59.660008) (width 0.2) (layer "F.Cu") (net 9))
  (segment (start 153.986328 59.660008) (end 153.986328 61.35) (width 0.2) (layer "F.Cu") (net 9))
  (segment (start 174.136328 81.560008) (end 174.636328 81.060008) (width 0.2) (layer "F.Cu") (net 9))
  (segment (start 186.136328 90.560008) (end 186.636328 91.060008) (width 0.2) (layer "F.Cu") (net 9))
  (segment (start 201.515 124.3) (end 201.515 123.3) (width 0.4) (layer "F.Cu") (net 9))
  (segment (start 239.27 123.3) (end 239.3 123.3) (width 0.2) (layer "F.Cu") (net 9))
  (segment (start 128.486328 55.060008) (end 128.65 55.22368) (width 0.2) (layer "F.Cu") (net 9))
  (segment (start 157.496328 78.577157) (end 158.219179 78.577157) (width 0.2) (layer "F.Cu") (net 9))
  (segment (start 220.4 61.15) (end 220.85 61.6) (width 0.2) (layer "F.Cu") (net 9))
  (segment (start 135.286328 59.660008) (end 135.286328 61.0275) (width 0.2) (layer "F.Cu") (net 9))
  (segment (start 146.9 58.45) (end 146.336328 59.013672) (width 0.2) (layer "F.Cu") (net 9))
  (segment (start 116.286328 114.422157) (end 117.821328 114.422157) (width 0.15) (layer "F.Cu") (net 9))
  (segment (start 225.386328 56.586328) (end 225.386328 55.060008) (width 0.2) (layer "F.Cu") (net 9))
  (segment (start 183.136328 90.560008) (end 182.636328 91.060008) (width 0.2) (layer "F.Cu") (net 9))
  (segment (start 115.036328 99.607157) (end 114.426328 99.607157) (width 0.2) (layer "F.Cu") (net 9))
  (segment (start 240.832829 61.6) (end 241.4 61.032829) (width 0.2) (layer "F.Cu") (net 9))
  (segment (start 131.036328 55.060008) (end 130.9 55.196336) (width 0.2) (layer "F.Cu") (net 9))
  (segment (start 228.745 79.952) (end 229.993 79.952) (width 0.12) (layer "F.Cu") (net 9))
  (segment (start 136.136328 53.813672) (end 136.136328 55.060008) (width 0.2) (layer "F.Cu") (net 9))
  (segment (start 230.486328 55.060008) (end 230.486328 56.286328) (width 0.2) (layer "F.Cu") (net 9))
  (segment (start 221.365 126.4) (end 220.7 126.4) (width 0.2) (layer "F.Cu") (net 9))
  (segment (start 228.786328 53.813672) (end 228.786328 55.060008) (width 0.2) (layer "F.Cu") (net 9))
  (segment (start 115.661328 114.422157) (end 114.286328 114.422157) (width 0.2) (layer "F.Cu") (net 9))
  (segment (start 152.849831 58.450169) (end 152.286328 59.013672) (width 0.2) (layer "F.Cu") (net 9))
  (segment (start 196.136328 77.560008) (end 196.636328 77.060008) (width 0.2) (layer "F.Cu") (net 9))
  (segment (start 230.486328 56.286328) (end 230.8 56.6) (width 0.2) (layer "F.Cu") (net 9))
  (segment (start 174.6 84.07368) (end 175.086328 84.560008) (width 0.2) (layer "F.Cu") (net 9))
  (segment (start 184.136328 89.560008) (end 183.636328 89.060008) (width 0.2) (layer "F.Cu") (net 9))
  (segment (start 128.199831 58.410509) (end 128.199831 58.450169) (width 0.2) (layer "F.Cu") (net 9))
  (segment (start 134.45 55.046336) (end 134.436328 55.060008) (width 0.2) (layer "F.Cu") (net 9))
  (segment (start 132.036328 96.110008) (end 131.576328 95.650008) (width 0.2) (layer "F.Cu") (net 9))
  (segment (start 185.136328 92.560008) (end 184.636328 93.060008) (width 0.2) (layer "F.Cu") (net 9))
  (segment (start 111.851328 64.160008) (end 111.190008 64.160008) (width 0.4) (layer "F.Cu") (net 9))
  (segment (start 186.136328 88.560008) (end 186.636328 88.060008) (width 0.2) (layer "F.Cu") (net 9))
  (segment (start 165.35703 96.289306) (end 165.386328 96.260008) (width 0.2) (layer "F.Cu") (net 9))
  (segment (start 175.317366 76.741046) (end 176.136328 77.560008) (width 0.2) (layer "F.Cu") (net 9))
  (segment (start 156.55 55.046336) (end 156.536328 55.060008) (width 0.2) (layer "F.Cu") (net 9))
  (segment (start 238.136328 55.060008) (end 238.136328 56.55) (width 0.2) (layer "F.Cu") (net 9))
  (segment (start 219.436328 55.060008) (end 219.436328 56.6) (width 0.2) (layer "F.Cu") (net 9))
  (segment (start 218.586328 61.390516) (end 218.586328 59.660008) (width 0.2) (layer "F.Cu") (net 9))
  (segment (start 134.45 53.8) (end 134.45 55.046336) (width 0.2) (layer "F.Cu") (net 9))
  (segment (start 220.62 88.734904) (end 220.304904 89.05) (width 0.12) (layer "F.Cu") (net 9))
  (segment (start 175.734 107.8) (end 175.2 107.8) (width 0.2) (layer "F.Cu") (net 9))
  (segment (start 114.426328 99.607157) (end 114.411328 99.622157) (width 0.2) (layer "F.Cu") (net 9))
  (segment (start 158.7 58.4) (end 158.7 58.501334) (width 0.2) (layer "F.Cu") (net 9))
  (segment (start 109.801328 114.872157) (end 109.036328 114.872157) (width 0.3) (layer "F.Cu") (net 9))
  (segment (start 192.136328 98.560008) (end 192.57632 99) (width 0.2) (layer "F.Cu") (net 9))
  (segment (start 146.336328 59.660008) (end 146.336328 60.986328) (width 0.2) (layer "F.Cu") (net 9))
  (segment (start 136.011328 115.522157) (end 136.011328 114.397157) (width 0.2) (layer "F.Cu") (net 9))
  (segment (start 241.4 59.796336) (end 241.536328 59.660008) (width 0.2) (layer "F.Cu") (net 9))
  (segment (start 200.736328 55.060008) (end 200.736328 56.55) (width 0.2) (layer "F.Cu") (net 9))
  (segment (start 190.136328 102.560008) (end 190.136328 103.060008) (width 0.2) (layer "F.Cu") (net 9))
  (segment (start 159.936328 61.336328) (end 159.95 61.35) (width 0.2) (layer "F.Cu") (net 9))
  (segment (start 194.136328 93.560008) (end 194.6 94.02368) (width 0.2) (layer "F.Cu") (net 9))
  (segment (start 173.136328 78.560008) (end 172.63632 78.06) (width 0.2) (layer "F.Cu") (net 9))
  (segment (start 179.136328 96.560008) (end 178.636328 97.060008) (width 0.2) (layer "F.Cu") (net 9))
  (segment (start 182.636328 78.060008) (end 182.636328 78.0405) (width 0.127) (layer "F.Cu") (net 9))
  (segment (start 142.936328 59.660008) (end 142.936328 61.413672) (width 0.2) (layer "F.Cu") (net 9))
  (segment (start 190.136328 90.560008) (end 190.636328 91.060008) (width 0.2) (layer "F.Cu") (net 9))
  (segment (start 237.808 75.451) (end 242.261 75.451) (width 0.4) (layer "F.Cu") (net 9))
  (segment (start 164.586328 96.289306) (end 165.35703 96.289306) (width 0.2) (layer "F.Cu") (net 9))
  (segment (start 137.5 58.4) (end 136.986328 58.913672) (width 0.2) (layer "F.Cu") (net 9))
  (segment (start 233.886328 59.024178) (end 233.886328 59.660008) (width 0.2) (layer "F.Cu") (net 9))
  (segment (start 186.136328 76.867228) (end 186.136328 77.560008) (width 0.2) (layer "F.Cu") (net 9))
  (segment (start 221.3 55.22368) (end 221.3 56.5) (width 0.2) (layer "F.Cu") (net 9))
  (segment (start 239.836328 55.060008) (end 239.95 55.17368) (width 0.2) (layer "F.Cu") (net 9))
  (segment (start 156.175 105.7545) (end 156.175 104.91) (width 0.15) (layer "F.Cu") (net 9))
  (segment (start 242.25 55.196336) (end 242.25 56.5) (width 0.2) (layer "F.Cu") (net 9))
  (segment (start 193.136328 99.560008) (end 193.57 99.96) (width 0.2) (layer "F.Cu") (net 9))
  (segment (start 137.801328 113.969157) (end 137.314328 113.969157) (width 0.2) (layer "F.Cu") (net 9))
  (segment (start 130.6 58.4) (end 130.6 58.523835) (width 0.2) (layer "F.Cu") (net 9))
  (segment (start 125.95 61.25) (end 125.936328 61.236328) (width 0.2) (layer "F.Cu") (net 9))
  (segment (start 239.95 56.45) (end 240.1 56.6) (width 0.2) (layer "F.Cu") (net 9))
  (segment (start 132.4 58.4) (end 132.4 58.45) (width 0.2) (layer "F.Cu") (net 9))
  (segment (start 201.75 61.25) (end 202.1 61.6) (width 0.2) (layer "F.Cu") (net 9))
  (segment (start 120.054 98.604485) (end 120.054 98.704) (width 0.2) (layer "F.Cu") (net 9))
  (segment (start 216.036328 55.060008) (end 216.036328 56.55) (width 0.2) (layer "F.Cu") (net 9))
  (segment (start 185.136328 88.560008) (end 184.636328 88.060008) (width 0.2) (layer "F.Cu") (net 9))
  (segment (start 188.636328 83.060008) (end 188.655836 83.060008) (width 0.127) (layer "F.Cu") (net 9))
  (segment (start 186.136328 87.560008) (end 185.636328 87.060008) (width 0.2) (layer "F.Cu") (net 9))
  (segment (start 239.1 61.1) (end 239.1 59.77368) (width 0.2) (layer "F.Cu") (net 9))
  (segment (start 244.086328 53.813672) (end 244.086328 55.060008) (width 0.2) (layer "F.Cu") (net 9))
  (segment (start 204.6 58.4) (end 204.6 58.501334) (width 0.2) (layer "F.Cu") (net 9))
  (segment (start 145.486328 55.060008) (end 145.486328 56.75) (width 0.2) (layer "F.Cu") (net 9))
  (segment (start 157.3165 57.209955) (end 156.536328 56.429783) (width 0.2) (layer "F.Cu") (net 9))
  (segment (start 126.55 58.4) (end 125.936328 59.013672) (width 0.2) (layer "F.Cu") (net 9))
  (segment (start 182.136328 87.560008) (end 181.636328 87.060008) (width 0.2) (layer "F.Cu") (net 9))
  (segment (start 235.586328 61.336328) (end 235.6 61.35) (width 0.2) (layer "F.Cu") (net 9))
  (segment (start 213.35 59.796336) (end 213.35 61.1) (width 0.2) (layer "F.Cu") (net 9))
  (segment (start 184.136328 91.560008) (end 183.636328 92.060008) (width 0.2) (layer "F.Cu") (net 9))
  (segment (start 160.65 58.3) (end 159.936328 59.013672) (width 0.2) (layer "F.Cu") (net 9))
  (segment (start 188.136328 89.560008) (end 188.636328 89.060008) (width 0.2) (layer "F.Cu") (net 9))
  (segment (start 143.45 58.45) (end 142.936328 58.963672) (width 0.2) (layer "F.Cu") (net 9))
  (segment (start 131.05 55.046336) (end 131.036328 55.060008) (width 0.2) (layer "F.Cu") (net 9))
  (segment (start 148.886328 61.013672) (end 148.886328 59.660008) (width 0.2) (layer "F.Cu") (net 9))
  (segment (start 116.286328 114.422157) (end 115.661328 114.422157) (width 0.2) (layer "F.Cu") (net 9))
  (segment (start 125.1 53.8) (end 125.1 55.046336) (width 0.2) (layer "F.Cu") (net 9))
  (segment (start 220.787 113.352) (end 220.787 114.01) (width 0.2) (layer "F.Cu") (net 9))
  (segment (start 159.4 107.48) (end 159.4 108.315) (width 0.15) (layer "F.Cu") (net 9))
  (segment (start 134.821328 112.382157) (end 134.826328 112.377157) (width 0.15) (layer "F.Cu") (net 9))
  (segment (start 216.886328 59.660008) (end 216.886328 61.25) (width 0.2) (layer "F.Cu") (net 9))
  (segment (start 164.586328 99.659306) (end 164.586328 100.260008) (width 0.2) (layer "F.Cu") (net 9))
  (segment (start 204.85 56.439898) (end 204.85 55.196336) (width 0.2) (layer "F.Cu") (net 9))
  (segment (start 125.086328 55.060008) (end 125.086328 56.65) (width 0.2) (layer "F.Cu") (net 9))
  (segment (start 175.56 80.13) (end 175.63 80.06) (width 0.2) (layer "F.Cu") (net 9))
  (segment (start 228.5 58.35) (end 227.936328 58.913672) (width 0.2) (layer "F.Cu") (net 9))
  (segment (start 154.549831 58.450169) (end 153.986328 59.013672) (width 0.2) (layer "F.Cu") (net 9))
  (segment (start 138.9935 61.55) (end 139.536328 61.007172) (width 0.2) (layer "F.Cu") (net 9))
  (segment (start 190.136328 91.560008) (end 190.636328 92.060008) (width 0.2) (layer "F.Cu") (net 9))
  (segment (start 237.286328 59.660008) (end 237.286328 61.35) (width 0.2) (layer "F.Cu") (net 9))
  (segment (start 201.586328 59.660008) (end 201.75 59.82368) (width 0.2) (layer "F.Cu") (net 9))
  (segment (start 223.55 56.436565) (end 223.335618 56.650947) (width 0.2) (layer "F.Cu") (net 9))
  (segment (start 149.35 58.5) (end 148.886328 58.963672) (width 0.2) (layer "F.Cu") (net 9))
  (segment (start 128.65 56.5) (end 128.8 56.65) (width 0.2) (layer "F.Cu") (net 9))
  (segment (start 138 56.45) (end 138.15 56.6) (width 0.2) (layer "F.Cu") (net 9))
  (segment (start 162.7 105.7) (end 162.8 105.8) (width 0.15) (layer "F.Cu") (net 9))
  (segment (start 220.8 58.4) (end 220.286328 58.913672) (width 0.2) (layer "F.Cu") (net 9))
  (segment (start 171.136328 92.560008) (end 170.636328 93.060008) (width 0.2) (layer "F.Cu") (net 9))
  (segment (start 138.03 102.33) (end 138 102.3) (width 0.2) (layer "F.Cu") (net 9))
  (segment (start 191.636328 82.060008) (end 191.655836 82.060008) (width 0.127) (layer "F.Cu") (net 9))
  (segment (start 148.886328 58.963672) (end 148.886328 58.965006) (width 0.2) (layer "F.Cu") (net 9))
  (segment (start 229.636328 59.660008) (end 229.8 59.82368) (width 0.2) (layer "F.Cu") (net 9))
  (segment (start 160.786328 55.060008) (end 160.786328 56.55) (width 0.2) (layer "F.Cu") (net 9))
  (segment (start 155.686328 58.963672) (end 155.686328 59.660008) (width 0.2) (layer "F.Cu") (net 9))
  (segment (start 227.936328 58.913672) (end 227.936328 59.660008) (width 0.2) (layer "F.Cu") (net 9))
  (segment (start 232.085 122.9) (end 232.1 122.885) (width 0.2) (layer "F.Cu") (net 9))
  (segment (start 232.05 59.796336) (end 232.05 61.1) (width 0.2) (layer "F.Cu") (net 9))
  (segment (start 196.136328 100.560008) (end 196.636328 101.060008) (width 0.2) (layer "F.Cu") (net 9))
  (segment (start 204.6 58.501334) (end 204.136328 58.965006) (width 0.2) (layer "F.Cu") (net 9))
  (segment (start 151.436328 55.060008) (end 151.436328 56.713672) (width 0.2) (layer "F.Cu") (net 9))
  (segment (start 192.66 85.15) (end 192.546336 85.15) (width 0.127) (layer "F.Cu") (net 9))
  (segment (start 153.136328 53.813672) (end 153.136328 55.060008) (width 0.2) (layer "F.Cu") (net 9))
  (segment (start 200.736328 53.813672) (end 200.736328 55.060008) (width 0.2) (layer "F.Cu") (net 9))
  (segment (start 204 61.1) (end 204 59.796336) (width 0.2) (layer "F.Cu") (net 9))
  (segment (start 222.836328 59.660008) (end 222.7 59.796336) (width 0.2) (layer "F.Cu") (net 9))
  (segment (start 238.136328 53.813672) (end 238.136328 55.060008) (width 0.2) (layer "F.Cu") (net 9))
  (segment (start 239.85 53.8) (end 239.85 55.046336) (width 0.2) (layer "F.Cu") (net 9))
  (segment (start 143.661328 99.727157) (end 144.286328 99.727157) (width 0.15) (layer "F.Cu") (net 9))
  (segment (start 193.136328 95.560008) (end 193.636328 96.060008) (width 0.2) (layer "F.Cu") (net 9))
  (segment (start 190.136328 98.560008) (end 190.636328 99.060008) (width 0.2) (layer "F.Cu") (net 9))
  (segment (start 188.136328 91.560008) (end 188.636328 92.060008) (width 0.2) (layer "F.Cu") (net 9))
  (segment (start 117.911328 114.512157) (end 117.301328 114.512157) (width 0.15) (layer "F.Cu") (net 9))
  (segment (start 120.4 67) (end 120.555128 67.155128) (width 0.4) (layer "F.Cu") (net 9))
  (via (at 132.736328 104.817157) (size 0.5) (drill 0.2) (layers "F.Cu" "B.Cu") (net 9))
  (via (at 135.911328 104.872157) (size 0.5) (drill 0.2) (layers "F.Cu" "B.Cu") (net 9))
  (via (at 163.486328 100.220008) (size 0.5) (drill 0.2) (layers "F.Cu" "B.Cu") (net 9))
  (via (at 151.786328 96.224306) (size 0.5) (drill 0.2) (layers "F.Cu" "B.Cu") (net 9))
  (via (at 147.486328 96.224306) (size 0.5) (drill 0.2) (layers "F.Cu" "B.Cu") (net 9))
  (via (at 148.486328 101.320008) (size 0.5) (drill 0.2) (layers "F.Cu" "B.Cu") (net 9))
  (via (at 149.786328 100.320008) (size 0.5) (drill 0.2) (layers "F.Cu" "B.Cu") (net 9))
  (via (at 151.586328 100.620008) (size 0.5) (drill 0.2) (layers "F.Cu" "B.Cu") (net 9))
  (via (at 159.586328 94.020008) (size 0.5) (drill 0.2) (layers "F.Cu" "B.Cu") (net 9))
  (via (at 158.486328 94.020008) (size 0.5) (drill 0.2) (layers "F.Cu" "B.Cu") (net 9))
  (via (at 157.486328 94.020008) (size 0.5) (drill 0.2) (layers "F.Cu" "B.Cu") (net 9))
  (via (at 156.486328 94.020008) (size 0.5) (drill 0.2) (layers "F.Cu" "B.Cu") (net 9))
  (via (at 213.649828 117.647157) (size 0.5) (drill 0.2) (layers "F.Cu" "B.Cu") (net 9))
  (via (at 212.159828 117.607157) (size 0.5) (drill 0.2) (layers "F.Cu" "B.Cu") (net 9))
  (via (at 210.649828 117.567157) (size 0.5) (drill 0.2) (layers "F.Cu" "B.Cu") (net 9))
  (via (at 209.159828 117.567157) (size 0.5) (drill 0.2) (layers "F.Cu" "B.Cu") (net 9))
  (via (at 213.689828 124.891328) (size 0.5) (drill 0.2) (layers "F.Cu" "B.Cu") (net 9))
  (via (at 212.179828 124.891328) (size 0.5) (drill 0.2) (layers "F.Cu" "B.Cu") (net 9))
  (via (at 210.679828 124.891328) (size 0.5) (drill 0.2) (layers "F.Cu" "B.Cu") (net 9))
  (via (at 209.169828 124.891328) (size 0.5) (drill 0.2) (layers "F.Cu" "B.Cu") (net 9))
  (via (at 206.199828 124.921328) (size 0.5) (drill 0.2) (layers "F.Cu" "B.Cu") (net 9))
  (via (at 157.786328 95.620008) (size 0.5) (drill 0.2) (layers "F.Cu" "B.Cu") (net 9))
  (via (at 159.086328 95.620008) (size 0.5) (drill 0.2) (layers "F.Cu" "B.Cu") (net 9))
  (via (at 157.786328 96.620008) (size 0.5) (drill 0.2) (layers "F.Cu" "B.Cu") (net 9))
  (via (at 159.086328 96.620008) (size 0.5) (drill 0.2) (layers "F.Cu" "B.Cu") (net 9))
  (via (at 218.163369 46.897157) (size 0.5) (drill 0.2) (layers "F.Cu" "B.Cu") (net 9))
  (via (at 220.009502 46.897157) (size 0.5) (drill 0.2) (layers "F.Cu" "B.Cu") (net 9))
  (via (at 221.855635 46.897157) (size 0.5) (drill 0.2) (layers "F.Cu" "B.Cu") (net 9))
  (via (at 223.701768 46.897157) (size 0.5) (drill 0.2) (layers "F.Cu" "B.Cu") (net 9))
  (via (at 255.047901 46.897157) (size 0.5) (drill 0.2) (layers "F.Cu" "B.Cu") (net 9))
  (via (at 242.144034 46.897157) (size 0.5) (drill 0.2) (layers "F.Cu" "B.Cu") (net 9))
  (via (at 231.086328 46.897157) (size 0.5) (drill 0.2) (layers "F.Cu" "B.Cu") (net 9))
  (via (at 229.240167 46.897157) (size 0.5) (drill 0.2) (layers "F.Cu" "B.Cu") (net 9))
  (via (at 218.954918 135.197157) (size 0.5) (drill 0.2) (layers "F.Cu" "B.Cu") (net 9))
  (via (at 220.775256 135.197157) (size 0.5) (drill 0.2) (layers "F.Cu" "B.Cu") (net 9))
  (via (at 222.595594 135.197157) (size 0.5) (drill 0.2) (layers "F.Cu" "B.Cu") (net 9))
  (via (at 224.415932 135.197157) (size 0.5) (drill 0.2) (layers "F.Cu" "B.Cu") (net 9))
  (via (at 226.236328 135.197157) (size 0.5) (drill 0.2) (layers "F.Cu" "B.Cu") (net 9))
  (via (at 258.740167 88.667733) (size 0.5) (drill 0.2) (layers "F.Cu" "B.Cu") (net 9))
  (via (at 170.5 82.6445) (size 0.5) (drill 0.2) (layers "F.Cu" "B.Cu") (net 9))
  (via (at 170.636328 103.060008) (size 0.5) (drill 0.2) (layers "F.Cu" "B.Cu") (net 9))
  (via (at 183.636328 101.060008) (size 0.5) (drill 0.2) (layers "F.Cu" "B.Cu") (net 9))
  (via blind (at 185.636328 95.060008) (size 0.5) (drill 0.2) (layers "F.Cu" "In2.Cu") (net 9))
  (via (at 178.467089 87.060008) (size 0.5) (drill 0.2) (layers "F.Cu" "B.Cu") (net 9))
  (via blind (at 185.779682 76.510582) (size 0.5) (drill 0.2) (layers "F.Cu" "In2.Cu") (net 9))
  (via (at 135.836328 80.810008) (size 0.5) (drill 0.2) (layers "F.Cu" "B.Cu") (net 9))
  (via (at 127.586328 82.572859) (size 0.5) (drill 0.2) (layers "F.Cu" "B.Cu") (net 9))
  (via (at 128.586328 82.572859) (size 0.5) (drill 0.2) (layers "F.Cu" "B.Cu") (net 9))
  (via (at 128.586328 84.572859) (size 0.5) (drill 0.2) (layers "F.Cu" "B.Cu") (net 9))
  (via (at 128.586328 86.572859) (size 0.5) (drill 0.2) (layers "F.Cu" "B.Cu") (net 9))
  (via (at 127.086328 87.572859) (size 0.5) (drill 0.2) (layers "F.Cu" "B.Cu") (net 9))
  (via (at 127.086328 83.572859) (size 0.5) (drill 0.2) (layers "F.Cu" "B.Cu") (net 9))
  (via (at 127.586328 86.572859) (size 0.5) (drill 0.2) (layers "F.Cu" "B.Cu") (net 9))
  (via (at 128.086328 83.572859) (size 0.5) (drill 0.2) (layers "F.Cu" "B.Cu") (net 9))
  (via (at 127.586328 84.572859) (size 0.5) (drill 0.2) (layers "F.Cu" "B.Cu") (net 9))
  (via (at 128.086328 85.572859) (size 0.5) (drill 0.2) (layers "F.Cu" "B.Cu") (net 9))
  (via (at 127.086328 85.572859) (size 0.5) (drill 0.2) (layers "F.Cu" "B.Cu") (net 9))
  (via (at 114.936328 79.810008) (size 0.5) (drill 0.2) (layers "F.Cu" "B.Cu") (net 9))
  (via (at 114.936328 81.360008) (size 0.5) (drill 0.2) (layers "F.Cu" "B.Cu") (net 9))
  (via (at 114.936328 82.910008) (size 0.5) (drill 0.2) (layers "F.Cu" "B.Cu") (net 9))
  (via (at 114.336328 79.210008) (size 0.5) (drill 0.2) (layers "F.Cu" "B.Cu") (net 9))
  (via (at 114.336328 80.760008) (size 0.5) (drill 0.2) (layers "F.Cu" "B.Cu") (net 9))
  (via (at 114.336328 82.310008) (size 0.5) (drill 0.2) (layers "F.Cu" "B.Cu") (net 9))
  (via (at 245.786328 56.6) (size 0.5) (drill 0.2) (layers "F.Cu" "B.Cu") (net 9))
  (via (at 193.636328 92.060008) (size 0.5) (drill 0.2) (layers "F.Cu" "B.Cu") (net 9))
  (via (at 162.486328 56.55) (size 0.5) (drill 0.2) (layers "F.Cu" "B.Cu") (net 9))
  (via blind (at 244.936328 61.3) (size 0.5) (drill 0.2) (layers "F.Cu" "In5.Cu") (net 9))
  (via (at 194.636328 88.060008) (size 0.5) (drill 0.2) (layers "F.Cu" "B.Cu") (net 9))
  (via locked (at 155.984758 82.086872) (size 0.5) (drill 0.2) (layers "F.Cu" "B.Cu") (net 9))
  (via locked (at 154.986242 81.058328) (size 0.5) (drill 0.2) (layers "F.Cu" "B.Cu") (net 9))
  (via locked (at 158.236328 78.560008) (size 0.5) (drill 0.2) (layers "F.Cu" "B.Cu") (net 9))
  (via (at 190.607338 102.060008) (size 0.5) (drill 0.2) (layers "F.Cu" "B.Cu") (net 9))
  (via (at 180.636328 93.060008) (size 0.5) (drill 0.2) (layers "F.Cu" "B.Cu") (net 9))
  (via (at 147.686328 89.110008) (size 0.5) (drill 0.2) (layers "F.Cu" "B.Cu") (net 9))
  (via (at 149.186328 88.360008) (size 0.5) (drill 0.2) (layers "F.Cu" "B.Cu") (net 9))
  (via (at 146.186328 89.860008) (size 0.5) (drill 0.2) (layers "F.Cu" "B.Cu") (net 9))
  (via (at 147.686328 90.610008) (size 0.5) (drill 0.2) (layers "F.Cu" "B.Cu") (net 9))
  (via (at 149.186328 89.860008) (size 0.5) (drill 0.2) (layers "F.Cu" "B.Cu") (net 9))
  (via (at 146.186328 91.360008) (size 0.5) (drill 0.2) (layers "F.Cu" "B.Cu") (net 9))
  (via (at 147.686328 92.110008) (size 0.5) (drill 0.2) (layers "F.Cu" "B.Cu") (net 9))
  (via (at 149.186328 91.360008) (size 0.5) (drill 0.2) (layers "F.Cu" "B.Cu") (net 9))
  (via (at 151.788012 46.897157) (size 0.5) (drill 0.2) (layers "F.Cu" "B.Cu") (net 9))
  (via (at 153.638012 46.897157) (size 0.5) (drill 0.2) (layers "F.Cu" "B.Cu") (net 9))
  (via (at 155.488012 46.897157) (size 0.5) (drill 0.2) (layers "F.Cu" "B.Cu") (net 9))
  (via (at 134.15 58.4) (size 0.5) (drill 0.2) (layers "F.Cu" "B.Cu") (net 9))
  (via (at 135.85 58.4) (size 0.5) (drill 0.2) (layers "F.Cu" "B.Cu") (net 9))
  (via (at 145.2 58.35) (size 0.5) (drill 0.2) (layers "F.Cu" "B.Cu") (net 9))
  (via (at 234.5 58.410506) (size 0.5) (drill 0.2) (layers "F.Cu" "B.Cu") (net 9))
  (via (at 236.25 58.4) (size 0.5) (drill 0.2) (layers "F.Cu" "B.Cu") (net 9))
  (via (at 237.85 58.35) (size 0.5) (drill 0.2) (layers "F.Cu" "B.Cu") (net 9))
  (via (at 242.1 58.35) (size 0.5) (drill 0.2) (layers "F.Cu" "B.Cu") (net 9))
  (via (at 126.55 58.35) (size 0.5) (drill 0.2) (layers "F.Cu" "B.Cu") (net 9))
  (via (at 149.75 58.35) (size 0.5) (drill 0.2) (layers "F.Cu" "B.Cu") (net 9))
  (via (at 169.801328 57.660008) (size 0.5) (drill 0.2) (layers "F.Cu" "B.Cu") (net 9))
  (via (at 123.917728 70.524208) (size 0.5) (drill 0.2) (layers "F.Cu" "B.Cu") (net 9))
  (via (at 123.917728 69.355808) (size 0.5) (drill 0.2) (layers "F.Cu" "B.Cu") (net 9))
  (via (at 197.336328 53.531608) (size 0.5) (drill 0.2) (layers "F.Cu" "B.Cu") (net 9))
  (via (at 185.436328 57.494008) (size 0.5) (drill 0.2) (layers "F.Cu" "B.Cu") (net 9))
  (via (at 195.520128 57.468608) (size 0.5) (drill 0.2) (layers "F.Cu" "B.Cu") (net 9))
  (via (at 115.436328 91.890008) (size 0.5) (drill 0.2) (layers "F.Cu" "B.Cu") (net 9))
  (via (at 148.499328 123.102008) (size 0.5) (drill 0.2) (layers "F.Cu" "B.Cu") (net 9))
  (via (at 147.799328 123.102008) (size 0.5) (drill 0.2) (layers "F.Cu" "B.Cu") (net 9))
  (via (at 147.099328 123.102008) (size 0.5) (drill 0.2) (layers "F.Cu" "B.Cu") (net 9))
  (via (at 146.399328 123.102008) (size 0.5) (drill 0.2) (layers "F.Cu" "B.Cu") (net 9))
  (via (at 155.549328 112.977007) (size 0.5) (drill 0.2) (layers "F.Cu" "B.Cu") (net 9))
  (via (at 150.799328 118.102008) (size 0.5) (drill 0.2) (layers "F.Cu" "B.Cu") (net 9))
  (via (at 150.799328 118.702008) (size 0.5) (drill 0.2) (layers "F.Cu" "B.Cu") (net 9))
  (via (at 150.799328 119.302008) (size 0.5) (drill 0.2) (layers "F.Cu" "B.Cu") (net 9))
  (via (at 151.299328 119.702008) (size 0.5) (drill 0.2) (layers "F.Cu" "B.Cu") (net 9))
  (via (at 151.899328 119.702008) (size 0.5) (drill 0.2) (layers "F.Cu" "B.Cu") (net 9))
  (via (at 152.499328 119.702008) (size 0.5) (drill 0.2) (layers "F.Cu" "B.Cu") (net 9))
  (via (at 156.299328 117.402008) (size 0.5) (drill 0.2) (layers "F.Cu" "B.Cu") (net 9))
  (via (at 155.699328 117.102008) (size 0.5) (drill 0.2) (layers "F.Cu" "B.Cu") (net 9))
  (via (at 156.299328 116.702008) (size 0.5) (drill 0.2) (layers "F.Cu" "B.Cu") (net 9))
  (via (at 155.699328 116.402008) (size 0.5) (drill 0.2) (layers "F.Cu" "B.Cu") (net 9))
  (via (at 129.661328 93.210008) (size 0.5) (drill 0.2) (layers "F.Cu" "B.Cu") (net 9))
  (via (at 129.661328 94.060008) (size 0.5) (drill 0.2) (layers "F.Cu" "B.Cu") (net 9))
  (via (at 130.761328 91.040008) (size 0.5) (drill 0.2) (layers "F.Cu" "B.Cu") (net 9))
  (via (at 144.125 81.625) (size 0.5) (drill 0.2) (layers "F.Cu" "B.Cu") (net 9))
  (via (at 144.75 81.625) (size 0.5) (drill 0.2) (layers "F.Cu" "B.Cu") (net 9))
  (via (at 143.461328 84.610008) (size 0.5) (drill 0.2) (layers "F.Cu" "B.Cu") (net 9))
  (via (at 143.461328 85.610008) (size 0.5) (drill 0.2) (layers "F.Cu" "B.Cu") (net 9))
  (via (at 143.461328 86.610008) (size 0.5) (drill 0.2) (layers "F.Cu" "B.Cu") (net 9))
  (via (at 143.461328 87.610008) (size 0.5) (drill 0.2) (layers "F.Cu" "B.Cu") (net 9))
  (via (at 143.461328 88.610008) (size 0.5) (drill 0.2) (layers "F.Cu" "B.Cu") (net 9))
  (via (at 135.836328 81.810008) (size 0.5) (drill 0.2) (layers "F.Cu" "B.Cu") (net 9))
  (via (at 135.836328 82.810008) (size 0.5) (drill 0.2) (layers "F.Cu" "B.Cu") (net 9))
  (via (at 135.836328 83.810008) (size 0.5) (drill 0.2) (layers "F.Cu" "B.Cu") (net 9))
  (via (at 135.836328 84.810008) (size 0.5) (drill 0.2) (layers "F.Cu" "B.Cu") (net 9))
  (via (at 135.836328 85.810008) (size 0.5) (drill 0.2) (layers "F.Cu" "B.Cu") (net 9))
  (via (at 135.836328 86.810008) (size 0.5) (drill 0.2) (layers "F.Cu" "B.Cu") (net 9))
  (via (at 135.786328 88.335008) (size 0.5) (drill 0.2) (layers "F.Cu" "B.Cu") (net 9))
  (via (at 115.525 105.54) (size 0.5) (drill 0.2) (layers "F.Cu" "B.Cu") (net 9))
  (via (at 116.125 105.54) (size 0.5) (drill 0.2) (layers "F.Cu" "B.Cu") (net 9))
  (via (at 114.9 105.54) (size 0.5) (drill 0.2) (layers "F.Cu" "B.Cu") (net 9))
  (via (at 112.916328 110.310008) (size 0.5) (drill 0.2) (layers "F.Cu" "B.Cu") (net 9))
  (via (at 112.916328 110.860008) (size 0.5) (drill 0.2) (layers "F.Cu" "B.Cu") (net 9))
  (via (at 112.396328 110.590008) (size 0.5) (drill 0.2) (layers "F.Cu" "B.Cu") (net 9))
  (via (at 121.159104 108.617157) (size 0.5) (drill 0.2) (layers "F.Cu" "B.Cu") (net 9))
  (via (at 121.797992 108.617157) (size 0.5) (drill 0.2) (layers "F.Cu" "B.Cu") (net 9))
  (via (at 122.43688 108.617157) (size 0.5) (drill 0.2) (layers "F.Cu" "B.Cu") (net 9))
  (via (at 123.714656 108.617157) (size 0.5) (drill 0.2) (layers "F.Cu" "B.Cu") (net 9))
  (via (at 123.075768 108.617157) (size 0.5) (drill 0.2) (layers "F.Cu" "B.Cu") (net 9))
  (via (at 218.75 62.95) (size 0.5) (drill 0.2) (layers "F.Cu" "B.Cu") (net 9))
  (via (at 235.5 105.7) (size 0.5) (drill 0.2) (layers "F.Cu" "B.Cu") (net 9))
  (via (at 243.9 76) (size 0.5) (drill 0.2) (layers "F.Cu" "B.Cu") (net 9))
  (via (at 242.55 123.54) (size 0.5) (drill 0.2) (layers "F.Cu" "B.Cu") (net 9))
  (via (at 127.55 66.5) (size 0.5) (drill 0.2) (layers "F.Cu" "B.Cu") (net 9))
  (via (at 253.6 96.15) (size 0.5) (drill 0.2) (layers "F.Cu" "B.Cu") (net 9))
  (via (at 156.55 53.8) (size 0.5) (drill 0.2) (layers "F.Cu" "B.Cu") (net 9))
  (via (at 258.740167 90.354007) (size 0.5) (drill 0.2) (layers "F.Cu" "B.Cu") (net 9))
  (via (at 222.05 100.95) (size 0.5) (drill 0.2) (layers "F.Cu" "B.Cu") (net 9))
  (via (at 253.56 103.8) (size 0.5) (drill 0.2) (layers "F.Cu" "B.Cu") (net 9))
  (via (at 248.45 108.9) (size 0.5) (drill 0.2) (layers "F.Cu" "B.Cu") (net 9))
  (via (at 107.936328 55.554017) (size 0.5) (drill 0.2) (layers "F.Cu" "B.Cu") (net 9))
  (via (at 160.425 102.8) (size 0.5) (drill 0.2) (layers "F.Cu" "B.Cu") (net 9))
  (via (at 133 117.9) (size 0.5) (drill 0.2) (layers "F.Cu" "B.Cu") (net 9))
  (via (at 248.236328 135.197157) (size 0.5) (drill 0.2) (layers "F.Cu" "B.Cu") (net 9))
  (via (at 134.211328 84.610008) (size 0.5) (drill 0.2) (layers "F.Cu" "B.Cu") (net 9))
  (via (at 199.5 75.2) (size 0.5) (drill 0.2) (layers "F.Cu" "B.Cu") (net 9))
  (via (at 138.954964 46.897157) (size 0.5) (drill 0.2) (layers "F.Cu" "B.Cu") (net 9))
  (via (at 251 93.6) (size 0.5) (drill 0.2) (layers "F.Cu" "B.Cu") (net 9))
  (via blind (at 141.236328 61.610008) (size 0.5) (drill 0.2) (layers "F.Cu" "In2.Cu") (net 9))
  (via (at 156.41 111.53) (size 0.5) (drill 0.2) (layers "F.Cu" "B.Cu") (net 9))
  (via (at 143.136328 114.137157) (size 0.5) (drill 0.2) (layers "F.Cu" "B.Cu") (net 9))
  (via (at 161.910002 111.53) (size 0.5) (drill 0.2) (layers "F.Cu" "B.Cu") (net 9))
  (via blind (at 195.636328 103.060008) (size 0.5) (drill 0.2) (layers "F.Cu" "In2.Cu") (net 9))
  (via (at 151.2 58.35) (size 0.5) (drill 0.2) (layers "F.Cu" "B.Cu") (net 9))
  (via (at 119.9 67.2) (size 0.5) (drill 0.2) (layers "F.Cu" "B.Cu") (net 9))
  (via (at 189.9 114.1) (size 0.5) (drill 0.2) (layers "F.Cu" "B.Cu") (free) (net 9))
  (via (at 203.5 61.6) (size 0.5) (drill 0.2) (layers "F.Cu" "B.Cu") (net 9))
  (via (at 199.721103 46.897157) (size 0.5) (drill 0.2) (layers "F.Cu" "B.Cu") (net 9))
  (via (at 210.797901 46.897157) (size 0.5) (drill 0.2) (layers "F.Cu" "B.Cu") (net 9))
  (via blind (at 196.636328 103.060008) (size 0.5) (drill 0.2) (layers "F.Cu" "In2.Cu") (net 9))
  (via (at 131.446328 95.650008) (size 0.5) (drill 0.2) (layers "F.Cu" "B.Cu") (net 9))
  (via (at 202.436328 53.813672) (size 0.5) (drill 0.2) (layers "F.Cu" "B.Cu") (net 9))
  (via (at 202.1 58.4) (size 0.5) (drill 0.2) (layers "F.Cu" "B.Cu") (net 9))
  (via (at 146.1 127) (size 0.5) (drill 0.2) (layers "F.Cu" "B.Cu") (net 9))
  (via (at 240.4 105.8) (size 0.5) (drill 0.2) (layers "F.Cu" "B.Cu") (net 9))
  (via (at 190.636328 96.060008) (size 0.5) (drill 0.2) (layers "F.Cu" "B.Cu") (net 9))
  (via (at 111.190008 64.160008) (size 0.5) (drill 0.2) (layers "F.Cu" "B.Cu") (net 9))
  (via (at 120.578694 135.197157) (size 0.5) (drill 0.2) (layers "F.Cu" "B.Cu") (net 9))
  (via (at 107.936328 48.628529) (size 0.5) (drill 0.2) (layers "F.Cu" "B.Cu") (net 9))
  (via (at 166.236328 92.910008) (size 0.5) (drill 0.2) (layers "F.Cu" "B.Cu") (net 9))
  (via (at 239.9 121.2) (size 0.5) (drill 0.2) (layers "F.Cu" "B.Cu") (net 9))
  (via blind (at 235.6 61.35) (size 0.5) (drill 0.2) (layers "F.Cu" "In2.Cu") (net 9))
  (via (at 136.084324 129.875) (size 0.5) (drill 0.2) (layers "F.Cu" "B.Cu") (net 9))
  (via (at 107.936328 60.748133) (size 0.5) (drill 0.2) (layers "F.Cu" "B.Cu") (net 9))
  (via (at 190.5 111.1) (size 0.5) (drill 0.2) (layers "F.Cu" "B.Cu") (free) (net 9))
  (via (at 124.3109 46.897157) (size 0.5) (drill 0.2) (layers "F.Cu" "B.Cu") (net 9))
  (via (at 132 116) (size 0.5) (drill 0.2) (layers "F.Cu" "B.Cu") (net 9))
  (via (at 186.636328 94.060008) (size 0.5) (drill 0.2) (layers "F.Cu" "B.Cu") (net 9))
  (via (at 239.9 122.7) (size 0.5) (drill 0.2) (layers "F.Cu" "B.Cu") (net 9))
  (via (at 253.53 116.52) (size 0.5) (drill 0.2) (layers "F.Cu" "B.Cu") (net 9))
  (via (at 207.954918 135.197157) (size 0.5) (drill 0.2) (layers "F.Cu" "B.Cu") (free) (net 9))
  (via (at 162.004 77.687) (size 0.5) (drill 0.2) (layers "F.Cu" "B.Cu") (net 9))
  (via (at 107.936328 64.210877) (size 0.5) (drill 0.2) (layers "F.Cu" "B.Cu") (net 9))
  (via (at 109.666836 46.897157) (size 0.5) (drill 0.2) (layers "F.Cu" "B.Cu") (net 9))
  (via (at 107.936328 102.301061) (size 0.5) (drill 0.2) (layers "F.Cu" "B.Cu") (net 9))
  (via (at 247.18 83.48) (size 0.5) (drill 0.2) (layers "F.Cu" "B.Cu") (net 9))
  (via (at 120.75 103.125) (size 0.5) (drill 0.2) (layers "F.Cu" "B.Cu") (net 9))
  (via (at 167.907482 135.197157) (size 0.5) (drill 0.2) (layers "F.Cu" "B.Cu") (net 9))
  (via (at 212.85 61.6) (size 0.5) (drill 0.2) (layers "F.Cu" "B.Cu") (net 9))
  (via (at 175.636328 98.060008) (size 0.5) (drill 0.2) (layers "F.Cu" "B.Cu") (net 9))
  (via (at 181.636328 61.910008) (size 0.5) (drill 0.2) (layers "F.Cu" "B.Cu") (net 9))
  (via (at 133.9 124.575) (size 0.5) (drill 0.2) (layers "F.Cu" "B.Cu") (free) (net 9))
  (via (at 124.85 58.35) (size 0.5) (drill 0.2) (layers "F.Cu" "B.Cu") (net 9))
  (via (at 107.936328 76.330481) (size 0.5) (drill 0.2) (layers "F.Cu" "B.Cu") (net 9))
  (via (at 114.411328 92.997157) (size 0.5) (drill 0.2) (layers "F.Cu" "B.Cu") (net 9))
  (via (at 224.972 119.541) (size 0.5) (drill 0.2) (layers "F.Cu" "B.Cu") (net 9))
  (via (at 251.1 97.4) (size 0.5) (drill 0.2) (layers "F.Cu" "B.Cu") (net 9))
  (via (at 143.786328 53.813672) (size 0.5) (drill 0.2) (layers "F.Cu" "B.Cu") (net 9))
  (via (at 255.367619 73.491267) (size 0.5) (drill 0.2) (layers "F.Cu" "B.Cu") (net 9))
  (via (at 238.86 80.41) (size 0.5) (drill 0.2) (layers "F.Cu" "B.Cu") (net 9))
  (via (at 247.18 94.91) (size 0.5) (drill 0.2) (layers "F.Cu" "B.Cu") (net 9))
  (via (at 158.72 110.53) (size 0.5) (drill 0.2) (layers "F.Cu" "B.Cu") (net 9))
  (via (at 191.655836 82.060008) (size 0.5) (drill 0.2) (layers "F.Cu" "B.Cu") (net 9))
  (via (at 258.740167 51.569705) (size 0.5) (drill 0.2) (layers "F.Cu" "B.Cu") (net 9))
  (via (at 154.549831 58.410509) (size 0.5) (drill 0.2) (layers "F.Cu" "B.Cu") (net 9))
  (via (at 178.82951 135.197157) (size 0.5) (drill 0.2) (layers "F.Cu" "B.Cu") (free) (net 9))
  (via (at 256.1 80.9) (size 0.5) (drill 0.2) (layers "F.Cu" "B.Cu") (net 9))
  (via blind (at 199.886328 61.3) (size 0.5) (drill 0.2) (layers "F.Cu" "In5.Cu") (net 9))
  (via (at 190.7 82.05) (size 0.5) (drill 0.2) (layers "F.Cu" "B.Cu") (net 9))
  (via (at 202.3 66.05) (size 0.5) (drill 0.2) (layers "F.Cu" "B.Cu") (net 9))
  (via (at 227.1 62.55) (size 0.5) (drill 0.2) (layers "F.Cu" "B.Cu") (net 9))
  (via (at 256.1 75.82) (size 0.5) (drill 0.2) (layers "F.Cu" "B.Cu") (net 9))
  (via (at 251.355635 46.897157) (size 0.5) (drill 0.2) (layers "F.Cu" "B.Cu") (net 9))
  (via (at 138.75 97.5) (size 0.5) (drill 0.2) (layers "F.Cu" "B.Cu") (net 9))
  (via (at 247.18 106.34) (size 0.5) (drill 0.2) (layers "F.Cu" "B.Cu") (net 9))
  (via (at 115.411328 92.997157) (size 0.5) (drill 0.2) (layers "F.Cu" "B.Cu") (net 9))
  (via (at 122.480392 46.897157) (size 0.5) (drill 0.2) (layers "F.Cu" "B.Cu") (net 9))
  (via (at 258.740167 124.079487) (size 0.5) (drill 0.2) (layers "F.Cu" "B.Cu") (net 9))
  (via (at 228.13458 135.197157) (size 0.5) (drill 0.2) (layers "F.Cu" "B.Cu") (net 9))
  (via (at 242.75 81.45) (size 0.5) (drill 0.2) (layers "F.Cu" "B.Cu") (net 9))
  (via (at 156.16 105.7695) (size 0.5) (drill 0.2) (layers "F.Cu" "B.Cu") (net 9))
  (via (at 170.136328 61.010008) (size 0.5) (drill 0.2) (layers "F.Cu" "B.Cu") (net 9))
  (via (at 245.91 97.47) (size 0.5) (drill 0.2) (layers "F.Cu" "B.Cu") (net 9))
  (via (at 166.65 116.3) (size 0.5) (drill 0.2) (layers "F.Cu" "B.Cu") (net 9))
  (via (at 258.740167 115.648117) (size 0.5) (drill 0.2) (layers "F.Cu" "B.Cu") (net 9))
  (via (at 259.2415 81.922637) (size 0.5) (drill 0.2) (layers "F.Cu" "B.Cu") (net 9))
  (via (at 167.85 110.25) (size 0.5) (drill 0.2) (layers "F.Cu" "B.Cu") (net 9))
  (via (at 239.9 114.8) (size 0.5) (drill 0.2) (layers "F.Cu" "B.Cu") (net 9))
  (via (at 199.2 111.9) (size 0.5) (drill 0.2) (layers "F.Cu" "B.Cu") (net 9))
  (via (at 187.636328 101.060008) (size 0.5) (drill 0.2) (layers "F.Cu" "B.Cu") (net 9))
  (via (at 220.787 114.01) (size 0.5) (drill 0.2) (layers "F.Cu" "B.Cu") (net 9))
  (via (at 123.606328 105.890008) (size 0.5) (drill 0.2) (layers "F.Cu" "B.Cu") (net 9))
  (via (at 259.05 103.844199) (size 0.5) (drill 0.2) (layers "F.Cu" "B.Cu") (net 9))
  (via (at 259.1 73.491267) (size 0.5) (drill 0.2) (layers "F.Cu" "B.Cu") (net 9))
  (via (at 118.776328 60.240008) (size 0.5) (drill 0.2) (layers "F.Cu" "B.Cu") (net 9))
  (via (at 247.18 113.96) (size 0.5) (drill 0.2) (layers "F.Cu" "B.Cu") (net 9))
  (via (at 188.644305 46.897157) (size 0.5) (drill 0.2) (layers "F.Cu" "B.Cu") (net 9))
  (via (at 196.655836 77.060008) (size 0.5) (drill 0.2) (layers "F.Cu" "B.Cu") (net 9))
  (via (at 242.77 77.46) (size 0.5) (drill 0.2) (layers "F.Cu" "B.Cu") (net 9))
  (via (at 186.636328 92.060008) (size 0.5) (drill 0.2) (layers "F.Cu" "B.Cu") (net 9))
  (via (at 141.275 128.7) (size 0.5) (drill 0.2) (layers "F.Cu" "B.Cu") (net 9))
  (via (at 139.45 133.025) (size 0.5) (drill 0.2) (layers "F.Cu" "B.Cu") (net 9))
  (via (at 135.011328 85.285008) (size 0.5) (drill 0.2) (layers "F.Cu" "B.Cu") (net 9))
  (via (at 157.75 61.55) (size 0.5) (drill 0.2) (layers "F.Cu" "B.Cu") (net 9))
  (via (at 247.446369 117.8005) (size 0.5) (drill 0.2) (layers "F.Cu" "B.Cu") (net 9))
  (via (at 168.73 110.23) (size 0.5) (drill 0.2) (layers "F.Cu" "B.Cu") (net 9))
  (via (at 107.936328 109.226549) (size 0.5) (drill 0.2) (layers "F.Cu" "B.Cu") (net 9))
  (via (at 239.85 53.8) (size 0.5) (drill 0.2) (layers "F.Cu" "B.Cu") (net 9))
  (via (at 126.775 100.997157) (size 0.5) (drill 0.2) (layers "F.Cu" "B.Cu") (net 9))
  (via (at 253.56 108.88) (size 0.5) (drill 0.2) (layers "F.Cu" "B.Cu") (net 9))
  (via (at 154.525 102.8) (size 0.5) (drill 0.2) (layers "F.Cu" "B.Cu") (net 9))
  (via (at 107.936328 78.061853) (size 0.5) (drill 0.2) (layers "F.Cu" "B.Cu") (net 9))
  (via (at 208.386328 53.813672) (size 0.5) (drill 0.2) (layers "F.Cu" "B.Cu") (net 9))
  (via (at 183.636328 94.060008) (size 0.5) (drill 0.2) (layers "F.Cu" "B.Cu") (net 9))
  (via blind (at 209.236328 61.15) (size 0.5) (drill 0.2) (layers "F.Cu" "In2.Cu") (net 9))
  (via (at 132.838986 128.15) (size 0.5) (drill 0.2) (layers "F.Cu" "B.Cu") (net 9))
  (via (at 112.25 102.375) (size 0.5) (drill 0.2) (layers "F.Cu" "B.Cu") (net 9))
  (via (at 163.05 70.3) (size 0.5) (drill 0.2) (layers "F.Cu" "B.Cu") (net 9))
  (via (at 256.1 113.96) (size 0.5) (drill 0.2) (layers "F.Cu" "B.Cu") (net 9))
  (via (at 217.6 105.75) (size 0.5) (drill 0.2) (layers "F.Cu" "B.Cu") (net 9))
  (via (at 154.85 56.7) (size 0.5) (drill 0.2) (layers "F.Cu" "B.Cu") (net 9))
  (via (at 107.936328 114.420665) (size 0.5) (drill 0.2) (layers "F.Cu" "B.Cu") (net 9))
  (via (at 173.368496 135.197157) (size 0.5) (drill 0.2) (layers "F.Cu" "B.Cu") (free) (net 9))
  (via (at 151.52444 135.197157) (size 0.5) (drill 0.2) (layers "F.Cu" "B.Cu") (net 9))
  (via (at 177.615828 83.060007) (size 0.5) (drill 0.2) (layers "F.Cu" "B.Cu") (net 9))
  (via (at 245.91 82.23) (size 0.5) (drill 0.2) (layers "F.Cu" "B.Cu") (net 9))
  (via (at 251 115.25) (size 0.5) (drill 0.2) (layers "F.Cu" "B.Cu") (net 9))
  (via (at 114.411328 91.872157) (size 0.5) (drill 0.2) (layers "F.Cu" "B.Cu") (net 9))
  (via (at 137.536328 116.247157) (size 0.5) (drill 0.2) (layers "F.Cu" "B.Cu") (net 9))
  (via (at 220.304904 89.05) (size 0.5) (drill 0.2) (layers "F.Cu" "B.Cu") (net 9))
  (via (at 239.13458 135.197157) (size 0.5) (drill 0.2) (layers "F.Cu" "B.Cu") (net 9))
  (via (at 158.303139 57.210837) (size 0.5) (drill 0.2) (layers "F.Cu" "B.Cu") (net 9))
  (via (at 132.826328 107.397157) (size 0.5) (drill 0.2) (layers "F.Cu" "B.Cu") (net 9))
  (via (at 190.5 112.9) (size 0.5) (drill 0.2) (layers "F.Cu" "B.Cu") (free) (net 9))
  (via (at 153.136328 56.7) (size 0.5) (drill 0.2) (layers "F.Cu" "B.Cu") (net 9))
  (via (at 234.75 56.45) (size 0.5) (drill 0.2) (layers "F.Cu" "B.Cu") (net 9))
  (via (at 240.297901 46.897157) (size 0.5) (drill 0.2) (layers "F.Cu" "B.Cu") (net 9))
  (via (at 122.399032 135.197157) (size 0.5) (drill 0.2) (layers "F.Cu" "B.Cu") (net 9))
  (via (at 211.595594 135.197157) (size 0.5) (drill 0.2) (layers "F.Cu" "B.Cu") (net 9))
  (via (at 179.636328 79.0405) (size 0.5) (drill 0.2) (layers "F.Cu" "B.Cu") (net 9))
  (via (at 132.225 103.175) (size 0.5) (drill 0.2) (layers "F.Cu" "B.Cu") (net 9))
  (via (at 217.736328 53.813672) (size 0.5) (drill 0.2) (layers "F.Cu" "B.Cu") (net 9))
  (via (at 248.45 101.28) (size 0.5) (drill 0.2) (layers "F.Cu" "B.Cu") (net 9))
  (via (at 232.5 125.8) (size 0.5) (drill 0.2) (layers "F.Cu" "B.Cu") (net 9))
  (via (at 203.413369 46.897157) (size 0.5) (drill 0.2) (layers "F.Cu" "B.Cu") (net 9))
  (via (at 257.54 95.1205) (size 0.5) (drill 0.2) (layers "F.Cu" "B.Cu") (net 9))
  (via (at 107.936328 74.599109) (size 0.5) (drill 0.2) (layers "F.Cu" "B.Cu") (net 9))
  (via (at 253.53 124.18) (size 0.5) (drill 0.2) (layers "F.Cu" "B.Cu") (net 9))
  (via (at 258.740167 58.314801) (size 0.5) (drill 0.2) (layers "F.Cu" "B.Cu") (net 9))
  (via (at 137.286328 113.997157) (size 0.5) (drill 0.2) (layers "F.Cu" "B.Cu") (net 9))
  (via (at 243.37 93.66) (size 0.5) (drill 0.2) (layers "F.Cu" "B.Cu") (net 9))
  (via (at 189.9 112.9) (size 0.5) (drill 0.2) (layers "F.Cu" "B.Cu") (free) (net 9))
  (via (at 196.028837 46.897157) (size 0.5) (drill 0.2) (layers "F.Cu" "B.Cu") (net 9))
  (via (at 164.186328 53.710008) (size 0.5) (drill 0.2) (layers "F.Cu" "B.Cu") (net 9))
  (via (at 182.886328 53.531608) (size 0.5) (drill 0.2) (layers "F.Cu" "B.Cu") (net 9))
  (via (at 176.636328 91.060008) (size 0.5) (drill 0.2) (layers "F.Cu" "B.Cu") (net 9))
  (via (at 109.656666 135.197157) (size 0.5) (drill 0.2) (layers "F.Cu" "B.Cu") (net 9))
  (via (at 253.681345 73.491267) (size 0.5) (drill 0.2) (layers "F.Cu" "B.Cu") (net 9))
  (via (at 120.626328 53.670008) (size 0.5) (drill 0.2) (layers "F.Cu" "B.Cu") (net 9))
  (via (at 208.1 58.35) (size 0.5) (drill 0.2) (layers "F.Cu" "B.Cu") (net 9))
  (via (at 134.45 53.8) (size 0.5) (drill 0.2) (layers "F.Cu" "B.Cu") (net 9))
  (via (at 138.15 56.6) (size 0.5) (drill 0.2) (layers "F.Cu" "B.Cu") (net 9))
  (via (at 257.6 70.5) (size 0.5) (drill 0.2) (layers "F.Cu" "B.Cu") (net 9))
  (via (at 227.35 65.65) (size 0.5) (drill 0.2) (layers "F.Cu" "B.Cu") (net 9))
  (via (at 220.675 126.375) (size 0.5) (drill 0.2) (layers "F.Cu" "B.Cu") (net 9))
  (via (at 246 127.55) (size 0.5) (drill 0.2) (layers "F.Cu" "B.Cu") (free) (net 9))
  (via (at 149.8 127) (size 0.5) (drill 0.2) (layers "F.Cu" "B.Cu") (net 9))
  (via (at 107.936328 53.822645) (size 0.5) (drill 0.2) (layers "F.Cu" "B.Cu") (net 9))
  (via (at 206.7 53.8) (size 0.5) (drill 0.2) (layers "F.Cu" "B.Cu") (net 9))
  (via (at 147.536831 56.633051) (size 0.5) (drill 0.2) (layers "F.Cu" "B.Cu") (net 9))
  (via (at 159.41 111.53) (size 0.5) (drill 0.2) (layers "F.Cu" "B.Cu") (net 9))
  (via (at 248.31 73.52) (size 0.5) (drill 0.2) (layers "F.Cu" "B.Cu") (net 9))
  (via (at 193.392214 135.197157) (size 0.5) (drill 0.2) (layers "F.Cu" "B.Cu") (net 9))
  (via (at 196.636328 101.060008) (size 0.5) (drill 0.2) (layers "F.Cu" "B.Cu") (net 9))
  (via (at 171.548158 135.197157) (size 0.5) (drill 0.2) (layers "F.Cu" "B.Cu") (net 9))
  (via (at 190.636328 94.060008) (size 0.5) (drill 0.2) (layers "F.Cu" "B.Cu") (net 9))
  (via (at 164 101.45) (size 0.5) (drill 0.2) (layers "F.Cu" "B.Cu") (net 9))
  (via (at 145.5 53.8) (size 0.5) (drill 0.2) (layers "F.Cu" "B.Cu") (net 9))
  (via (at 157.3165 57.209955) (size 0.5) (drill 0.2) (layers "F.Cu" "B.Cu") (net 9))
  (via (at 245.91 108.9) (size 0.5) (drill 0.2) (layers "F.Cu" "B.Cu") (net 9))
  (via (at 186.636328 91.060008) (size 0.5) (drill 0.2) (layers "F.Cu" "B.Cu") (net 9))
  (via (at 244.64 83.48) (size 0.5) (drill 0.2) (layers "F.Cu" "B.Cu") (net 9))
  (via (at 234.55 86.475) (size 0.5) (drill 0.2) (layers "F.Cu" "B.Cu") (net 9))
  (via (at 248.45 97.47) (size 0.5) (drill 0.2) (layers "F.Cu" "B.Cu") (net 9))
  (via (at 253.53 86.04) (size 0.5) (drill 0.2) (layers "F.Cu" "B.Cu") (net 9))
  (via (at 193.086328 53.531608) (size 0.5) (drill 0.2) (layers "F.Cu" "B.Cu") (net 9))
  (via (at 252.2 103.85) (size 0.5) (drill 0.2) (layers "F.Cu" "B.Cu") (net 9))
  (via (at 209.7 58.35) (size 0.5) (drill 0.2) (layers "F.Cu" "B.Cu") (net 9))
  (via (at 258.740167 92.040281) (size 0.5) (drill 0.2) (layers "F.Cu" "B.Cu") (net 9))
  (via (at 253.5 102.475) (size 0.5) (drill 0.2) (layers "F.Cu" "B.Cu") (net 9))
  (via (at 166.490709 46.897157) (size 0.5) (drill 0.2) (layers "F.Cu" "B.Cu") (net 9))
  (via (at 107.936328 67.673621) (size 0.5) (drill 0.2) (layers "F.Cu" "B.Cu") (net 9))
  (via (at 206.399543 58.35) (size 0.5) (drill 0.2) (layers "F.Cu" "B.Cu") (net 9))
  (via (at 248.425 121.6) (size 0.5) (drill 0.2) (layers "F.Cu" "B.Cu") (net 9))
  (via (at 212.125 100.95) (size 0.5) (drill 0.2) (layers "F.Cu" "B.Cu") (net 9))
  (via (at 212.545984 57.203492) (size 0.5) (drill 0.2) (layers "F.Cu" "B.Cu") (net 9))
  (via (at 226 109) (size 0.5) (drill 0.2) (layers "F.Cu" "B.Cu") (net 9))
  (via blind (at 227.936328 61.610008) (size 0.5) (drill 0.2) (layers "F.Cu" "In2.Cu") (net 9))
  (via (at 187.636328 93.060008) (size 0.5) (drill 0.2) (layers "F.Cu" "B.Cu") (net 9))
  (via (at 181.636328 87.060008) (size 0.5) (drill 0.2) (layers "F.Cu" "B.Cu") (net 9))
  (via (at 178.636328 97.060008) (size 0.5) (drill 0.2) (layers "F.Cu" "B.Cu") (net 9))
  (via (at 244.64 110.15) (size 0.5) (drill 0.2) (layers "F.Cu" "B.Cu") (net 9))
  (via (at 244.086328 53.813672) (size 0.5) (drill 0.2) (layers "F.Cu" "B.Cu") (net 9))
  (via (at 153.180968 80.027158) (size 0.5) (drill 0.2) (layers "F.Cu" "B.Cu") (net 9))
  (via (at 132.736328 103.757157) (size 0.5) (drill 0.2) (layers "F.Cu" "B.Cu") (net 9))
  (via (at 220.8 58.4) (size 0.5) (drill 0.2) (layers "F.Cu" "B.Cu") (net 9))
  (via (at 187.78 80.06) (size 0.5) (drill 0.2) (layers "F.Cu" "B.Cu") (net 9))
  (via (at 163.6 102.78) (size 0.5) (drill 0.2) (layers "F.Cu" "B.Cu") (net 9))
  (via (at 174.386328 53.710008) (size 0.5) (drill 0.2) (layers "F.Cu" "B.Cu") (net 9))
  (via (at 208.386328 57.010008) (size 0.5) (drill 0.2) (layers "F.Cu" "B.Cu") (net 9))
  (via (at 251.975 89.825) (size 0.5) (drill 0.2) (layers "F.Cu" "B.Cu") (net 9))
  (via (at 139.526328 99.757157) (size 0.5) (drill 0.2) (layers "F.Cu" "B.Cu") (net 9))
  (via blind (at 190.6235 101.05) (size 0.5) (drill 0.2) (layers "F.Cu" "In2.Cu") (net 9))
  (via (at 234.1 103.4) (size 0.5) (drill 0.2) (layers "F.Cu" "B.Cu") (net 9))
  (via (at 135.55 110.65) (size 0.5) (drill 0.2) (layers "F.Cu" "B.Cu") (net 9))
  (via (at 253.56 113.96) (size 0.5) (drill 0.2) (layers "F.Cu" "B.Cu") (net 9))
  (via (at 140 79.25) (size 0.5) (drill 0.2) (layers "F.Cu" "B.Cu") (net 9))
  (via (at 234.05 80.5) (size 0.5) (drill 0.2) (layers "F.Cu" "B.Cu") (net 9))
  (via (at 188.636328 92.060008) (size 0.5) (drill 0.2) (layers "F.Cu" "B.Cu") (net 9))
  (via (at 118.819376 46.897157) (size 0.5) (drill 0.2) (layers "F.Cu" "B.Cu") (net 9))
  (via (at 242.725 83.45) (size 0.5) (drill 0.2) (layers "F.Cu" "B.Cu") (net 9))
  (via (at 256.894034 46.897157) (size 0.5) (drill 0.2) (layers "F.Cu" "B.Cu") (net 9))
  (via (at 213.415932 135.197157) (size 0.5) (drill 0.2) (layers "F.Cu" "B.Cu") (net 9))
  (via (at 238.7 82.45) (size 0.5) (drill 0.2) (layers "F.Cu" "B.Cu") (net 9))
  (via (at 128.875 129.375) (size 0.5) (drill 0.2) (layers "F.Cu" "B.Cu") (net 9))
  (via (at 186.636328 98.060008) (size 0.5) (drill 0.2) (layers "F.Cu" "B.Cu") (net 9))
  (via (at 258.740167 130.824583) (size 0.5) (drill 0.2) (layers "F.Cu" "B.Cu") (net 9))
  (via (at 259.2415 83.572289) (size 0.5) (drill 0.2) (layers "F.Cu" "B.Cu") (net 9))
  (via (at 246.5 127.1) (size 0.5) (drill 0.2) (layers "F.Cu" "B.Cu") (free) (net 9))
  (via (at 141.275 124.475) (size 0.5) (drill 0.2) (layers "F.Cu" "B.Cu") (net 9))
  (via (at 107.936328 100.569689) (size 0.5) (drill 0.2) (layers "F.Cu" "B.Cu") (net 9))
  (via (at 245.91 89.85) (size 0.5) (drill 0.2) (layers "F.Cu" "B.Cu") (net 9))
  (via (at 221.35 104.7) (size 0.5) (drill 0.2) (layers "F.Cu" "B.Cu") (net 9))
  (via (at 252.3 110.125) (size 0.5) (drill 0.2) (layers "F.Cu" "B.Cu") (net 9))
  (via (at 143.461328 81.610008) (size 0.5) (drill 0.2) (layers "F.Cu" "B.Cu") (net 9))
  (via (at 138.561328 92.635008) (size 0.5) (drill 0.2) (layers "F.Cu" "B.Cu") (net 9))
  (via blind (at 161.636328 61.35) (size 0.5) (drill 0.2) (layers "F.Cu" "In2.Cu") (net 9))
  (via (at 172.61 78.06) (size 0.5) (drill 0.2) (layers "F.Cu" "B.Cu") (net 9))
  (via (at 107.936328 135.197157) (size 0.5) (drill 0.2) (layers "F.Cu" "B.Cu") (net 9))
  (via (at 247.18 91.1) (size 0.5) (drill 0.2) (layers "F.Cu" "B.Cu") (net 9))
  (via (at 185.2 61.3285) (size 0.5) (drill 0.2) (layers "F.Cu" "B.Cu") (net 9))
  (via blind (at 193.636328 90.060008) (size 0.5) (drill 0.2) (layers "F.Cu" "In2.Cu") (net 9))
  (via (at 233.6 122.3) (size 0.5) (drill 0.2) (layers "F.Cu" "B.Cu") (net 9))
  (via (at 259.05 100.471651) (size 0.5) (drill 0.2) (layers "F.Cu" "B.Cu") (net 9))
  (via (at 259.05 98.785377) (size 0.5) (drill 0.2) (layers "F.Cu" "B.Cu") (net 9))
  (via (at 132.35 61.45) (size 0.5) (drill 0.2) (layers "F.Cu" "B.Cu") (net 9))
  (via (at 140.8 130.4) (size 0.5) (drill 0.2) (layers "F.Cu" "B.Cu") (net 9))
  (via (at 245.77 74.36) (size 0.5) (drill 0.2) (layers "F.Cu" "B.Cu") (net 9))
  (via (at 184.2 76.4) (size 0.5) (drill 0.2) (layers "F.Cu" "B.Cu") (net 9))
  (via (at 253.55 80) (size 0.5) (drill 0.2) (layers "F.Cu" "B.Cu") (net 9))
  (via (at 107.936328 104.032433) (size 0.5) (drill 0.2) (layers "F.Cu" "B.Cu") (net 9))
  (via (at 247 127.55) (size 0.5) (drill 0.2) (layers "F.Cu" "B.Cu") (free) (net 9))
  (via (at 158.66 102.79) (size 0.5) (drill 0.2) (layers "F.Cu" "B.Cu") (net 9))
  (via (at 187.636328 91.060008) (size 0.5) (drill 0.2) (layers "F.Cu" "B.Cu") (net 9))
  (via (at 159.1 53.8) (size 0.5) (drill 0.2) (layers "F.Cu" "B.Cu") (net 9))
  (via (at 237.9 88.45) (size 0.5) (drill 0.2) (layers "F.Cu" "B.Cu") (net 9))
  (via (at 146.276996 46.897157) (size 0.5) (drill 0.2) (layers "F.Cu" "B.Cu") (net 9))
  (via (at 150.325 64.575) (size 0.5) (drill 0.2) (layers "F.Cu" "B.Cu") (net 9))
  (via (at 130.7 56.65) (size 0.5) (drill 0.2) (layers "F.Cu" "B.Cu") (net 9))
  (via (at 146.9 58.35) (size 0.5) (drill 0.2) (layers "F.Cu" "B.Cu") (net 9))
  (via (at 128.199831 58.410509) (size 0.5) (drill 0.2) (layers "F.Cu" "B.Cu") (net 9))
  (via (at 248.45 93.66) (size 0.5) (drill 0.2) (layers "F.Cu" "B.Cu") (net 9))
  (via (at 131.500722 135.197157) (size 0.5) (drill 0.2) (layers "F.Cu" "B.Cu") (net 9))
  (via (at 128.8 56.65) (size 0.5) (drill 0.2) (layers "F.Cu" "B.Cu") (net 9))
  (via (at 249.72 79.67) (size 0.5) (drill 0.2) (layers "F.Cu" "B.Cu") (net 9))
  (via blind (at 216.886328 61.25) (size 0.5) (drill 0.2) (layers "F.Cu" "In2.Cu") (net 9))
  (via (at 131.05 53.8) (size 0.5) (drill 0.2) (layers "F.Cu" "B.Cu") (net 9))
  (via (at 247.8 126.3) (size 0.5) (drill 0.2) (layers "F.Cu" "B.Cu") (net 9))
  (via (at 192.66 85.15) (size 0.5) (drill 0.2) (layers "F.Cu" "B.Cu") (net 9))
  (via (at 190.636328 92.060008) (size 0.5) (drill 0.2) (layers "F.Cu" "B.Cu") (net 9))
  (via (at 190.636328 91.060008) (size 0.5) (drill 0.2) (layers "F.Cu" "B.Cu") (net 9))
  (via (at 162.798443 46.897157) (size 0.5) (drill 0.2) (layers "F.Cu" "B.Cu") (net 9))
  (via (at 193.57 99.96) (size 0.5) (drill 0.2) (layers "F.Cu" "B.Cu") (net 9))
  (via (at 254.8 108.9) (size 0.5) (drill 0.2) (layers "F.Cu" "B.Cu") (net 9))
  (via (at 182.636328 86.060008) (size 0.5) (drill 0.2) (layers "F.Cu" "B.Cu") (net 9))
  (via (at 148.107504 46.897157) (size 0.5) (drill 0.2) (layers "F.Cu" "B.Cu") (net 9))
  (via (at 223.55 106.4) (size 0.5) (drill 0.2) (layers "F.Cu" "B.Cu") (net 9))
  (via (at 257.45 101.14) (size 0.5) (drill 0.2) (layers "F.Cu" "B.Cu") (net 9))
  (via (at 227.394034 46.897157) (size 0.5) (drill 0.2) (layers "F.Cu" "B.Cu") (net 9))
  (via (at 137.075 133.475) (size 0.5) (drill 0.2) (layers "F.Cu" "B.Cu") (net 9))
  (via (at 155.85 102.8) (size 0.5) (drill 0.2) (layers "F.Cu" "B.Cu") (net 9))
  (via (at 160.65 58.25) (size 0.5) (drill 0.2) (layers "F.Cu" "B.Cu") (net 9))
  (via (at 259.05 95.412829) (size 0.5) (drill 0.2) (layers "F.Cu" "B.Cu") (net 9))
  (via (at 237.95 84.45) (size 0.5) (drill 0.2) (layers "F.Cu" "B.Cu") (net 9))
  (via (at 186.798172 46.897157) (size 0.5) (drill 0.2) (layers "F.Cu" "B.Cu") (net 9))
  (via blind (at 159.95 61.35) (size 0.5) (drill 0.2) (layers "F.Cu" "In2.Cu") (net 9))
  (via (at 187.9312 135.197157) (size 0.5) (drill 0.2) (layers "F.Cu" "B.Cu") (net 9))
  (via (at 259.2315 75.16756) (size 0.5) (drill 0.2) (layers "F.Cu" "B.Cu") (net 9))
  (via (at 211.786328 53.813672) (size 0.5) (drill 0.2) (layers "F.Cu" "B.Cu") (net 9))
  (via (at 126.8 53.8) (size 0.5) (drill 0.2) (layers "F.Cu" "B.Cu") (net 9))
  (via (at 182.636328 93.060008) (size 0.5) (drill 0.2) (layers "F.Cu" "B.Cu") (net 9))
  (via (at 206.13458 135.197157) (size 0.5) (drill 0.2) (layers "F.Cu" "B.Cu") (free) (net 9))
  (via (at 187.636328 88.060008) (size 0.5) (drill 0.2) (layers "F.Cu" "B.Cu") (net 9))
  (via (at 131.3 64.4) (size 0.5) (drill 0.2) (layers "F.Cu" "B.Cu") (net 9))
  (via (at 245.91 105.09) (size 0.5) (drill 0.2) (layers "F.Cu" "B.Cu") (net 9))
  (via (at 168.1 63.75) (size 0.5) (drill 0.2) (layers "F.Cu" "B.Cu") (net 9))
  (via (at 181.636328 89.060008) (size 0.5) (drill 0.2) (layers "F.Cu" "B.Cu") (net 9))
  (via (at 157.25 132.775) (size 0.5) (drill 0.2) (layers "F.Cu" "B.Cu") (net 9))
  (via (at 259.05 105.530473) (size 0.5) (drill 0.2) (layers "F.Cu" "B.Cu") (net 9))
  (via (at 184.636328 93.060008) (size 0.5) (drill 0.2) (layers "F.Cu" "B.Cu") (net 9))
  (via (at 165.4 104.9) (size 0.5) (drill 0.2) (layers "F.Cu" "B.Cu") (net 9))
  (via (at 194.655836 81.060008) (size 0.5) (drill 0.2) (layers "F.Cu" "B.Cu") (net 9))
  (via (at 124.25 61.25) (size 0.5) (drill 0.2) (layers "F.Cu" "B.Cu") (net 9))
  (via (at 125.1 130.3) (size 0.5) (drill 0.2) (layers "F.Cu" "B.Cu") (net 9))
  (via (at 118.776328 61.070008) (size 0.5) (drill 0.2) (layers "F.Cu" "B.Cu") (net 9))
  (via (at 256.613726 69.6) (size 0.5) (drill 0.2) (layers "F.Cu" "B.Cu") (net 9))
  (via (at 131.243648 131.775) (size 0.5) (drill 0.2) (layers "F.Cu" "B.Cu") (net 9))
  (via (at 177.636328 94.060008) (size 0.5) (drill 0.2) (layers "F.Cu" "B.Cu") (net 9))
  (via blind (at 153.986328 61.35) (size 0.5) (drill 0.2) (layers "F.Cu" "In2.Cu") (net 9))
  (via (at 125.25 129.375) (size 0.5) (drill 0.2) (layers "F.Cu" "B.Cu") (net 9))
  (via (at 184.290524 135.197157) (size 0.5) (drill 0.2) (layers "F.Cu" "B.Cu") (net 9))
  (via (at 244.64 102.53) (size 0.5) (drill 0.2) (layers "F.Cu" "B.Cu") (net 9))
  (via (at 256.1 121.54) (size 0.5) (drill 0.2) (layers "F.Cu" "B.Cu") (net 9))
  (via (at 258.740167 129.138309) (size 0.5) (drill 0.2) (layers "F.Cu" "B.Cu") (net 9))
  (via (at 183.636328 92.060008) (size 0.5) (drill 0.2) (layers "F.Cu" "B.Cu") (net 9))
  (via (at 214.049831 58.410509) (size 0.5) (drill 0.2) (layers "F.Cu" "B.Cu") (net 9))
  (via (at 112.25 101.625) (size 0.5) (drill 0.2) (layers "F.Cu" "B.Cu") (net 9))
  (via (at 258.740167 119.020665) (size 0.5) (drill 0.2) (layers "F.Cu" "B.Cu") (net 9))
  (via (at 249.72 113.96) (size 0.5) (drill 0.2) (layers "F.Cu" "B.Cu") (net 9))
  (via (at 259.2 68.432445) (size 0.5) (drill 0.2) (layers "F.Cu" "B.Cu") (net 9))
  (via (at 189.9 112.3) (size 0.5) (drill 0.2) (layers "F.Cu" "B.Cu") (free) (net 9))
  (via (at 214.336328 53.813672) (size 0.5) (drill 0.2) (layers "F.Cu" "B.Cu") (net 9))
  (via (at 201.567236 46.897157) (size 0.5) (drill 0.2) (layers "F.Cu" "B.Cu") (net 9))
  (via (at 251.954918 135.197157) (size 0.5) (drill 0.2) (layers "F.Cu" "B.Cu") (net 9))
  (via (at 165.386328 96.260008) (size 0.5) (drill 0.2) (layers "F.Cu" "B.Cu") (net 9))
  (via (at 252.26 124.14) (size 0.5) (drill 0.2) (layers "F.Cu" "B.Cu") (net 9))
  (via (at 134.211328 85.735008) (size 0.5) (drill 0.2) (layers "F.Cu" "B.Cu") (net 9))
  (via (at 168.05 91.05) (size 0.5) (drill 0.2) (layers "F.Cu" "B.Cu") (net 9))
  (via (at 129.680384 135.197157) (size 0.5) (drill 0.2) (layers "F.Cu" "B.Cu") (net 9))
  (via (at 172.636328 86.060008) (size 0.5) (drill 0.2) (layers "F.Cu" "B.Cu") (net 9))
  (via (at 129.65 61.6) (size 0.5) (drill 0.2) (layers "F.Cu" "B.Cu") (net 9))
  (via (at 189.9 111.7) (size 0.5) (drill 0.2) (layers "F.Cu" "B.Cu") (free) (net 9))
  (via (at 123.575 100.997157) (size 0.5) (drill 0.2) (layers "F.Cu" "B.Cu") (net 9))
  (via (at 137.589828 97.7) (size 0.5) (drill 0.2) (layers "F.Cu" "B.Cu") (net 9))
  (via (at 189.636328 88.060008) (size 0.5) (drill 0.2) (layers "F.Cu" "B.Cu") (net 9))
  (via (at 216.05 53.8) (size 0.5) (drill 0.2) (layers "F.Cu" "B.Cu") (net 9))
  (via (at 152.83 106.43) (size 0.5) (drill 0.2) (layers "F.Cu" "B.Cu") (net 9))
  (via (at 182.636328 78.0405) (size 0.5) (drill 0.2) (layers "F.Cu" "B.Cu") (net 9))
  (via (at 166.236328 93.760008) (size 0.5) (drill 0.2) (layers "F.Cu" "B.Cu") (net 9))
  (via (at 183.636328 81.0405) (size 0.5) (drill 0.2) (layers "F.Cu" "B.Cu") (net 9))
  (via (at 140 77.7) (size 0.5) (drill 0.2) (layers "F.Cu" "B.Cu") (net 9))
  (via (at 138.2 101.4) (size 0.5) (drill 0.2) (layers "F.Cu" "B.Cu") (net 9))
  (via (at 158.805792 135.197157) (size 0.5) (drill 0.2) (layers "F.Cu" "B.Cu") (net 9))
  (via (at 124.625 128.875) (size 0.5) (drill 0.2) (layers "F.Cu" "B.Cu") (net 9))
  (via (at 134.826328 112.377157) (size 0.5) (drill 0.2) (layers "F.Cu" "B.Cu") (net 9))
  (via (at 107.936328 59.016761) (size 0.5) (drill 0.2) (layers "F.Cu" "B.Cu") (net 9))
  (via (at 244.64 106.34) (size 0.5) (drill 0.2) (layers "F.Cu" "B.Cu") (net 9))
  (via (at 223.7 53.8) (size 0.5) (drill 0.2) (layers "F.Cu" "B.Cu") (net 9))
  (via (at 249.78 77.09) (size 0.5) (drill 0.2) (layers "F.Cu" "B.Cu") (net 9))
  (via (at 132.218648 126.675) (size 0.5) (drill 0.2) (layers "F.Cu" "B.Cu") (net 9))
  (via (at 225.4 56.6) (size 0.5) (drill 0.2) (layers "F.Cu" "B.Cu") (net 9))
  (via (at 238.451768 46.897157) (size 0.5) (drill 0.2) (layers "F.Cu" "B.Cu") (net 9))
  (via (at 249.5 117.8175) (size 0.5) (drill 0.2) (layers "F.Cu" "B.Cu") (net 9))
  (via (at 176.636328 101.060008) (size 0.5) (drill 0.2) (layers "F.Cu" "B.Cu") (net 9))
  (via (at 253.201768 46.897157) (size 0.5) (drill 0.2) (layers "F.Cu" "B.Cu") (net 9))
  (via (at 253.55 99.075) (size 0.5) (drill 0.2) (layers "F.Cu" "B.Cu") (net 9))
  (via (at 162.446468 135.197157) (size 0.5) (drill 0.2) (layers "F.Cu" "B.Cu") (net 9))
  (via (at 107.936328 52.091273) (size 0.5) (drill 0.2) (layers "F.Cu" "B.Cu") (net 9))
  (via (at 164.586328 100.260008) (size 0.5) (drill 0.2) (layers "F.Cu" "B.Cu") (net 9))
  (via (at 247.2 124.2) (size 0.5) (drill 0.2) (layers "F.Cu" "B.Cu") (net 9))
  (via (at 156.5142 77.660008) (size 0.5) (drill 0.2) (layers "F.Cu" "B.Cu") (net 9))
  (via (at 245.91 86.04) (size 0.5) (drill 0.2) (layers "F.Cu" "B.Cu") (net 9))
  (via (at 189.9 111.1) (size 0.5) (drill 0.2) (layers "F.Cu" "B.Cu") (free) (net 9))
  (via (at 117.125 99.125) (size 0.5) (drill 0.2) (layers "F.Cu" "B.Cu") (net 9))
  (via (at 152.044328 128.268157) (size 0.5) (drill 0.2) (layers "F.Cu" "B.Cu") (net 9))
  (via (at 230.8 56.6) (size 0.5) (drill 0.2) (layers "F.Cu" "B.Cu") (net 9))
  (via (at 189.9 113.5) (size 0.5) (drill 0.2) (layers "F.Cu" "B.Cu") (free) (net 9))
  (via (at 254.8 124.14) (size 0.5) (drill 0.2) (layers "F.Cu" "B.Cu") (net 9))
  (via (at 192.336571 46.897157) (size 0.5) (drill 0.2) (layers "F.Cu" "B.Cu") (net 9))
  (via (at 245.5 127.1) (size 0.5) (drill 0.2) (layers "F.Cu" "B.Cu") (net 9))
  (via (at 118.37 91.1) (size 0.5) (drill 0.2) (layers "F.Cu" "B.Cu") (net 9))
  (via (at 134.659324 128.15) (size 0.5) (drill 0.2) (layers "F.Cu" "B.Cu") (net 9))
  (via (at 228.5 58.35) (size 0.5) (drill 0.2) (layers "F.Cu" "B.Cu") (net 9))
  (via (at 186.636328 88.060008) (size 0.5) (drill 0.2) (layers "F.Cu" "B.Cu") (net 9))
  (via (at 245.65 62.7) (size 0.5) (drill 0.2) (layers "F.Cu" "B.Cu") (net 9))
  (via (at 254.8 113.98) (size 0.5) (drill 0.2) (layers "F.Cu" "B.Cu") (net 9))
  (via (at 204.635517 56.654381) (size 0.5) (drill 0.2) (layers "F.Cu" "B.Cu") (net 9))
  (via (at 107.936328 72.867737) (size 0.5) (drill 0.2) (layers "F.Cu" "B.Cu") (net 9))
  (via (at 158.636328 91.060008) (size 0.5) (drill 0.2) (layers "F.Cu" "B.Cu") (net 9))
  (via (at 198.7 58.3) (size 0.5) (drill 0.2) (layers "F.Cu" "B.Cu") (net 9))
  (via (at 256.1 78.4) (size 0.5) (drill 0.2) (layers "F.Cu" "B.Cu") (net 9))
  (via blind (at 189.636328 97.060008) (size 0.5) (drill 0.2) (layers "F.Cu" "In2.Cu") (net 9))
  (via (at 258.740167 60.001075) (size 0.5) (drill 0.2) (layers "F.Cu" "B.Cu") (net 9))
  (via (at 230.95 100.95) (size 0.5) (drill 0.2) (layers "F.Cu" "B.Cu") (net 9))
  (via (at 109.036328 115.997157) (size 0.5) (drill 0.2) (layers "F.Cu" "B.Cu") (net 9))
  (via (at 166.15 110.25) (size 0.5) (drill 0.2) (layers "F.Cu" "B.Cu") (net 9))
  (via (at 229.954918 135.197157) (size 0.5) (drill 0.2) (layers "F.Cu" "B.Cu") (net 9))
  (via (at 247.18 79.67) (size 0.5) (drill 0.2) (layers "F.Cu" "B.Cu") (net 9))
  (via (at 253.53 111.41) (size 0.5) (drill 0.2) (layers "F.Cu" "B.Cu") (net 9))
  (via (at 238.6 121.5) (size 0.5) (drill 0.2) (layers "F.Cu" "B.Cu") (net 9))
  (via (at 160.62613 135.197157) (size 0.5) (drill 0.2) (layers "F.Cu" "B.Cu") (net 9))
  (via (at 213.2 106.1) (size 0.5) (drill 0.2) (layers "F.Cu" "B.Cu") (net 9))
  (via (at 183.5 61.55) (size 0.5) (drill 0.2) (layers "F.Cu" "B.Cu") (net 9))
  (via (at 132.25 105.25) (size 0.5) (drill 0.2) (layers "F.Cu" "B.Cu") (net 9))
  (via (at 255.1 68.2) (size 0.5) (drill 0.2) (layers "F.Cu" "B.Cu") (net 9))
  (via (at 256.1 85.98) (size 0.5) (drill 0.2) (layers "F.Cu" "B.Cu") (net 9))
  (via (at 202.1 61.6) (size 0.5) (drill 0.2) (layers "F.Cu" "B.Cu") (net 9))
  (via (at 142.1 112) (size 0.5) (drill 0.2) (layers "F.Cu" "B.Cu") (net 9))
  (via (at 146.4 113.6) (size 0.5) (drill 0.2) (layers "F.Cu" "B.Cu") (net 9))
  (via (at 195.646328 53.531608) (size 0.5) (drill 0.2) (layers "F.Cu" "B.Cu") (net 9))
  (via (at 213.559808 89.05) (size 0.5) (drill 0.2) (layers "F.Cu" "B.Cu") (net 9))
  (via (at 161.05 98.7) (size 0.5) (drill 0.2) (layers "F.Cu" "B.Cu") (net 9))
  (via (at 118.776328 61.830008) (size 0.5) (drill 0.2) (layers "F.Cu" "B.Cu") (net 9))
  (via (at 203.442164 89.05) (size 0.5) (drill 0.2) (layers "F.Cu" "B.Cu") (net 9))
  (via (at 221.45 56.65) (size 0.5) (drill 0.2) (layers "F.Cu" "B.Cu") (net 9))
  (via (at 166.087144 135.197157) (size 0.5) (drill 0.2) (layers "F.Cu" "B.Cu") (net 9))
  (via (at 248.45 78.42) (size 0.5) (drill 0.2) (layers "F.Cu" "B.Cu") (net 9))
  (via (at 112.25 103.875) (size 0.5) (drill 0.2) (layers "F.Cu" "B.Cu") (net 9))
  (via (at 226.8 58.35) (size 0.5) (drill 0.2) (layers "F.Cu" "B.Cu") (net 9))
  (via (at 198.853228 135.197157) (size 0.5) (drill 0.2) (layers "F.Cu" "B.Cu") (net 9))
  (via (at 256.11 103.7495) (size 0.5) (drill 0.2) (layers "F.Cu" "B.Cu") (net 9))
  (via (at 145.825 135.197157) (size 0.5) (drill 0.2) (layers "F.Cu" "B.Cu") (net 9))
  (via (at 168.9 75.5) (size 0.5) (drill 0.2) (layers "F.Cu" "B.Cu") (net 9))
  (via (at 107.936328 112.89) (size 0.5) (drill 0.2) (layers "F.Cu" "B.Cu") (net 9))
  (via (at 107.936328 50.359901) (size 0.5) (drill 0.2) (layers "F.Cu" "B.Cu") (net 9))
  (via (at 128.5 73) (size 0.5) (drill 0.2) (layers "F.Cu" "B.Cu") (net 9))
  (via (at 206.686328 57.010008) (size 0.5) (drill 0.2) (layers "F.Cu" "B.Cu") (net 9))
  (via (at 247.18 87.29) (size 0.5) (drill 0.2) (layers "F.Cu" "B.Cu") (net 9))
  (via (at 228.786328 56.65) (size 0.5) (drill 0.2) (layers "F.Cu" "B.Cu") (net 9))
  (via (at 231.32 78.88) (size 0.5) (drill 0.2) (layers "F.Cu" "B.Cu") (net 9))
  (via (at 243.37 89.85) (size 0.5) (drill 0.2) (layers "F.Cu" "B.Cu") (net 9))
  (via (at 259.05 97.099103) (size 0.5) (drill 0.2) (layers "F.Cu" "B.Cu") (net 9))
  (via (at 164.266806 135.197157) (size 0.5) (drill 0.2) (layers "F.Cu" "B.Cu") (net 9))
  (via (at 257.505991 98.890089) (size 0.5) (drill 0.2) (layers "F.Cu" "B.Cu") (net 9))
  (via (at 182.470186 135.197157) (size 0.5) (drill 0.2) (layers "F.Cu" "B.Cu") (net 9))
  (via (at 177.009172 135.197157) (size 0.5) (drill 0.2) (layers "F.Cu" "B.Cu") (net 9))
  (via (at 241.3 116.3) (size 0.5) (drill 0.2) (layers "F.Cu" "B.Cu") (net 9))
  (via (at 170.182975 46.897157) (size 0.5) (drill 0.2) (layers "F.Cu" "B.Cu") (net 9))
  (via (at 124.189104 100.997157) (size 0.5) (drill 0.2) (layers "F.Cu" "B.Cu") (net 9))
  (via (at 213 64.1) (size 0.5) (drill 0.2) (layers "F.Cu" "B.Cu") (net 9))
  (via (at 248.45 112.71) (size 0.5) (drill 0.2) (layers "F.Cu" "B.Cu") (net 9))
  (via (at 230.475 88.85) (size 0.5) (drill 0.2) (layers "F.Cu" "B.Cu") (net 9))
  (via (at 174.636328 81.060008) (size 0.5) (drill 0.2) (layers "F.Cu" "B.Cu") (net 9))
  (via (at 162.1 103.23) (size 0.5) (drill 0.2) (layers "F.Cu" "B.Cu") (net 9))
  (via (at 249.745 119.055) (size 0.5) (drill 0.2) (layers "F.Cu" "B.Cu") (net 9))
  (via (at 159.106177 46.897157) (size 0.5) (drill 0.2) (layers "F.Cu" "B.Cu") (net 9))
  (via (at 107.936328 130.003013) (size 0.5) (drill 0.2) (layers "F.Cu" "B.Cu") (net 9))
  (via (at 258.740167 134.197157) (size 0.5) (drill 0.2) (layers "F.Cu" "B.Cu") (net 9))
  (via (at 247.21 77.09) (size 0.5) (drill 0.2) (layers "F.Cu" "B.Cu") (net 9))
  (via (at 107.936328 65.942249) (size 0.5) (drill 0.2) (layers "F.Cu" "B.Cu") (net 9))
  (via (at 129.802424 46.897157) (size 0.5) (drill 0.2) (layers "F.Cu" "B.Cu") (net 9))
  (via (at 258.740167 63.373623) (size 0.5) (drill 0.2) (layers "F.Cu" "B.Cu") (net 9))
  (via (at 217.75 56.6) (size 0.5) (drill 0.2) (layers "F.Cu" "B.Cu") (net 9))
  (via (at 143.786328 56.75) (size 0.5) (drill 0.2) (layers "F.Cu" "B.Cu") (net 9))
  (via (at 235.65 101.5) (size 0.5) (drill 0.2) (layers "F.Cu" "B.Cu") (net 9))
  (via (at 228.84 78.15) (size 0.5) (drill 0.2) (layers "F.Cu" "B.Cu") (net 9))
  (via (at 251 124.125) (size 0.5) (drill 0.2) (layers "F.Cu" "B.Cu") (net 9))
  (via (at 201.515 122.415) (size 0.5) (drill 0.2) (layers "F.Cu" "B.Cu") (net 9))
  (via blind (at 193.636328 98.060008) (size 0.5) (drill 0.2) (layers "F.Cu" "In2.Cu") (net 9))
  (via (at 257.415932 135.197157) (size 0.5) (drill 0.2) (layers "F.Cu" "B.Cu") (net 9))
  (via (at 145.644328 128.268157) (size 0.5) (drill 0.2) (layers "F.Cu" "B.Cu") (net 9))
  (via (at 135.708828 61.45) (size 0.5) (drill 0.2) (layers "F.Cu" "B.Cu") (net 9))
  (via (at 140.602412 135.197157) (size 0.5) (drill 0.2) (layers "F.Cu" "B.Cu") (net 9))
  (via (at 190.5 112.3) (size 0.5) (drill 0.2) (layers "F.Cu" "B.Cu") (free) (net 9))
  (via (at 111.477004 135.197157) (size 0.5) (drill 0.2) (layers "F.Cu" "B.Cu") (net 9))
  (via (at 196.9 88.5) (size 0.5) (drill 0.2) (layers "F.Cu" "B.Cu") (net 9))
  (via (at 135.141398 135.197157) (size 0.5) (drill 0.2) (layers "F.Cu" "B.Cu") (net 9))
  (via (at 237 63.7) (size 0.5) (drill 0.2) (layers "F.Cu" "B.Cu") (net 9))
  (via (at 167.586328 53.710008) (size 0.5) (drill 0.2) (layers "F.Cu" "B.Cu") (net 9))
  (via (at 214.490167 46.897157) (size 0.5) (drill 0.2) (layers "F.Cu" "B.Cu") (net 9))
  (via (at 112.25 104.75) (size 0.5) (drill 0.2) (layers "F.Cu" "B.Cu") (net 9))
  (via (at 131.632932 46.897157) (size 0.5) (drill 0.2) (layers "F.Cu" "B.Cu") (net 9))
  (via (at 259.05 108.903021) (size 0.5) (drill 0.2) (layers "F.Cu" "B.Cu") (net 9))
  (via blind (at 192.636328 93.060008) (size 0.5) (drill 0.2) (layers "F.Cu" "In5.Cu") (net 9))
  (via (at 229.3 112.5) (size 0.5) (drill 0.2) (layers "F.Cu" "B.Cu") (net 9))
  (via (at 256.1 124.12) (size 0.5) (drill 0.2) (layers "F.Cu" "B.Cu") (net 9))
  (via (at 161.75 102.6995) (size 0.5) (drill 0.2) (layers "F.Cu" "B.Cu") (net 9))
  (via (at 123.6 91.4) (size 0.5) (drill 0.2) (layers "F.Cu" "B.Cu") (net 9))
  (via (at 155.536328 88.310008) (size 0.5) (drill 0.2) (layers "F.Cu" "B.Cu") (net 9))
  (via (at 136.704662 131.775) (size 0.5) (drill 0.2) (layers "F.Cu" "B.Cu") (net 9))
  (via (at 170.136328 53.710008) (size 0.5) (drill 0.2) (layers "F.Cu" "B.Cu") (net 9))
  (via (at 172.029108 46.897157) (size 0.5) (drill 0.2) (layers "F.Cu" "B.Cu") (net 9))
  (via (at 245.91 93.66) (size 0.5) (drill 0.2) (layers "F.Cu" "B.Cu") (net 9))
  (via (at 244.65 79.67) (size 0.5) (drill 0.2) (layers "F.Cu" "B.Cu") (net 9))
  (via (at 232.45 106.4) (size 0.5) (drill 0.2) (layers "F.Cu" "B.Cu") (net 9))
  (via (at 246.415932 135.197157) (size 0.5) (drill 0.2) (layers "F.Cu" "B.Cu") (net 9))
  (via (at 251.05 111.5) (size 0.5) (drill 0.2) (layers "F.Cu" "B.Cu") (net 9))
  (via (at 154.2 126.4) (size 0.5) (drill 0.2) (layers "F.Cu" "B.Cu") (net 9))
  (via (at 257 63.2) (size 0.5) (drill 0.2) (layers "F.Cu" "B.Cu") (net 9))
  (via (at 259.2315 78.550089) (size 0.5) (drill 0.2) (layers "F.Cu" "B.Cu") (net 9))
  (via blind (at 243.25 61.25) (size 0.5) (drill 0.2) (layers "F.Cu" "In5.Cu") (net 9))
  (via (at 242.77 79.46) (size 0.5) (drill 0.2) (layers "F.Cu" "B.Cu") (net 9))
  (via blind (at 196.61 90.060008) (size 0.5) (drill 0.2) (layers "F.Cu" "In2.Cu") (net 9))
  (via (at 232.8 58.4) (size 0.5) (drill 0.2) (layers "F.Cu" "B.Cu") (net 9))
  (via (at 242.386328 53.813672) (size 0.5) (drill 0.2) (layers "F.Cu" "B.Cu") (net 9))
  (via (at 152.8305 108.54) (size 0.5) (drill 0.2) (layers "F.Cu" "B.Cu") (net 9))
  (via (at 252.26 121.64) (size 0.5) (drill 0.2) (layers "F.Cu" "B.Cu") (net 9))
  (via (at 115.11768 135.197157) (size 0.5) (drill 0.2) (layers "F.Cu" "B.Cu") (net 9))
  (via (at 248.45 86.04) (size 0.5) (drill 0.2) (layers "F.Cu" "B.Cu") (net 9))
  (via (at 175.2 107.8) (size 0.5) (drill 0.2) (layers "F.Cu" "B.Cu") (net 9))
  (via (at 242.725 85.45) (size 0.5) (drill 0.2) (layers "F.Cu" "B.Cu") (net 9))
  (via (at 138 102.3) (size 0.5) (drill 0.2) (layers "F.Cu" "B.Cu") (net 9))
  (via (at 168.3 109.8) (size 0.5) (drill 0.2) (layers "F.Cu" "B.Cu") (net 9))
  (via (at 257.053893 73.491267) (size 0.5) (drill 0.2) (layers "F.Cu" "B.Cu") (net 9))
  (via (at 156.25 58.4) (size 0.5) (drill 0.2) (layers "F.Cu" "B.Cu") (net 9))
  (via (at 175.636328 88.060008) (size 0.5) (drill 0.2) (layers "F.Cu" "B.Cu") (net 9))
  (via (at 116.938018 135.197157) (size 0.5) (drill 0.2) (layers "F.Cu" "B.Cu") (net 9))
  (via (at 194.182704 46.897157) (size 0.5) (drill 0.2) (layers "F.Cu" "B.Cu") (net 9))
  (via (at 180.649848 135.197157) (size 0.5) (drill 0.2) (layers "F.Cu" "B.Cu") (net 9))
  (via (at 126.786328 56.7) (size 0.5) (drill 0.2) (layers "F.Cu" "B.Cu") (net 9))
  (via (at 139.725 129.875) (size 0.5) (drill 0.2) (layers "F.Cu" "B.Cu") (net 9))
  (via (at 175.313 76.741046) (size 0.5) (drill 0.2) (layers "F.Cu" "B.Cu") (net 9))
  (via (at 107.936328 57.285389) (size 0.5) (drill 0.2) (layers "F.Cu" "B.Cu") (net 9))
  (via (at 184.636328 91.060008) (size 0.5) (drill 0.2) (layers "F.Cu" "B.Cu") (net 9))
  (via (at 223.4 58.35) (size 0.5) (drill 0.2) (layers "F.Cu" "B.Cu") (net 9))
  (via blind (at 195.636328 95.060008) (size 0.5) (drill 0.2) (layers "F.Cu" "In2.Cu") (net 9))
  (via (at 256.77 125.76) (size 0.5) (drill 0.2) (layers "F.Cu" "B.Cu") (net 9))
  (via (at 160.95231 46.897157) (size 0.5) (drill 0.2) (layers "F.Cu" "B.Cu") (net 9))
  (via (at 107.936328 86.718713) (size 0.5) (drill 0.2) (layers "F.Cu" "B.Cu") (net 9))
  (via (at 239.8 87.1) (size 0.5) (drill 0.2) (layers "F.Cu" "B.Cu") (net 9))
  (via (at 233.036328 53.813672) (size 0.5) (drill 0.2) (layers "F.Cu" "B.Cu") (net 9))
  (via (at 222.03 82.9) (size 0.5) (drill 0.2) (layers "F.Cu" "B.Cu") (net 9))
  (via (at 208.951768 46.897157) (size 0.5) (drill 0.2) (layers "F.Cu" "B.Cu") (net 9))
  (via (at 242.77 74.46) (size 0.5) (drill 0.2) (layers "F.Cu" "B.Cu") (net 9))
  (via (at 112.25 100.875) (size 0.5) (drill 0.2) (layers "F.Cu" "B.Cu") (net 9))
  (via (at 259.05 110.589295) (size 0.5) (drill 0.2) (layers "F.Cu" "B.Cu") (net 9))
  (via (at 167.45 109.8) (size 0.5) (drill 0.2) (layers "F.Cu" "B.Cu") (net 9))
  (via (at 255.29129 86.03634) (size 0.5) (drill 0.2) (layers "F.Cu" "B.Cu") (net 9))
  (via (at 134.45 56.5) (size 0.5) (drill 0.2) (layers "F.Cu" "B.Cu") (net 9))
  (via (at 143.116328 115.227157) (size 0.5) (drill 0.2) (layers "F.Cu" "B.Cu") (net 9))
  (via (at 247.18 102.53) (size 0.5) (drill 0.2) (layers "F.Cu" "B.Cu") (net 9))
  (via (at 115.411328 94.122157) (size 0.5) (drill 0.2) (layers "F.Cu" "B.Cu") (net 9))
  (via (at 183.340779 56.810501) (size 0.5) (drill 0.2) (layers "F.Cu" "B.Cu") (net 9))
  (via (at 125.1 53.8) (size 0.5) (drill 0.2) (layers "F.Cu" "B.Cu") (net 9))
  (via (at 236.45 53.8) (size 0.5) (drill 0.2) (layers "F.Cu" "B.Cu") (net 9))
  (via (at 216.036328 56.55) (size 0.5) (drill 0.2) (layers "F.Cu" "B.Cu") (net 9))
  (via (at 192.7 99) (size 0.5) (drill 0.2) (layers "F.Cu" "B.Cu") (net 9))
  (via (at 145.65 107.5) (size 0.5) (drill 0.2) (layers "F.Cu" "B.Cu") (net 9))
  (via (at 222.2 61.6) (size 0.5) (drill 0.2) (layers "F.Cu" "B.Cu") (net 9))
  (via (at 254.23 125.7395) (size 0.5) (drill 0.2) (layers "F.Cu" "B.Cu") (net 9))
  (via (at 107.936328 126.540269) (size 0.5) (drill 0.2) (layers "F.Cu" "B.Cu") (net 9))
  (via (at 131.95 118.55) (size 0.5) (drill 0.2) (layers "F.Cu" "B.Cu") (net 9))
  (via (at 132.736328 56.5) (size 0.5) (drill 0.2) (layers "F.Cu" "B.Cu") (net 9))
  (via (at 245.87 77.09) (size 0.5) (drill 0.2) (layers "F.Cu" "B.Cu") (net 9))
  (via blind (at 233.886328 61.4) (size 0.5) (drill 0.2) (layers "F.Cu" "In2.Cu") (net 9))
  (via (at 114.911328 93.622157) (size 0.5) (drill 0.2) (layers "F.Cu" "B.Cu") (net 9))
  (via (at 249.72 83.48) (size 0.5) (drill 0.2) (layers "F.Cu" "B.Cu") (net 9))
  (via (at 181.636328 85.060008) (size 0.5) (drill 0.2) (layers "F.Cu" "B.Cu") (net 9))
  (via (at 240.1 56.6) (size 0.5) (drill 0.2) (layers "F.Cu" "B.Cu") (net 9))
  (via (at 256.1 106.3) (size 0.5) (drill 0.2) (layers "F.Cu" "B.Cu") (net 9))
  (via (at 225.386328 53.813672) (size 0.5) (drill 0.2) (layers "F.Cu" "B.Cu") (net 9))
  (via (at 259.2315 80.236363) (size 0.5) (drill 0.2) (layers "F.Cu" "B.Cu") (net 9))
  (via (at 249.725 121.625) (size 0.5) (drill 0.2) (layers "F.Cu" "B.Cu") (net 9))
  (via (at 107.936328 81.524597) (size 0.5) (drill 0.2) (layers "F.Cu" "B.Cu") (net 9))
  (via (at 140.386328 53.813672) (size 0.5) (drill 0.2) (layers "F.Cu" "B.Cu") (net 9))
  (via (at 219.707624 85.492376) (size 0.5) (drill 0.2) (layers "F.Cu" "B.Cu") (net 9))
  (via (at 107.936328 62.479505) (size 0.5) (drill 0.2) (layers "F.Cu" "B.Cu") (net 9))
  (via (at 175.188834 135.197157) (size 0.5) (drill 0.2) (layers "F.Cu" "B.Cu") (net 9))
  (via (at 172.186328 57.710008) (size 0.5) (drill 0.2) (layers "F.Cu" "B.Cu") (net 9))
  (via blind (at 196.636328 99.0195) (size 0.5) (drill 0.2) (layers "F.Cu" "In2.Cu") (net 9))
  (via (at 190.536328 53.531608) (size 0.5) (drill 0.2) (layers "F.Cu" "B.Cu") (net 9))
  (via (at 136.15 56.5) (size 0.5) (drill 0.2) (layers "F.Cu" "B.Cu") (net 9))
  (via (at 251.075 100.075) (size 0.5) (drill 0.2) (layers "F.Cu" "B.Cu") (net 9))
  (via (at 181.259773 46.897157) (size 0.5) (drill 0.2) (layers "F.Cu" "B.Cu") (net 9))
  (via (at 134.263986 129.875) (size 0.5) (drill 0.2) (layers "F.Cu" "B.Cu") (net 9))
  (via (at 122.175 94.7) (size 0.5) (drill 0.2) (layers "F.Cu" "B.Cu") (net 9))
  (via (at 112.25 103.125) (size 0.5) (drill 0.2) (layers "F.Cu" "B.Cu") (net 9))
  (via (at 107.936328 88.450085) (size 0.5) (drill 0.2) (layers "F.Cu" "B.Cu") (net 9))
  (via (at 107.936328 124.808897) (size 0.5) (drill 0.2) (layers "F.Cu" "B.Cu") (net 9))
  (via (at 160.786328 56.55) (size 0.5) (drill 0.2) (layers "F.Cu" "B.Cu") (net 9))
  (via (at 252.25 80.95) (size 0.5) (drill 0.2) (layers "F.Cu" "B.Cu") (net 9))
  (via (at 169.3 91.05) (size 0.5) (drill 0.2) (layers "F.Cu" "B.Cu") (net 9))
  (via blind (at 175.56 80.13) (size 0.5) (drill 0.2) (layers "F.Cu" "In2.Cu") (net 9))
  (via (at 134.884324 131.775) (size 0.5) (drill 0.2) (layers "F.Cu" "B.Cu") (net 9))
  (via (at 159.941681 101.4505) (size 0.5) (drill 0.2) (layers "F.Cu" "B.Cu") (net 9))
  (via (at 232.8 122.9) (size 0.5) (drill 0.2) (layers "F.Cu" "B.Cu") (net 9))
  (via (at 157.61 110.54) (size 0.5) (drill 0.2) (layers "F.Cu" "B.Cu") (net 9))
  (via (at 193.636328 88.060008) (size 0.5) (drill 0.2) (layers "F.Cu" "B.Cu") (net 9))
  (via (at 109.85 110.6) (size 0.5) (drill 0.2) (layers "F.Cu" "B.Cu") (net 9))
  (via (at 258.740167 66.746171) (size 0.5) (drill 0.2) (layers "F.Cu" "B.Cu") (net 9))
  (via (at 127.725 129.425) (size 0.5) (drill 0.2) (layers "F.Cu" "B.Cu") (net 9))
  (via (at 121.636328 53.670008) (size 0.5) (drill 0.2) (layers "F.Cu" "B.Cu") (net 9))
  (via (at 159.4 107.48) (size 0.5) (drill 0.2) (layers "F.Cu" "B.Cu") (net 9))
  (via blind (at 194.636328 90.060008) (size 0.5) (drill 0.2) (layers "F.Cu" "In2.Cu") (net 9))
  (via (at 136.479662 128.15) (size 0.5) (drill 0.2) (layers "F.Cu" "B.Cu") (net 9))
  (via (at 187.986328 53.531608) (size 0.5) (drill 0.2) (layers "F.Cu" "B.Cu") (net 9))
  (via (at 107.936328 95.375573) (size 0.5) (drill 0.2) (layers "F.Cu" "B.Cu") (net 9))
  (via (at 239.728 119.375) (size 0.5) (drill 0.2) (layers "F.Cu" "B.Cu") (net 9))
  (via (at 247.175 119.4) (size 0.5) (drill 0.2) (layers "F.Cu" "B.Cu") (net 9))
  (via (at 132.7 77.1) (size 0.5) (drill 0.2) (layers "F.Cu" "B.Cu") (net 9))
  (via (at 245.925 121.325) (size 0.5) (drill 0.2) (layers "F.Cu" "B.Cu") (net 9))
  (via (at 113.297342 135.197157) (size 0.5) (drill 0.2) (layers "F.Cu" "B.Cu") (net 9))
  (via (at 200.736328 56.55) (size 0.5) (drill 0.2) (layers "F.Cu" "B.Cu") (net 9))
  (via (at 252.26 116.56) (size 0.5) (drill 0.2) (layers "F.Cu" "B.Cu") (net 9))
  (via (at 128.25 128.875) (size 0.5) (drill 0.2) (layers "F.Cu" "B.Cu") (net 9))
  (via (at 253.534926 83.898226) (size 0.5) (drill 0.2) (layers "F.Cu" "B.Cu") (net 9))
  (via (at 175.721374 46.897157) (size 0.5) (drill 0.2) (layers "F.Cu" "B.Cu") (net 9))
  (via (at 160.636328 90.660008) (size 0.5) (drill 0.2) (layers "F.Cu" "B.Cu") (net 9))
  (via (at 140.1 56.6) (size 0.5) (drill 0.2) (layers "F.Cu" "B.Cu") (net 9))
  (via (at 139.776328 115.797157) (size 0.5) (drill 0.2) (layers "F.Cu" "B.Cu") (net 9))
  (via blind (at 194.636328 98.060008) (size 0.5) (drill 0.2) (layers "F.Cu" "In2.Cu") (net 9))
  (via (at 256.1 108.88) (size 0.5) (drill 0.2) (layers "F.Cu" "B.Cu") (net 9))
  (via (at 115.525 105) (size 0.5) (drill 0.2) (layers "F.Cu" "B.Cu") (net 9))
  (via (at 141.1 121.2) (size 0.5) (drill 0.2) (layers "F.Cu" "B.Cu") (net 9))
  (via (at 244.086328 56.55) (size 0.5) (drill 0.2) (layers "F.Cu" "B.Cu") (net 9))
  (via (at 203.9 73.3) (size 0.5) (drill 0.2) (layers "F.Cu" "B.Cu") (net 9))
  (via (at 191.636328 90.060008) (size 0.5) (drill 0.2) (layers "F.Cu" "B.Cu") (net 9))
  (via (at 237.7 124.8) (size 0.5) (drill 0.2) (layers "F.Cu" "B.Cu") (net 9))
  (via (at 231.775256 135.197157) (size 0.5) (drill 0.2) (layers "F.Cu" "B.Cu") (net 9))
  (via (at 211.45 58.35) (size 0.5) (drill 0.2) (layers "F.Cu" "B.Cu") (net 9))
  (via (at 258.740167 113.961843) (size 0.5) (drill 0.2) (layers "F.Cu" "B.Cu") (net 9))
  (via (at 258.740167 48.197157) (size 0.5) (drill 0.2) (layers "F.Cu" "B.Cu") (net 9))
  (via blind (at 207.55 61.15) (size 0.5) (drill 0.2) (layers "F.Cu" "In2.Cu") (net 9))
  (via (at 155.11 110.54) (size 0.5) (drill 0.2) (layers "F.Cu" "B.Cu") (net 9))
  (via (at 128.15 61.610008) (size 0.5) (drill 0.2) (layers "F.Cu" "B.Cu") (net 9))
  (via (at 137.679662 126.675) (size 0.5) (drill 0.2) (layers "F.Cu" "B.Cu") (net 9))
  (via (at 184.636328 86.060008) (size 0.5) (drill 0.2) (layers "F.Cu" "B.Cu") (net 9))
  (via (at 127 128.875) (size 0.5) (drill 0.2) (layers "F.Cu" "B.Cu") (net 9))
  (via (at 113.327852 46.897157) (size 0.5) (drill 0.2) (layers "F.Cu" "B.Cu") (net 9))
  (via (at 120.649884 46.897157) (size 0.5) (drill 0.2) (layers "F.Cu" "B.Cu") (net 9))
  (via (at 164.644576 46.897157) (size 0.5) (drill 0.2) (layers "F.Cu" "B.Cu") (net 9))
  (via (at 242.775256 135.197157) (size 0.5) (drill 0.2) (layers "F.Cu" "B.Cu") (net 9))
  (via (at 250.13458 135.197157) (size 0.5) (drill 0.2) (layers "F.Cu" "B.Cu") (net 9))
  (via (at 220.8 64.4) (size 0.5) (drill 0.2) (layers "F.Cu" "B.Cu") (net 9))
  (via (at 136.16751 120.16751) (size 0.5) (drill 0.2) (layers "F.Cu" "B.Cu") (net 9))
  (via (at 124.4 121.3) (size 0.5) (drill 0.2) (layers "F.Cu" "B.Cu") (net 9))
  (via (at 145.486328 56.75) (size 0.5) (drill 0.2) (layers "F.Cu" "B.Cu") (net 9))
  (via (at 139.1 131.575) (size 0.5) (drill 0.2) (layers "F.Cu" "B.Cu") (net 9))
  (via (at 253.5 93.7) (size 0.5) (drill 0.2) (layers "F.Cu" "B.Cu") (net 9))
  (via (at 124.21937 135.197157) (size 0.5) (drill 0.2) (layers "F.Cu" "B.Cu") (net 9))
  (via (at 258.3 69.6) (size 0.5) (drill 0.2) (layers "F.Cu" "B.Cu") (net 9))
  (via (at 144.296328 99.737157) (size 0.5) (drill 0.2) (layers "F.Cu" "B.Cu") (net 9))
  (via (at 152.875 100.05) (size 0.5) (drill 0.2) (layers "F.Cu" "B.Cu") (net 9))
  (via (at 254.8 121.64) (size 0.5) (drill 0.2) (layers "F.Cu" "B.Cu") (net 9))
  (via (at 254.8 81) (size 0.5) (drill 0.2) (layers "F.Cu" "B.Cu") (net 9))
  (via (at 117.286328 114.497157) (size 0.5) (drill 0.2) (layers "F.Cu" "B.Cu") (net 9))
  (via (at 256.1 111.38) (size 0.5) (drill 0.2) (layers "F.Cu" "B.Cu") (net 9))
  (via (at 210.1 53.8) (size 0.5) (drill 0.2) (layers "F.Cu" "B.Cu") (net 9))
  (via (at 197.87497 46.897157) (size 0.5) (drill 0.2) (layers "F.Cu" "B.Cu") (net 9))
  (via (at 211.45 61.6) (size 0.5) (drill 0.2) (layers "F.Cu" "B.Cu") (net 9))
  (via (at 137.904662 129.875) (size 0.5) (drill 0.2) (layers "F.Cu" "B.Cu") (net 9))
  (via (at 242.1 56.65) (size 0.5) (drill 0.2) (layers "F.Cu" "B.Cu") (net 9))
  (via (at 243.37 97.47) (size 0.5) (drill 0.2) (layers "F.Cu" "B.Cu") (net 9))
  (via (at 116.988868 46.897157) (size 0.5) (drill 0.2) (layers "F.Cu" "B.Cu") (net 9))
  (via (at 258.740167 54.942253) (size 0.5) (drill 0.2) (layers "F.Cu" "B.Cu") (net 9))
  (via (at 240.954918 135.197157) (size 0.5) (drill 0.2) (layers "F.Cu" "B.Cu") (net 9))
  (via (at 136.036328 87.660008) (size 0.5) (drill 0.2) (layers "F.Cu" "B.Cu") (net 9))
  (via (at 184.636328 88.060008) (size 0.5) (drill 0.2) (layers "F.Cu" "B.Cu") (net 9))
  (via (at 160.61 110.54) (size 0.5) (drill 0.2) (layers "F.Cu" "B.Cu") (net 9))
  (via blind (at 190.636328 99.060008) (size 0.5) (drill 0.2) (layers "F.Cu" "In2.Cu") (net 9))
  (via (at 124.7 88.1) (size 0.5) (drill 0.2) (layers "F.Cu" "B.Cu") (net 9))
  (via (at 216.336328 46.897157) (size 0.5) (drill 0.2) (layers "F.Cu" "B.Cu") (net 9))
  (via (at 185.636328 87.060008) (size 0.5) (drill 0.2) (layers "F.Cu" "B.Cu") (net 9))
  (via (at 213.6 57.2) (size 0.5) (drill 0.2) (layers "F.Cu" "B.Cu") (net 9))
  (via (at 151.45 53.8) (size 0.5) (drill 0.2) (layers "F.Cu" "B.Cu") (net 9))
  (via (at 132.443648 129.875) (size 0.5) (drill 0.2) (layers "F.Cu" "B.Cu") (net 9))
  (via (at 249.509502 46.897157) (size 0.5) (drill 0.2) (layers "F.Cu" "B.Cu") (net 9))
  (via (at 258.740167 53.255979) (size 0.5) (drill 0.2) (layers "F.Cu" "B.Cu") (net 9))
  (via (at 258.740167 61.687349) (size 0.5) (drill 0.2) (layers "F.Cu" "B.Cu") (net 9))
  (via (at 171.636328 96.060008) (size 0.5) (drill 0.2) (layers "F.Cu" "B.Cu") (net 9))
  (via (at 249.72 98.72) (size 0.5) (drill 0.2) (layers "F.Cu" "B.Cu") (net 9))
  (via (at 248.45 82.23) (size 0.5) (drill 0.2) (layers "F.Cu" "B.Cu") (net 9))
  (via (at 158.7 58.4) (size 0.5) (drill 0.2) (layers "F.Cu" "B.Cu") (net 9))
  (via (at 127.971916 46.897157) (size 0.5) (drill 0.2) (layers "F.Cu" "B.Cu") (net 9))
  (via (at 250.925 121.7) (size 0.5) (drill 0.2) (layers "F.Cu" "B.Cu") (net 9))
  (via (at 195.212552 135.197157) (size 0.5) (drill 0.2) (layers "F.Cu" "B.Cu") (net 9))
  (via (at 255.3 69.6) (size 0.5) (drill 0.2) (layers "F.Cu" "B.Cu") (net 9))
  (via (at 180.636328 82.0405) (size 0.5) (drill 0.2) (layers "F.Cu" "B.Cu") (net 9))
  (via (at 161.72 110.53) (size 0.5) (drill 0.2) (layers "F.Cu" "B.Cu") (net 9))
  (via (at 157 101.525) (size 0.5) (drill 0.2) (layers "F.Cu" "B.Cu") (net 9))
  (via (at 147.89 131.16) (size 0.5) (drill 0.2) (layers "F.Cu" "B.Cu") (net 9))
  (via (at 111.179992 65.160008) (size 0.5) (drill 0.2) (layers "F.Cu" "B.Cu") (net 9))
  (via (at 182.636328 99.060008) (size 0.5) (drill 0.2) (layers "F.Cu" "B.Cu") (net 9))
  (via (at 164.186328 61.010008) (size 0.5) (drill 0.2) (layers "F.Cu" "B.Cu") (net 9))
  (via (at 243.799831 58.410509) (size 0.5) (drill 0.2) (layers "F.Cu" "B.Cu") (net 9))
  (via (at 114.9 105) (size 0.5) (drill 0.2) (layers "F.Cu" "B.Cu") (net 9))
  (via (at 243.37 101.28) (size 0.5) (drill 0.2) (layers "F.Cu" "B.Cu") (net 9))
  (via (at 107.936328 83.255969) (size 0.5) (drill 0.2) (layers "F.Cu" "B.Cu") (net 9))
  (via (at 188.636328 89.060008) (size 0.5) (drill 0.2) (layers "F.Cu" "B.Cu") (net 9))
  (via blind (at 196.6 95.0505) (size 0.5) (drill 0.2) (layers "F.Cu" "In2.Cu") (net 9))
  (via (at 195.636328 92.060008) (size 0.5) (drill 0.2) (layers "F.Cu" "B.Cu") (net 9))
  (via (at 116.125 105) (size 0.5) (drill 0.2) (layers "F.Cu" "B.Cu") (net 9))
  (via (at 251.65 125.76) (size 0.5) (drill 0.2) (layers "F.Cu" "B.Cu") (net 9))
  (via (at 186.636328 89.060008) (size 0.5) (drill 0.2) (layers "F.Cu" "B.Cu") (net 9))
  (via (at 259.05 107.216747) (size 0.5) (drill 0.2) (layers "F.Cu" "B.Cu") (net 9))
  (via (at 156.22 110.53) (size 0.5) (drill 0.2) (layers "F.Cu" "B.Cu") (net 9))
  (via (at 239.6 58.4) (size 0.5) (drill 0.2) (layers "F.Cu" "B.Cu") (net 9))
  (via (at 182.636328 91.060008) (size 0.5) (drill 0.2) (layers "F.Cu" "B.Cu") (net 9))
  (via (at 230.15 61.55) (size 0.5) (drill 0.2) (layers "F.Cu" "B.Cu") (net 9))
  (via (at 107.936328 79.793225) (size 0.5) (drill 0.2) (layers "F.Cu" "B.Cu") (net 9))
  (via (at 109.036328 114.872157) (size 0.5) (drill 0.2) (layers "F.Cu" "B.Cu") (net 9))
  (via (at 251.1 85.9995) (size 0.5) (drill 0.2) (layers "F.Cu" "B.Cu") (net 9))
  (via (at 156.2 61.55) (size 0.5) (drill 0.2) (layers "F.Cu" "B.Cu") (net 9))
  (via (at 142.7 61.65) (size 0.5) (drill 0.2) (layers "F.Cu" "B.Cu") (net 9))
  (via (at 226.348047 88.9) (size 0.5) (drill 0.2) (layers "F.Cu" "B.Cu") (net 9))
  (via (at 107.936328 46.897157) (size 0.5) (drill 0.2) (layers "F.Cu" "B.Cu") (net 9))
  (via (at 122.09 88.7) (size 0.5) (drill 0.2) (layers "F.Cu" "B.Cu") (net 9))
  (via (at 166.041 76.407) (size 0.5) (drill 0.2) (layers "F.Cu" "B.Cu") (net 9))
  (via (at 163.710531 106.325475) (size 0.5) (drill 0.2) (layers "F.Cu" "B.Cu") (net 9))
  (via (at 138.3 128.15) (size 0.5) (drill 0.2) (layers "F.Cu" "B.Cu") (net 9))
  (via (at 126.141408 46.897157) (size 0.5) (drill 0.2) (layers "F.Cu" "B.Cu") (net 9))
  (via (at 163.986328 57.610008) (size 0.5) (drill 0.2) (layers "F.Cu" "B.Cu") (net 9))
  (via (at 192.658 97.07) (size 0.5) (drill 0.2) (layers "F.Cu" "B.Cu") (net 9))
  (via (at 136.036328 114.372157) (size 0.5) (drill 0.2) (layers "F.Cu" "B.Cu") (net 9))
  (via (at 233.2 112.5) (size 0.5) (drill 0.2) (layers "F.Cu" "B.Cu") (net 9))
  (via (at 228.55 64.35) (size 0.5) (drill 0.2) (layers "F.Cu" "B.Cu") (net 9))
  (via (at 133.32106 135.197157) (size 0.5) (drill 0.2) (layers "F.Cu" "B.Cu") (net 9))
  (via blind (at 194.6 94.0505) (size 0.5) (drill 0.2) (layers "F.Cu" "In2.Cu") (net 9))
  (via (at 254.8 91.16) (size 0.5) (drill 0.2) (layers "F.Cu" "B.Cu") (net 9))
  (via (at 179.636328 100.060008) (size 0.5) (drill 0.2) (layers "F.Cu" "B.Cu") (net 9))
  (via (at 149.77 131.16) (size 0.5) (drill 0.2) (layers "F.Cu" "B.Cu") (net 9))
  (via (at 258.740167 49.883431) (size 0.5) (drill 0.2) (layers "F.Cu" "B.Cu") (net 9))
  (via (at 138.782074 135.197157) (size 0.5) (drill 0.2) (layers "F.Cu" "B.Cu") (net 9))
  (via (at 158.68 105.78) (size 0.5) (drill 0.2) (layers "F.Cu" "B.Cu") (net 9))
  (via (at 195.655836 84.060008) (size 0.5) (drill 0.2) (layers "F.Cu" "B.Cu") (net 9))
  (via (at 165.45 99.4) (size 0.5) (drill 0.2) (layers "F.Cu" "B.Cu") (net 9))
  (via (at 255.8 62) (size 0.5) (drill 0.2) (layers "F.Cu" "B.Cu") (net 9))
  (via (at 124.2 97.925) (size 0.5) (drill 0.2) (layers "F.Cu" "B.Cu") (net 9))
  (via (at 258.740167 86.981459) (size 0.5) (drill 0.2) (layers "F.Cu" "B.Cu") (net 9))
  (via (at 249.72 87.29) (size 0.5) (drill 0.2) (layers "F.Cu" "B.Cu") (net 9))
  (via (at 107.936328 119.614781) (size 0.5) (drill 0.2) (layers "F.Cu" "B.Cu") (net 9))
  (via (at 254.8 116.5) (size 0.5) (drill 0.2) (layers "F.Cu" "B.Cu") (net 9))
  (via (at 186.110862 135.197157) (size 0.5) (drill 0.2) (layers "F.Cu" "B.Cu") (net 9))
  (via (at 180.636328 103.060008) (size 0.5) (drill 0.2) (layers "F.Cu" "B.Cu") (net 9))
  (via (at 141.85 58.35) (size 0.5) (drill 0.2) (layers "F.Cu" "B.Cu") (net 9))
  (via (at 184.636328 84.0405) (size 0.5) (drill 0.2) (layers "F.Cu" "B.Cu") (net 9))
  (via (at 132.736328 53.813672) (size 0.5) (drill 0.2) (layers "F.Cu" "B.Cu") (net 9))
  (via (at 210.086328 57.010008) (size 0.5) (drill 0.2) (layers "F.Cu" "B.Cu") (net 9))
  (via (at 216.932356 89.05) (size 0.5) (drill 0.2) (layers "F.Cu" "B.Cu") (net 9))
  (via (at 258.740167 85.295185) (size 0.5) (drill 0.2) (layers "F.Cu" "B.Cu") (net 9))
  (via (at 179.636328 90.060008) (size 0.5) (drill 0.2) (layers "F.Cu" "B.Cu") (net 9))
  (via (at 225.5 125.8) (size 0.5) (drill 0.2) (layers "F.Cu" "B.Cu") (net 9))
  (via (at 130.08 108.81) (size 0.5) (drill 0.2) (layers "F.Cu" "B.Cu") (net 9))
  (via (at 234.736328 53.813672) (size 0.5) (drill 0.2) (layers "F.Cu" "B.Cu") (net 9))
  (via (at 232.913369 46.897157) (size 0.5) (drill 0.2) (layers "F.Cu" "B.Cu") (net 9))
  (via blind (at 205.836328 61.2) (size 0.5) (drill 0.2) (layers "F.Cu" "In5.Cu") (net 9))
  (via (at 258.740167 56.628527) (size 0.5) (drill 0.2) (layers "F.Cu" "B.Cu") (net 9))
  (via (at 238.94 78.39) (size 0.5) (drill 0.2) (layers "F.Cu" "B.Cu") (net 9))
  (via (at 230.41 83.26) (size 0.5) (drill 0.2) (layers "F.Cu" "B.Cu") (net 9))
  (via (at 107.88 107.5) (size 0.5) (drill 0.2) (layers "F.Cu" "B.Cu") (net 9))
  (via (at 114.911328 92.372157) (size 0.5) (drill 0.2) (layers "F.Cu" "B.Cu") (net 9))
  (via (at 230.25 104.7) (size 0.5) (drill 0.2) (layers "F.Cu" "B.Cu") (net 9))
  (via (at 228.786328 53.813672) (size 0.5) (drill 0.2) (layers "F.Cu" "B.Cu") (net 9))
  (via (at 205.259502 46.897157) (size 0.5) (drill 0.2) (layers "F.Cu" "B.Cu") (net 9))
  (via (at 249.72 102.53) (size 0.5) (drill 0.2) (layers "F.Cu" "B.Cu") (net 9))
  (via (at 148.4 61.5) (size 0.5) (drill 0.2) (layers "F.Cu" "B.Cu") (net 9))
  (via (at 253.775256 135.197157) (size 0.5) (drill 0.2) (layers "F.Cu" "B.Cu") (net 9))
  (via (at 165.886328 53.710008) (size 0.5) (drill 0.2) (layers "F.Cu" "B.Cu") (net 9))
  (via (at 190.655836 79.060008) (size 0.5) (drill 0.2) (layers "F.Cu" "B.Cu") (net 9))
  (via (at 128.486328 53.813672) (size 0.5) (drill 0.2) (layers "F.Cu" "B.Cu") (net 9))
  (via (at 133.46344 46.897157) (size 0.5) (drill 0.2) (layers "F.Cu" "B.Cu") (net 9))
  (via (at 137.55 71.2) (size 0.5) (drill 0.2) (layers "F.Cu" "B.Cu") (net 9))
  (via (at 225.547901 46.897157) (size 0.5) (drill 0.2) (layers "F.Cu" "B.Cu") (net 9))
  (via (at 256.09 101.57) (size 0.5) (drill 0.2) (layers "F.Cu" "B.Cu") (net 9))
  (via (at 190.567128 57.468608) (size 0.5) (drill 0.2) (layers "F.Cu" "B.Cu") (net 9))
  (via (at 170.636328 93.060008) (size 0.5) (drill 0.2) (layers "F.Cu" "B.Cu") (net 9))
  (via (at 172.636328 99.060008) (size 0.5) (drill 0.2) (layers "F.Cu" "B.Cu") (net 9))
  (via (at 256.2 64.5) (size 0.5) (drill 0.2) (layers "F.Cu" "B.Cu") (net 9))
  (via (at 107.936328 133.465757) (size 0.5) (drill 0.2) (layers "F.Cu" "B.Cu") (net 9))
  (via (at 253.2 75.9) (size 0.5) (drill 0.2) (layers "F.Cu" "B.Cu") (net 9))
  (via (at 177.567507 46.897157) (size 0.5) (drill 0.2) (layers "F.Cu" "B.Cu") (net 9))
  (via (at 217.75 100.95) (size 0.5) (drill 0.2) (layers "F.Cu" "B.Cu") (net 9))
  (via (at 193.459548 78.081816) (size 0.5) (drill 0.2) (layers "F.Cu" "B.Cu") (net 9))
  (via (at 217.322873 87.877127) (size 0.5) (drill 0.2) (layers "F.Cu" "B.Cu") (net 9))
  (via (at 157.025 102.8) (size 0.5) (drill 0.2) (layers "F.Cu" "B.Cu") (net 9))
  (via (at 115.15836 46.897157) (size 0.5) (drill 0.2) (layers "F.Cu" "B.Cu") (net 9))
  (via (at 185.05 56.8) (size 0.5) (drill 0.2) (layers "F.Cu" "B.Cu") (net 9))
  (via (at 192.7 101.05) (size 0.5) (drill 0.2) (layers "F.Cu" "B.Cu") (net 9))
  (via (at 240.832829 61.6) (size 0.5) (drill 0.2) (layers "F.Cu" "B.Cu") (net 9))
  (via (at 235.415932 135.197157) (size 0.5) (drill 0.2) (layers "F.Cu" "B.Cu") (net 9))
  (via (at 252.3 105.15) (size 0.5) (drill 0.2) (layers "F.Cu" "B.Cu") (net 9))
  (via (at 107.936328 93.644201) (size 0.5) (drill 0.2) (layers "F.Cu" "B.Cu") (net 9))
  (via (at 153.2 126.4) (size 0.5) (drill 0.2) (layers "F.Cu" "B.Cu") (net 9))
  (via (at 111.497344 46.897157) (size 0.5) (drill 0.2) (layers "F.Cu" "B.Cu") (net 9))
  (via (at 247.18 98.72) (size 0.5) (drill 0.2) (layers "F.Cu" "B.Cu") (net 9))
  (via (at 256.1 83.48) (size 0.5) (drill 0.2) (layers "F.Cu" "B.Cu") (net 9))
  (via (at 258.740167 120.706939) (size 0.5) (drill 0.2) (layers "F.Cu" "B.Cu") (net 9))
  (via (at 259.05 93.726555) (size 0.5) (drill 0.2) (layers "F.Cu" "B.Cu") (net 9))
  (via (at 107.936328 131.734385) (size 0.5) (drill 0.2) (layers "F.Cu" "B.Cu") (net 9))
  (via (at 258.740167 112.275569) (size 0.5) (drill 0.2) (layers "F.Cu" "B.Cu") (net 9))
  (via (at 119.75 102.125) (size 0.5) (drill 0.2) (layers "F.Cu" "B.Cu") (net 9))
  (via (at 114.336328 77.660008) (size 0.5) (drill 0.2) (layers "F.Cu" "B.Cu") (net 9))
  (via (at 125.086328 56.65) (size 0.5) (drill 0.2) (layers "F.Cu" "B.Cu") (net 9))
  (via (at 124 129.375) (size 0.5) (drill 0.2) (layers "F.Cu" "B.Cu") (net 9))
  (via (at 133.063986 131.775) (size 0.5) (drill 0.2) (layers "F.Cu" "B.Cu") (net 9))
  (via (at 257.3 62) (size 0.5) (drill 0.2) (layers "F.Cu" "B.Cu") (net 9))
  (via (at 123.65 117.55) (size 0.5) (drill 0.2) (layers "F.Cu" "B.Cu") (net 9))
  (via (at 257.8 64.5) (size 0.5) (drill 0.2) (layers "F.Cu" "B.Cu") (net 9))
  (via (at 242.57 121.37) (size 0.5) (drill 0.2) (layers "F.Cu" "B.Cu") (net 9))
  (via (at 245.5 58.4) (size 0.5) (drill 0.2) (layers "F.Cu" "B.Cu") (net 9))
  (via (at 187.976328 57.468608) (size 0.5) (drill 0.2) (layers "F.Cu" "B.Cu") (net 9))
  (via (at 130.136328 91.040008) (size 0.5) (drill 0.2) (layers "F.Cu" "B.Cu") (net 9))
  (via (at 255.1 75.9) (size 0.5) (drill 0.2) (layers "F.Cu" "B.Cu") (net 9))
  (via (at 146.85 61.5) (size 0.5) (drill 0.2) (layers "F.Cu" "B.Cu") (net 9))
  (via (at 245.91 116.52) (size 0.5) (drill 0.2) (layers "F.Cu" "B.Cu") (net 9))
  (via (at 179.41364 46.897157) (size 0.5) (drill 0.2) (layers "F.Cu" "B.Cu") (net 9))
  (via (at 202.75 56.65) (size 0.5) (drill 0.2) (layers "F.Cu" "B.Cu") (net 9))
  (via (at 126.375 129.375) (size 0.5) (drill 0.2) (layers "F.Cu" "B.Cu") (net 9))
  (via (at 244.67 124.12) (size 0.5) (drill 0.2) (layers "F.Cu" "B.Cu") (net 9))
  (via (at 209.775256 135.197157) (size 0.5) (drill 0.2) (layers "F.Cu" "B.Cu") (net 9))
  (via (at 255.248574 88.575428) (size 0.5) (drill 0.2) (layers "F.Cu" "B.Cu") (net 9))
  (via (at 255.3 66.227452) (size 0.5) (drill 0.2) (layers "F.Cu" "B.Cu") (net 9))
  (via (at 155.1 135.175) (size 0.5) (drill 0.2) (layers "F.Cu" "B.Cu") (net 9))
  (via (at 231.64 80.43) (size 0.5) (drill 0.2) (layers "F.Cu" "B.Cu") (net 9))
  (via (at 244.64 91.1) (size 0.5) (drill 0.2) (layers "F.Cu" "B.Cu") (net 9))
  (via (at 181.636328 96.060008) (size 0.5) (drill 0.2) (layers "F.Cu" "B.Cu") (net 9))
  (via (at 135.83 103.021657) (size 0.5) (drill 0.2) (layers "F.Cu" "B.Cu") (net 9))
  (via blind (at 191.636328 103.060008) (size 0.5) (drill 0.2) (layers "F.Cu" "In2.Cu") (net 9))
  (via (at 220.85 61.6) (size 0.5) (drill 0.2) (layers "F.Cu" "B.Cu") (net 9))
  (via (at 134.038986 126.675) (size 0.5) (drill 0.2) (layers "F.Cu" "B.Cu") (net 9))
  (via (at 188.636328 94.060008) (size 0.5) (drill 0.2) (layers "F.Cu" "B.Cu") (net 9))
  (via (at 189.636328 86.060008) (size 0.5) (drill 0.2) (layers "F.Cu" "B.Cu") (net 9))
  (via (at 152.8305 105.54) (size 0.5) (drill 0.2) (layers "F.Cu" "B.Cu") (net 9))
  (via (at 190.5 114.7) (size 0.5) (drill 0.2) (layers "F.Cu" "B.Cu") (free) (net 9))
  (via (at 243.990167 46.897157) (size 0.5) (drill 0.2) (layers "F.Cu" "B.Cu") (net 9))
  (via (at 117.725 96.65) (size 0.5) (drill 0.2) (layers "F.Cu" "B.Cu") (net 9))
  (via (at 107.936328 71.136365) (size 0.5) (drill 0.2) (layers "F.Cu" "B.Cu") (net 9))
  (via (at 254.8 111.48) (size 0.5) (drill 0.2) (layers "F.Cu" "B.Cu") (net 9))
  (via (at 148.85 126.562) (size 0.5) (drill 0.2) (layers "F.Cu" "B.Cu") (net 9))
  (via (at 120.25 103.125) (size 0.5) (drill 0.2) (layers "F.Cu" "B.Cu") (net 9))
  (via (at 210.18726 89.05) (size 0.5) (drill 0.2) (layers "F.Cu" "B.Cu") (net 9))
  (via (at 136.4645 97.37) (size 0.5) (drill 0.2) (layers "F.Cu" "B.Cu") (net 9))
  (via (at 236.436328 56.5) (size 0.5) (drill 0.2) (layers "F.Cu" "B.Cu") (net 9))
  (via (at 173.636328 92.060008) (size 0.5) (drill 0.2) (layers "F.Cu" "B.Cu") (net 9))
  (via (at 249.72 94.91) (size 0.5) (drill 0.2) (layers "F.Cu" "B.Cu") (net 9))
  (via (at 132.275 133.35) (size 0.5) (drill 0.2) (layers "F.Cu" "B.Cu") (net 9))
  (via (at 227.1 53.8) (size 0.5) (drill 0.2) (layers "F.Cu" "B.Cu") (net 9))
  (via (at 239.6 61.6) (size 0.5) (drill 0.2) (layers "F.Cu" "B.Cu") (net 9))
  (via (at 243.37 112.71) (size 0.5) (drill 0.2) (layers "F.Cu" "B.Cu") (net 9))
  (via (at 252.3 112.7) (size 0.5) (drill 0.2) (layers "F.Cu" "B.Cu") (net 9))
  (via (at 119 119.6) (size 0.5) (drill 0.2) (layers "F.Cu" "B.Cu") (net 9))
  (via (at 188.6 103.2) (size 0.5) (drill 0.2) (layers "F.Cu" "B.Cu") (net 9))
  (via blind (at 125.95 61.25) (size 0.5) (drill 0.2) (layers "F.Cu" "In5.Cu") (net 9))
  (via (at 259.2 70.118719) (size 0.5) (drill 0.2) (layers "F.Cu" "B.Cu") (net 9))
  (via (at 107.936328 97.106945) (size 0.5) (drill 0.2) (layers "F.Cu" "B.Cu") (net 9))
  (via (at 189.751538 135.197157) (size 0.5) (drill 0.2) (layers "F.Cu" "B.Cu") (net 9))
  (via (at 230.5 53.8) (size 0.5) (drill 0.2) (layers "F.Cu" "B.Cu") (net 9))
  (via (at 139.525 124.475) (size 0.5) (drill 0.2) (layers "F.Cu" "B.Cu") (free) (net 9))
  (via (at 206.814712 89.05) (size 0.5) (drill 0.2) (layers "F.Cu" "B.Cu") (net 9))
  (via (at 193.4 105.1) (size 0.5) (drill 0.2) (layers "F.Cu" "B.Cu") (net 9))
  (via (at 245.925 119.375) (size 0.5) (drill 0.2) (layers "F.Cu" "B.Cu") (net 9))
  (via (at 114.936328 78.260008) (size 0.5) (drill 0.2) (layers "F.Cu" "B.Cu") (net 9))
  (via (at 191.571876 135.197157) (size 0.5) (drill 0.2) (layers "F.Cu" "B.Cu") (net 9))
  (via (at 142.086328 53.813672) (size 0.5) (drill 0.2) (layers "F.Cu" "B.Cu") (net 9))
  (via (at 107.936328 116.152037) (size 0.5) (drill 0.2) (layers "F.Cu" "B.Cu") (net 9))
  (via (at 258.740167 46.897157) (size 0.5) (drill 0.2) (layers "F.Cu" "B.Cu") (net 9))
  (via (at 107.936328 110.957921) (size 0.5) (drill 0.2) (layers "F.Cu" "B.Cu") (net 9))
  (via (at 256.044979 98.37846) (size 0.5) (drill 0.2) (layers "F.Cu" "B.Cu") (net 9))
  (via (at 192.636328 89.060008) (size 0.5) (drill 0.2) (layers "F.Cu" "B.Cu") (net 9))
  (via (at 230.25 58.4) (size 0.5) (drill 0.2) (layers "F.Cu" "B.Cu") (net 9))
  (via (at 253.53 106.33) (size 0.5) (drill 0.2) (layers "F.Cu" "B.Cu") (net 9))
  (via (at 244.64 87.29) (size 0.5) (drill 0.2) (layers "F.Cu" "B.Cu") (net 9))
  (via (at 247.663369 46.897157) (size 0.5) (drill 0.2) (layers "F.Cu" "B.Cu") (net 9))
  (via (at 182.636328 88.060008) (size 0.5) (drill 0.2) (layers "F.Cu" "B.Cu") (net 9))
  (via (at 126.039708 135.197157) (size 0.5) (drill 0.2) (layers "F.Cu" "B.Cu") (net 9))
  (via (at 167.05 110.25) (size 0.5) (drill 0.2) (layers "F.Cu" "B.Cu") (net 9))
  (via (at 130.6 58.4) (size 0.5) (drill 0.2) (layers "F.Cu" "B.Cu") (net 9))
  (via (at 172.636328 88.060009) (size 0.5) (drill 0.2) (layers "F.Cu" "B.Cu") (net 9))
  (via (at 126.25 104.6) (size 0.5) (drill 0.2) (layers "F.Cu" "B.Cu") (net 9))
  (via (at 156.985454 135.197157) (size 0.5) (drill 0.2) (layers "F.Cu" "B.Cu") (net 9))
  (via (at 221.136328 53.813672) (size 0.5) (drill 0.2) (layers "F.Cu" "B.Cu") (net 9))
  (via blind (at 218.119872 61.856972) (size 0.5) (drill 0.2) (layers "F.Cu" "In2.Cu") (net 9))
  (via (at 183.636328 87.060008) (size 0.5) (drill 0.2) (layers "F.Cu" "B.Cu") (net 9))
  (via (at 204.6 58.4) (size 0.5) (drill 0.2) (layers "F.Cu" "B.Cu") (net 9))
  (via (at 169.8 91.75) (size 0.5) (drill 0.2) (layers "F.Cu" "B.Cu") (net 9))
  (via (at 226.5243 124.659989) (size 0.5) (drill 0.2) (layers "F.Cu" "B.Cu") (net 9))
  (via (at 147.883764 135.197157) (size 0.5) (drill 0.2) (layers "F.Cu" "B.Cu") (net 9))
  (via (at 107.936328 91.912829) (size 0.5) (drill 0.2) (layers "F.Cu" "B.Cu") (net 9))
  (via (at 251.995071 73.491267) (size 0.5) (drill 0.2) (layers "F.Cu" "B.Cu") (net 9))
  (via (at 243.37 105.09) (size 0.5) (drill 0.2) (layers "F.Cu" "B.Cu") (net 9))
  (via (at 219.15 58.35) (size 0.5) (drill 0.2) (layers "F.Cu" "B.Cu") (net 9))
  (via (at 222.932371 88.9) (size 0.5) (drill 0.2) (layers "F.Cu" "B.Cu") (net 9))
  (via (at 112.25 99.5) (size 0.5) (drill 0.2) (layers "F.Cu" "B.Cu") (net 9))
  (via (at 138.9935 61.55) (size 0.5) (drill 0.2) (layers "F.Cu" "B.Cu") (net 9))
  (via (at 192.878528 57.468608) (size 0.5) (drill 0.2) (layers "F.Cu" "B.Cu") (net 9))
  (via (at 200.45 58.4) (size 0.5) (drill 0.2) (layers "F.Cu" "B.Cu") (net 9))
  (via (at 193.636328 96.060008) (size 0.5) (drill 0.2) (layers "F.Cu" "B.Cu") (net 9))
  (via (at 243.37 116.52) (size 0.5) (drill 0.2) (layers "F.Cu" "B.Cu") (net 9))
  (via (at 233.6 78.4) (size 0.5) (drill 0.2) (layers "F.Cu" "B.Cu") (net 9))
  (via (at 241.8 104.95) (size 0.5) (drill 0.2) (layers "F.Cu" "B.Cu") (net 9))
  (via (at 181.8 52.93) (size 0.5) (drill 0.2) (layers "F.Cu" "B.Cu") (net 9))
  (via (at 199.05 53.55) (size 0.5) (drill 0.2) (layers "F.Cu" "B.Cu") (net 9))
  (via (at 130.5 74.9) (size 0.5) (drill 0.2) (layers "F.Cu" "B.Cu") (net 9))
  (via (at 254.8 93.66) (size 0.5) (drill 0.2) (layers "F.Cu" "B.Cu") (net 9))
  (via (at 156.686328 89.160008) (size 0.5) (drill 0.2) (layers "F.Cu" "B.Cu") (net 9))
  (via (at 173.875241 46.897157) (size 0.5) (drill 0.2) (layers "F.Cu" "B.Cu") (net 9))
  (via (at 152.849831 58.410509) (size 0.5) (drill 0.2) (layers "F.Cu" "B.Cu") (net 9))
  (via (at 107.936328 105.763805) (size 0.5) (drill 0.2) (layers "F.Cu" "B.Cu") (net 9))
  (via (at 253.5 91.1) (size 0.5) (drill 0.2) (layers "F.Cu" "B.Cu") (net 9))
  (via (at 169.72782 135.197157) (size 0.5) (drill 0.2) (layers "F.Cu" "B.Cu") (net 9))
  (via (at 168.65 91.7) (size 0.5) (drill 0.2) (layers "F.Cu" "B.Cu") (net 9))
  (via (at 144.446488 46.897157) (size 0.5) (drill 0.2) (layers "F.Cu" "B.Cu") (net 9))
  (via (at 163.110002 110.54) (size 0.5) (drill 0.2) (layers "F.Cu" "B.Cu") (net 9))
  (via (at 254.8 103.82) (size 0.5) (drill 0.2) (layers "F.Cu" "B.Cu") (net 9))
  (via (at 153.136328 53.813672) (size 0.5) (drill 0.2) (layers "F.Cu" "B.Cu") (net 9))
  (via (at 143.45 58.4) (size 0.5) (drill 0.2) (layers "F.Cu" "B.Cu") (net 9))
  (via (at 256.07 96.52) (size 0.5) (drill 0.2) (layers "F.Cu" "B.Cu") (net 9))
  (via (at 126.1 100.997157) (size 0.5) (drill 0.2) (layers "F.Cu" "B.Cu") (net 9))
  (via (at 219.436328 56.6) (size 0.5) (drill 0.2) (layers "F.Cu" "B.Cu") (net 9))
  (via blind (at 193.636328 94.060008) (size 0.5) (drill 0.2) (layers "F.Cu" "In2.Cu") (net 9))
  (via (at 258.740167 132.510857) (size 0.5) (drill 0.2) (layers "F.Cu" "B.Cu") (net 9))
  (via (at 146.186328 88.360008) (size 0.5) (drill 0.2) (layers "F.Cu" "B.Cu") (net 9))
  (via (at 159.286328 91.510008) (size 0.5) (drill 0.2) (layers "F.Cu" "B.Cu") (net 9))
  (via (at 119.75 103.125) (size 0.5) (drill 0.2) (layers "F.Cu" "B.Cu") (net 9))
  (via (at 173.636328 102.060008) (size 0.5) (drill 0.2) (layers "F.Cu" "B.Cu") (net 9))
  (via (at 254.15 89.85) (size 0.5) (drill 0.2) (layers "F.Cu" "B.Cu") (net 9))
  (via (at 242.77 75.96) (size 0.5) (drill 0.2) (layers "F.Cu" "B.Cu") (net 9))
  (via (at 249.72 106.34) (size 0.5) (drill 0.2) (layers "F.Cu" "B.Cu") (net 9))
  (via (at 112.25 100.125) (size 0.5) (drill 0.2) (layers "F.Cu" "B.Cu") (net 9))
  (via (at 107.936328 117.883409) (size 0.5) (drill 0.2) (layers "F.Cu" "B.Cu") (net 9))
  (via blind (at 195.61 90.060008) (size 0.5) (drill 0.2) (layers "F.Cu" "In2.Cu") (net 9))
  (via (at 126.3 70.8) (size 0.5) (drill 0.2) (layers "F.Cu" "B.Cu") (net 9))
  (via (at 152.35 110.875) (size 0.5) (drill 0.2) (layers "F.Cu" "B.Cu") (net 9))
  (via (at 185.436328 53.531608) (size 0.5) (drill 0.2) (layers "F.Cu" "B.Cu") (net 9))
  (via (at 140.785472 46.897157) (size 0.5) (drill 0.2) (layers "F.Cu" "B.Cu") (net 9))
  (via (at 186.636328 87.060008) (size 0.5) (drill 0.2) (layers "F.Cu" "B.Cu") (net 9))
  (via (at 136.136328 53.813672) (size 0.5) (drill 0.2) (layers "F.Cu" "B.Cu") (net 9))
  (via (at 251.975 108.9) (size 0.5) (drill 0.2) (layers "F.Cu" "B.Cu") (net 9))
  (via (at 147.2 69.25) (size 0.5) (drill 0.2) (layers "F.Cu" "B.Cu") (net 9))
  (via blind (at 215.186328 61.3) (size 0.5) (drill 0.2) (layers "F.Cu" "In2.Cu") (net 9))
  (via (at 111.280008 63.160008) (size 0.5) (drill 0.2) (layers "F.Cu" "B.Cu") (net 9))
  (via (at 190.5 114.1) (size 0.5) (drill 0.2) (layers "F.Cu" "B.Cu") (free) (net 9))
  (via (at 247.55 127.1) (size 0.5) (drill 0.2) (layers "F.Cu" "B.Cu") (free) (net 9))
  (via (at 254.8 83.5) (size 0.5) (drill 0.2) (layers "F.Cu" "B.Cu") (net 9))
  (via (at 129.686328 92.410008) (size 0.5) (drill 0.2) (layers "F.Cu" "B.Cu") (net 9))
  (via (at 159.934 77.692) (size 0.5) (drill 0.2) (layers "F.Cu" "B.Cu") (net 9))
  (via (at 204.986328 53.813672) (size 0.5) (drill 0.2) (layers "F.Cu" "B.Cu") (net 9))
  (via (at 184.636328 89.060008) (size 0.5) (drill 0.2) (layers "F.Cu" "B.Cu") (net 9))
  (via (at 156.400167 98.625167) (size 0.5) (drill 0.2) (layers "F.Cu" "B.Cu") (net 9))
  (via (at 259.2315 76.861546) (size 0.5) (drill 0.2) (layers "F.Cu" "B.Cu") (net 9))
  (via (at 248.45 105.09) (size 0.5) (drill 0.2) (layers "F.Cu" "B.Cu") (net 9))
  (via (at 256.1 116.46) (size 0.5) (drill 0.2) (layers "F.Cu" "B.Cu") (net 9))
  (via (at 107.936328 128.271641) (size 0.5) (drill 0.2) (layers "F.Cu" "B.Cu") (net 9))
  (via (at 225.1 58.4) (size 0.5) (drill 0.2) (layers "F.Cu" "B.Cu") (net 9))
  (via (at 183.636328 89.060008) (size 0.5) (drill 0.2) (layers "F.Cu" "B.Cu") (net 9))
  (via (at 234.759502 46.897157) (size 0.5) (drill 0.2) (layers "F.Cu" "B.Cu") (net 9))
  (via (at 241 86.96) (size 0.5) (drill 0.2) (layers "F.Cu" "B.Cu") (net 9))
  (via (at 223.8 121.5) (size 0.5) (drill 0.2) (layers "F.Cu" "B.Cu") (net 9))
  (via (at 258.740167 125.765761) (size 0.5) (drill 0.2) (layers "F.Cu" "B.Cu") (net 9))
  (via (at 245.15 72) (size 0.5) (drill 0.2) (layers "F.Cu" "B.Cu") (net 9))
  (via (at 114.411328 94.122157) (size 0.5) (drill 0.2) (layers "F.Cu" "B.Cu") (net 9))
  (via (at 217.45 58.4) (size 0.5) (drill 0.2) (layers "F.Cu" "B.Cu") (net 9))
  (via (at 247.175 121.35) (size 0.5) (drill 0.2) (layers "F.Cu" "B.Cu") (net 9))
  (via (at 226.65 100.95) (size 0.5) (drill 0.2) (layers "F.Cu" "B.Cu") (net 9))
  (via (at 232.2 72) (size 0.5) (drill 0.2) (layers "F.Cu" "B.Cu") (net 9))
  (via (at 258.740167 117.334391) (size 0.5) (drill 0.2) (layers "F.Cu" "B.Cu") (net 9))
  (via (at 142.61598 46.897157) (size 0.5) (drill 0.2) (layers "F.Cu" "B.Cu") (net 9))
  (via (at 224.507624 80.692376) (size 0.5) (drill 0.2) (layers "F.Cu" "B.Cu") (net 9))
  (via (at 225.65 104.7) (size 0.5) (drill 0.2) (layers "F.Cu" "B.Cu") (net 9))
  (via (at 198.4 61.6) (size 0.5) (drill 0.2) (layers "F.Cu" "B.Cu") (net 9))
  (via (at 140.1 58.35) (size 0.5) (drill 0.2) (layers "F.Cu" "B.Cu") (net 9))
  (via (at 254.8 119.06) (size 0.5) (drill 0.2) (layers "F.Cu" "B.Cu") (net 9))
  (via (at 107.936328 98.838317) (size 0.5) (drill 0.2) (layers "F.Cu" "B.Cu") (net 9))
  (via (at 107.936328 123.077525) (size 0.5) (drill 0.2) (layers "F.Cu" "B.Cu") (free) (net 9))
  (via (at 249.72 110.15) (size 0.5) (drill 0.2) (layers "F.Cu" "B.Cu") (net 9))
  (via (at 171.836328 61.010008) (size 0.5) (drill 0.2) (layers "F.Cu" "B.Cu") (net 9))
  (via (at 181.636328 92.060008) (size 0.5) (drill 0.2) (layers "F.Cu" "B.Cu") (net 9))
  (via (at 223.335618 56.650947) (size 0.5) (drill 0.2) (layers "F.Cu" "B.Cu") (net 9))
  (via (at 124.827992 100.997157) (size 0.5) (drill 0.2) (layers "F.Cu" "B.Cu") (net 9))
  (via (at 137.5 58.4) (size 0.5) (drill 0.2) (layers "F.Cu" "B.Cu") (net 9))
  (via (at 184.952039 46.897157) (size 0.5) (drill 0.2) (layers "F.Cu" "B.Cu") (net 9))
  (via (at 253.55 100.95) (size 0.5) (drill 0.2) (layers "F.Cu" "B.Cu") (net 9))
  (via (at 196.9 87.5) (size 0.5) (drill 0.2) (layers "F.Cu" "B.Cu") (net 9))
  (via (at 107.936328 90.181457) (size 0.5) (drill 0.2) (layers "F.Cu" "B.Cu") (net 9))
  (via (at 231.6 61.55) (size 0.5) (drill 0.2) (layers "F.Cu" "B.Cu") (net 9))
  (via (at 190.5 113.5) (size 0.5) (drill 0.2) (layers "F.Cu" "B.Cu") (free) (net 9))
  (via (at 137.286328 115.122157) (size 0.5) (drill 0.2) (layers "F.Cu" "B.Cu") (net 9))
  (via (at 245.836328 46.897157) (size 0.5) (drill 0.2) (layers "F.Cu" "B.Cu") (net 9))
  (via (at 164.220002 110.53) (size 0.5) (drill 0.2) (layers "F.Cu" "B.Cu") (net 9))
  (via (at 149.704102 135.197157) (size 0.5) (drill 0.2) (layers "F.Cu" "B.Cu") (net 9))
  (via (at 244.595594 135.197157) (size 0.5) (drill 0.2) (layers "F.Cu" "B.Cu") (net 9))
  (via (at 137.5 61.55) (size 0.5) (drill 0.2) (layers "F.Cu" "B.Cu") (net 9))
  (via (at 129.686328 91.560008) (size 0.5) (drill 0.2) (layers "F.Cu" "B.Cu") (net 9))
  (via (at 215.8 58.4) (size 0.5) (drill 0.2) (layers "F.Cu" "B.Cu") (net 9))
  (via (at 140.375 64.575) (size 0.5) (drill 0.2) (layers "F.Cu" "B.Cu") (net 9))
  (via (at 254.8 106.4) (size 0.5) (drill 0.2) (layers "F.Cu" "B.Cu") (net 9))
  (via (at 227.85 106.4) (size 0.5) (drill 0.2) (layers "F.Cu" "B.Cu") (net 9))
  (via (at 244.64 98.72) (size 0.5) (drill 0.2) (layers "F.Cu" "B.Cu") (net 9))
  (via (at 174.636328 95.060008) (size 0.5) (drill 0.2) (layers "F.Cu" "B.Cu") (net 9))
  (via (at 244.64 113.96) (size 0.5) (drill 0.2) (layers "F.Cu" "B.Cu") (net 9))
  (via (at 219.45 65.8) (size 0.5) (drill 0.2) (layers "F.Cu" "B.Cu") (net 9))
  (via (at 253.53 119.1) (size 0.5) (drill 0.2) (layers "F.Cu" "B.Cu") (net 9))
  (via blind (at 195.636328 99.060008) (size 0.5) (drill 0.2) (layers "F.Cu" "In2.Cu") (net 9))
  (via (at 154.85 53.8) (size 0.5) (drill 0.2) (layers "F.Cu" "B.Cu") (net 9))
  (via (at 200.736328 53.813672) (size 0.5) (drill 0.2) (layers "F.Cu" "B.Cu") (net 9))
  (via (at 151.919672 61.910011) (size 0.5) (drill 0.2) (layers "F.Cu" "B.Cu") (net 9))
  (via (at 132.4 58.4) (size 0.5) (drill 0.2) (layers "F.Cu" "B.Cu") (net 9))
  (via (at 125.875 128.875) (size 0.5) (drill 0.2) (layers "F.Cu" "B.Cu") (net 9))
  (via (at 137.124456 46.897157) (size 0.5) (drill 0.2) (layers "F.Cu" "B.Cu") (net 9))
  (via (at 139.111328 92.635008) (size 0.5) (drill 0.2) (layers "F.Cu" "B.Cu") (net 9))
  (via (at 238.136328 56.55) (size 0.5) (drill 0.2) (layers "F.Cu" "B.Cu") (net 9))
  (via (at 137.836328 53.813672) (size 0.5) (drill 0.2) (layers "F.Cu" "B.Cu") (net 9))
  (via (at 255.595594 135.197157) (size 0.5) (drill 0.2) (layers "F.Cu" "B.Cu") (net 9))
  (via (at 139.5 126.675) (size 0.5) (drill 0.2) (layers "F.Cu" "B.Cu") (net 9))
  (via (at 245.92 78.42) (size 0.5) (drill 0.2) (layers "F.Cu" "B.Cu") (net 9))
  (via (at 259.05 102.157925) (size 0.5) (drill 0.2) (layers "F.Cu" "B.Cu") (net 9))
  (via (at 121.11 90.47) (size 0.5) (drill 0.2) (layers "F.Cu" "B.Cu") (net 9))
  (via (at 245.65 64.35) (size 0.5) (drill 0.2) (layers "F.Cu" "B.Cu") (net 9))
  (via (at 162.4 121.05) (size 0.5) (drill 0.2) (layers "F.Cu" "B.Cu") (net 9))
  (via (at 190.5 111.7) (size 0.5) (drill 0.2) (layers "F.Cu" "B.Cu") (free) (net 9))
  (via (at 147.2 53.8) (size 0.5) (drill 0.2) (layers "F.Cu" "B.Cu") (net 9))
  (via blind (at 237.286328 61.35) (size 0.5) (drill 0.2) (layers "F.Cu" "In5.Cu") (net 9))
  (via (at 151.4 56.75) (size 0.5) (drill 0.2) (layers "F.Cu" "B.Cu") (net 9))
  (via (at 202.1 88.7) (size 0.5) (drill 0.2) (layers "F.Cu" "B.Cu") (net 9))
  (via (at 136.961736 135.197157) (size 0.5) (drill 0.2) (layers "F.Cu" "B.Cu") (net 9))
  (via (at 237.037 115.731) (size 0.5) (drill 0.2) (layers "F.Cu" "B.Cu") (net 9))
  (via (at 256 70.6) (size 0.5) (drill 0.2) (layers "F.Cu" "B.Cu") (net 9))
  (via (at 142.42275 135.197157) (size 0.5) (drill 0.2) (layers "F.Cu" "B.Cu") (net 9))
  (via (at 245.91 112.71) (size 0.5) (drill 0.2) (layers "F.Cu" "B.Cu") (net 9))
  (via (at 174.6 84.05) (size 0.5) (drill 0.2) (layers "F.Cu" "B.Cu") (net 9))
  (via (at 107.936328 121.346153) (size 0.5) (drill 0.2) (layers "F.Cu" "B.Cu") (free) (net 9))
  (via (at 256.1 93.64) (size 0.5) (drill 0.2) (layers "F.Cu" "B.Cu") (net 9))
  (via (at 256.1 91.06) (size 0.5) (drill 0.2) (layers "F.Cu" "B.Cu") (net 9))
  (via (at 190.136328 103.060008) (size 0.5) (drill 0.2) (layers "F.Cu" "B.Cu") (net 9))
  (via (at 149.5 108.8) (size 0.5) (drill 0.2) (layers "F.Cu" "B.Cu") (net 9))
  (via (at 107.936328 69.404993) (size 0.5) (drill 0.2) (layers "F.Cu" "B.Cu") (net 9))
  (via (at 237.236328 135.197157) (size 0.5) (drill 0.2) (layers "F.Cu" "B.Cu") (net 9))
  (via (at 158.05 64.575) (size 0.5) (drill 0.2) (layers "F.Cu" "B.Cu") (net 9))
  (via (at 256.1 119.04) (size 0.5) (drill 0.2) (layers "F.Cu" "B.Cu") (net 9))
  (via (at 238.7 65.8) (size 0.5) (drill 0.2) (layers "F.Cu" "B.Cu") (net 9))
  (via (at 249.72 91.1) (size 0.5) (drill 0.2) (layers "F.Cu" "B.Cu") (net 9))
  (via (at 142.1 56.7) (size 0.5) (drill 0.2) (layers "F.Cu" "B.Cu") (net 9))
  (via (at 236.605635 46.897157) (size 0.5) (drill 0.2) (layers "F.Cu" "B.Cu") (net 9))
  (via (at 227.086328 56.65) (size 0.5) (drill 0.2) (layers "F.Cu" "B.Cu") (net 9))
  (via (at 162.8 105.8) (size 0.5) (drill 0.2) (layers "F.Cu" "B.Cu") (net 9))
  (via (at 215.5 69.85) (size 0.5) (drill 0.2) (layers "F.Cu" "B.Cu") (net 9))
  (via (at 247.18 110.15) (size 0.5) (drill 0.2) (layers "F.Cu" "B.Cu") (net 9))
  (via (at 212.644034 46.897157) (size 0.5) (drill 0.2) (layers "F.Cu" "B.Cu") (net 9))
  (via (at 183.105906 46.897157) (size 0.5) (drill 0.2) (layers "F.Cu" "B.Cu") (net 9))
  (via (at 258.740167 127.452035) (size 0.5) (drill 0.2) (layers "F.Cu" "B.Cu") (net 9))
  (via (at 208.2 68.9) (size 0.5) (drill 0.2) (layers "F.Cu" "B.Cu") (net 9))
  (via (at 244.64 94.91) (size 0.5) (drill 0.2) (layers "F.Cu" "B.Cu") (net 9))
  (via (at 219.45 53.8) (size 0.5) (drill 0.2) (layers "F.Cu" "B.Cu") (net 9))
  (via (at 151.029439 62.273848) (size 0.5) (drill 0.2) (layers "F.Cu" "B.Cu") (net 9))
  (via (at 160.8 53.8) (size 0.5) (drill 0.2) (layers "F.Cu" "B.Cu") (net 9))
  (via (at 236.2 62.6) (size 0.5) (drill 0.2) (layers "F.Cu" "B.Cu") (net 9))
  (via (at 192.636328 95.060008) (size 0.5) (drill 0.2) (layers "F.Cu" "B.Cu") (net 9))
  (via (at 258.740167 71.804993) (size 0.5) (drill 0.2) (layers "F.Cu" "B.Cu") (net 9))
  (via (at 248.45 116.52) (size 0.5) (drill 0.2) (layers "F.Cu" "B.Cu") (net 9))
  (via (at 245.91 101.28) (size 0.5) (drill 0.2) (layers "F.Cu" "B.Cu") (net 9))
  (via (at 133.586328 61) (size 0.5) (drill 0.2) (layers "F.Cu" "B.Cu") (net 9))
  (via (at 149.4 56.6) (size 0.5) (drill 0.2) (layers "F.Cu" "B.Cu") (net 9))
  (via (at 190.636328 98.060008) (size 0.5) (drill 0.2) (layers "F.Cu" "B.Cu") (net 9))
  (via (at 119.75 102.625) (size 0.5) (drill 0.2) (layers "F.Cu" "B.Cu") (net 9))
  (via blind (at 192.636328 103.060008) (size 0.5) (drill 0.2) (layers "F.Cu" "In2.Cu") (net 9))
  (via (at 207.105635 46.897157) (size 0.5) (drill 0.2) (layers "F.Cu" "B.Cu") (net 9))
  (via (at 127.383544 100.997157) (size 0.5) (drill 0.2) (layers "F.Cu" "B.Cu") (net 9))
  (via (at 252.26 119.06) (size 0.5) (drill 0.2) (layers "F.Cu" "B.Cu") (net 9))
  (via (at 118.758356 135.197157) (size 0.5) (drill 0.2) (layers "F.Cu" "B.Cu") (net 9))
  (via (at 122.15 100.575) (size 0.5) (drill 0.2) (layers "F.Cu" "B.Cu") (net 9))
  (via (at 171.836328 53.710008) (size 0.5) (drill 0.2) (layers "F.Cu" "B.Cu") (net 9))
  (via (at 125.46688 100.997157) (size 0.5) (drill 0.2) (layers "F.Cu" "B.Cu") (net 9))
  (via (at 188.655836 83.060008) (size 0.5) (drill 0.2) (layers "F.Cu" "B.Cu") (net 9))
  (via (at 179.4 109.2) (size 0.5) (drill 0.2) (layers "F.Cu" "B.Cu") (net 9))
  (via (at 232.3 109) (size 0.5) (drill 0.2) (layers "F.Cu" "B.Cu") (net 9))
  (via (at 107.936328 84.987341) (size 0.5) (drill 0.2) (layers "F.Cu" "B.Cu") (net 9))
  (via (at 193.636328 102.060008) (size 0.5) (drill 0.2) (layers "F.Cu" "B.Cu") (net 9))
  (via (at 238.136328 53.813672) (size 0.5) (drill 0.2) (layers "F.Cu" "B.Cu") (net 9))
  (via (at 196.636328 97.060008) (size 0.5) (drill 0.2) (layers "F.Cu" "B.Cu") (net 9))
  (via (at 258.740167 65.059897) (size 0.5) (drill 0.2) (layers "F.Cu" "B.Cu") (net 9))
  (via (at 157.260044 46.897157) (size 0.5) (drill 0.2) (layers "F.Cu" "B.Cu") (net 9))
  (via (at 140.78 107.12) (size 0.5) (drill 0.2) (layers "F.Cu" "B.Cu") (net 9))
  (via (at 149.938012 46.897157) (size 0.5) (drill 0.2) (layers "F.Cu" "B.Cu") (net 9))
  (via (at 168.336842 46.897157) (size 0.5) (drill 0.2) (layers "F.Cu" "B.Cu") (net 9))
  (via (at 254.8 78.42) (size 0.5) (drill 0.2) (layers "F.Cu" "B.Cu") (net 9))
  (via (at 127.860046 135.197157) (size 0.5) (drill 0.2) (layers "F.Cu" "B.Cu") (net 9))
  (via (at 190.490438 46.897157) (size 0.5) (drill 0.2) (layers "F.Cu" "B.Cu") (net 9))
  (via (at 167.7 75.5) (size 0.5) (drill 0.2) (layers "F.Cu" "B.Cu") (net 9))
  (via (at 204.314242 135.197157) (size 0.5) (drill 0.2) (layers "F.Cu" "B.Cu") (free) (net 9))
  (via (at 248.45 89.85) (size 0.5) (drill 0.2) (layers "F.Cu" "B.Cu") (net 9))
  (via (at 135.859324 126.675) (size 0.5) (drill 0.2) (layers "F.Cu" "B.Cu") (net 9))
  (via (at 233.595594 135.197157) (size 0.5) (drill 0.2) (layers "F.Cu" "B.Cu") (net 9))
  (via (at 189.9 114.7) (size 0.5) (drill 0.2) (layers "F.Cu" "B.Cu") (free) (net 9))
  (via (at 232.685618 56.650947) (size 0.5) (drill 0.2) (layers "F.Cu" "B.Cu") (net 9))
  (via (at 135.293948 46.897157) (size 0.5) (drill 0.2) (layers "F.Cu" "B.Cu") (net 9))
  (via (at 236.2 88.9) (size 0.5) (drill 0.2) (layers "F.Cu" "B.Cu") (net 9))
  (via (at 234.2 88.9) (size 0.5) (drill 0.2) (layers "F.Cu" "B.Cu") (net 9))
  (via (at 243.37 108.9) (size 0.5) (drill 0.2) (layers "F.Cu" "B.Cu") (net 9))
  (via (at 258.740167 122.393213) (size 0.5) (drill 0.2) (layers "F.Cu" "B.Cu") (net 9))
  (via (at 238.9 88.45) (size 0.5) (drill 0.2) (layers "F.Cu" "B.Cu") (net 9))
  (via (at 256.1 88.56) (size 0.5) (drill 0.2) (layers "F.Cu" "B.Cu") (net 9))
  (segment (start 156.861328 94.660008) (end 156.861328 94.395008) (width 0.2) (layer "B.Cu") (net 9))
  (segment (start 156.861328 94.395008) (end 156.486328 94.020008) (width 0.2) (layer "B.Cu") (net 9))
  (segment (start 152.005626 96.005008) (end 151.786328 96.224306) (width 0.2) (layer "B.Cu") (net 9))
  (segment (start 152.786328 96.005008) (end 152.005626 96.005008) (width 0.2) (layer "B.Cu") (net 9))
  (segment (start 159.586328 93.505008) (end 160.686328 93.505008) (width 0.2) (layer "B.Cu") (net 9))
  (segment (start 159.586328 93.505008) (end 159.586328 94.020008) (width 0.2) (layer "B.Cu") (net 9))
  (segment (start 158.486328 93.505008) (end 158.486328 94.020008) (width 0.2) (layer "B.Cu") (net 9))
  (segment (start 157.486328 93.505008) (end 157.486328 94.020008) (width 0.2) (layer "B.Cu") (net 9))
  (segment (start 156.486328 93.505008) (end 156.486328 94.020008) (width 0.2) (layer "B.Cu") (net 9))
  (segment (start 155.486328 93.505008) (end 156.486328 93.505008) (width 0.2) (layer "B.Cu") (net 9))
  (segment (start 155.984758 82.086872) (end 155.047272 82.086872) (width 0.15) (layer "B.Cu") (net 9))
  (segment (start 168.936328 57.660008) (end 169.801328 57.660008) (width 0.2) (layer "B.Cu") (net 9))
  (segment (start 197.336328 53.531608) (end 197.336328 54.275008) (width 0.2) (layer "B.Cu") (net 9))
  (segment (start 195.520128 57.468608) (end 194.760728 57.468608) (width 0.2) (layer "B.Cu") (net 9))
  (segment (start 238.94 78.04) (end 237.95 77.05) (width 0.2) (layer "B.Cu") (net 9))
  (segment (start 247.18 87.29) (end 247.825 87.935) (width 0.4) (layer "B.Cu") (net 9))
  (segment (start 186.77 97.415) (end 186.78 97.425) (width 0.2) (layer "B.Cu") (net 9))
  (segment (start 123.485 97.95) (end 124.175 97.95) (width 0.127) (layer "B.Cu") (net 9))
  (segment (start 156.489833 98.625167) (end 157.1 98.015) (width 0.2) (layer "B.Cu") (net 9))
  (segment (start 256.685 120.955) (end 256.1 121.54) (width 0.4) (layer "B.Cu") (net 9))
  (segment (start 253.7617 84.125) (end 254.175 84.125) (width 0.4) (layer "B.Cu") (net 9))
  (segment (start 238.45 95.9) (end 237.95 95.9) (width 0.2) (layer "B.Cu") (net 9))
  (segment (start 158.671328 91.025008) (end 158.636328 91.060008) (width 0.2) (layer "B.Cu") (net 9))
  (segment (start 254.8 113.98) (end 255.445 113.335) (width 0.4) (layer "B.Cu") (net 9))
  (segment (start 244.64 91.1) (end 245.285 91.745) (width 0.4) (layer "B.Cu") (net 9))
  (segment (start 253.55 98.74) (end 252.905 98.095) (width 0.2) (layer "B.Cu") (net 9))
  (segment (start 177.555821 83) (end 177.615828 83.060007) (width 0.2) (layer "B.Cu") (net 9))
  (segment (start 245.91 116.52) (end 246.555 115.875) (width 0.4) (layer "B.Cu") (net 9))
  (segment (start 158.59 102.86) (end 158.66 102.79) (width 0.15) (layer "B.Cu") (net 9))
  (segment (start 153.215 79.993126) (end 153.180968 80.027158) (width 0.2) (layer "B.Cu") (net 9))
  (segment (start 127.525 108.91) (end 128.235 109.62) (width 0.127) (layer "B.Cu") (net 9))
  (segment (start 195.78632 92.21) (end 195.636328 92.060008) (width 0.2) (layer "B.Cu") (net 9))
  (segment (start 193.636328 101.813672) (end 193.636328 102.060008) (width 0.2) (layer "B.Cu") (net 9))
  (segment (start 174.7 80.395) (end 174.7 80.996336) (width 0.2) (layer "B.Cu") (net 9))
  (segment (start 186.636328 90.961328) (end 186.636328 91.060008) (width 0.2) (layer "B.Cu") (net 9))
  (segment (start 156.400167 98.625167) (end 156.489833 98.625167) (width 0.2) (layer "B.Cu") (net 9))
  (segment (start 159.876328 89.825008) (end 159.636328 90.065008) (width 0.2) (layer "B.Cu") (net 9))
  (segment (start 178.16 97.536336) (end 178.636328 97.060008) (width 0.2) (layer "B.Cu") (net 9))
  (segment (start 138.96 98.235) (end 138.96 97.71) (width 0.127) (layer "B.Cu") (net 9))
  (segment (start 255.385 91.745) (end 254.8 91.16) (width 0.4) (layer "B.Cu") (net 9))
  (segment (start 135.776657 103.075) (end 135.83 103.021657) (width 0.127) (layer "B.Cu") (net 9))
  (segment (start 189.086328 89.240008) (end 189.086328 89.161328) (width 0.2) (layer "B.Cu") (net 9))
  (segment (start 254.175 119.685) (end 254.115 119.685) (width 0.4) (layer "B.Cu") (net 9))
  (segment (start 245.925 119.055) (end 245.285 118.415) (width 0.4) (layer "B.Cu") (net 9))
  (segment (start 179.3405 79.0405) (end 179.636328 79.0405) (width 0.2) (layer "B.Cu") (net 9))
  (segment (start 166.306328 93.830008) (end 166.236328 93.760008) (width 0.2) (layer "B.Cu") (net 9))
  (segment (start 251.635 119.685) (end 252.26 119.06) (width 0.4) (layer "B.Cu") (net 9))
  (segment (start 175.005 84.675) (end 174.6 84.27) (width 0.2) (layer "B.Cu") (net 9))
  (segment (start 182.79 99.67) (end 182.79 99.21368) (width 0.2) (layer "B.Cu") (net 9))
  (segment (start 254.175 75.235) (end 254.175 74.565) (width 0.2) (layer "B.Cu") (net 9))
  (segment (start 251.635 108.255) (end 251.635 108.56) (width 0.4) (layer "B.Cu") (net 9))
  (segment (start 256.1 119.07) (end 256.715 119.685) (width 0.4) (layer "B.Cu") (net 9))
  (segment (start 253.56 113.99) (end 254.175 114.605) (width 0.4) (layer "B.Cu") (net 9))
  (segment (start 172.636328 98.833672) (end 172.636328 99.060008) (width 0.2) (layer "B.Cu") (net 9))
  (segment (start 254.175 121.015) (end 254.8 121.64) (width 0.4) (layer "B.Cu") (net 9))
  (segment (start 188.186328 88.855008) (end 188.186328 88.861328) (width 0.2) (layer "B.Cu") (net 9))
  (segment (start 184.2 77.025) (end 184.2 76.4) (width 0.2) (layer "B.Cu") (net 9))
  (segment (start 121.426111 100.172716) (end 121.426111 99.926111) (width 0.127) (layer "B.Cu") (net 9))
  (segment (start 194.636328 88.323672) (end 194.636328 88.060008) (width 0.2) (layer "B.Cu") (net 9))
  (segment (start 120.54 90.47) (end 121.11 90.47) (width 0.1) (layer "B.Cu") (net 9))
  (segment (start 255.445 112.065) (end 255.385 112.065) (width 0.4) (layer "B.Cu") (net 9))
  (segment (start 185.186328 86.880008) (end 185.186328 86.911328) (width 0.2) (layer "B.Cu") (net 9))
  (segment (start 190.675 82.075) (end 190.7 82.05) (width 0.2) (layer "B.Cu") (net 9))
  (segment (start 173.225 91.64868) (end 173.636328 92.060008) (width 0.2) (layer "B.Cu") (net 9))
  (segment (start 165.030941 108.420941) (end 165.845 109.235) (width 0.2) (layer "B.Cu") (net 9))
  (segment (start 247.18 102.53) (end 247.825 103.175) (width 0.4) (layer "B.Cu") (net 9))
  (segment (start 163.765 101.685) (end 164 101.45) (width 0.2) (layer "B.Cu") (net 9))
  (segment (start 120.32 89.99) (end 120.34 90.01) (width 0.1) (layer "B.Cu") (net 9))
  (segment (start 161.9 101.685) (end 161.9 102.5495) (width 0.2) (layer "B.Cu") (net 9))
  (segment (start 238.9 93.05) (end 238.9 90.6) (width 0.4) (layer "B.Cu") (net 9))
  (segment (start 252.26 124.14) (end 252.905 123.495) (width 0.4) (layer "B.Cu") (net 9))
  (segment (start 255.385 122.225) (end 254.8 121.64) (width 0.4) (layer "B.Cu") (net 9))
  (segment (start 184.236328 101.960008) (end 184.236328 101.936328) (width 0.2) (layer "B.Cu") (net 9))
  (segment (start 238.86 80.41) (end 238.2 79.75) (width 0.2) (layer "B.Cu") (net 9))
  (segment (start 249.72 110.15) (end 250.365 110.795) (width 0.4) (layer "B.Cu") (net 9))
  (segment (start 153.6895 106.420437) (end 152.839563 106.420437) (width 0.15) (layer "B.Cu") (net 9))
  (segment (start 184.236328 101.936328) (end 183.636328 101.336328) (width 0.2) (layer "B.Cu") (net 9))
  (segment (start 121.736328 60.245008) (end 121.736328 61.280008) (width 0.2) (layer "B.Cu") (net 9))
  (segment (start 184.186328 86.213672) (end 184.339992 86.060008) (width 0.2) (layer "B.Cu") (net 9))
  (segment (start 182.366328 91.060008) (end 182.186328 91.240008) (width 0.1) (layer "B.Cu") (net 9))
  (segment (start 174.25 102.6) (end 173.710008 102.060008) (width 0.2) (layer "B.Cu") (net 9))
  (segment (start 120.736328 60.830008) (end 120.496328 61.070008) (width 0.2) (layer "B.Cu") (net 9))
  (segment (start 176.395 90.495) (end 176.65 90.75) (width 0.2) (layer "B.Cu") (net 9))
  (segment (start 129.075 110.685) (end 129.59 111.2) (width 0.127) (layer "B.Cu") (net 9))
  (segment (start 248.45 101.28) (end 249.095 100.635) (width 0.4) (layer "B.Cu") (net 9))
  (segment (start 190.655836 79.219164) (end 190.655836 79.060008) (width 0.2) (layer "B.Cu") (net 9))
  (segment (start 190.7 82.05) (end 190.7 82.55368) (width 0.2) (layer "B.Cu") (net 9))
  (segment (start 182.070828 77.475) (end 182.636328 78.0405) (width 0.2) (layer "B.Cu") (net 9))
  (segment (start 188.775 97.65) (end 189.745 97.65) (width 0.2) (layer "B.Cu") (net 9))
  (segment (start 255.248574 88.131426) (end 255.445 87.935) (width 0.4) (layer "B.Cu") (net 9))
  (segment (start 138.96 97.71) (end 138.75 97.5) (width 0.127) (layer "B.Cu") (net 9))
  (segment (start 127.42 87.906531) (end 127.086328 87.572859) (width 0.1) (layer "B.Cu") (net 9))
  (segment (start 237.95 82.45) (end 238.7 82.45) (width 0.2) (layer "B.Cu") (net 9))
  (segment (start 172.83 86.65) (end 172.8 86.65) (width 0.2) (layer "B.Cu") (net 9))
  (segment (start 190.567128 57.468608) (end 189.807728 57.468608) (width 0.2) (layer "B.Cu") (net 9))
  (segment (start 245.91 82.23) (end 246.555 81.585) (width 0.4) (layer "B.Cu") (net 9))
  (segment (start 255.1 75.9) (end 255.1 76.16) (width 0.4) (layer "B.Cu") (net 9))
  (segment (start 253.56 108.88) (end 253.56 108.91) (width 0.4) (layer "B.Cu") (net 9))
  (segment (start 237.9 88.45) (end 237.9 87.9) (width 0.2) (layer "B.Cu") (net 9))
  (segment (start 238.115 125.215) (end 237.7 124.8) (width 0.2) (layer "B.Cu") (net 9))
  (segment (start 247.446369 117.8005) (end 247.446369 118.036369) (width 0.4) (layer "B.Cu") (net 9))
  (segment (start 176.65 90.75) (end 176.65 91.046336) (width 0.2) (layer "B.Cu") (net 9))
  (segment (start 173.710008 102.060008) (end 173.636328 102.060008) (width 0.2) (layer "B.Cu") (net 9))
  (segment (start 249.72 94.91) (end 250.365 95.555) (width 0.4) (layer "B.Cu") (net 9))
  (segment (start 187.636328 91.060008) (end 187.366328 91.060008) (width 0.1) (layer "B.Cu") (net 9))
  (segment (start 238.55 95.8) (end 238.9 95.45) (width 0.4) (layer "B.Cu") (net 9))
  (segment (start 188.5 103.1) (end 188.6 103.2) (width 0.2) (layer "B.Cu") (net 9))
  (segment (start 226.3 125.815) (end 225.515 125.815) (width 0.2) (layer "B.Cu") (net 9))
  (segment (start 178.97 78.67) (end 179.3405 79.0405) (width 0.2) (layer "B.Cu") (net 9))
  (segment (start 185.186328 86.911328) (end 185.335008 87.060008) (width 0.2) (layer "B.Cu") (net 9))
  (segment (start 251.635 89.485) (end 251.975 89.825) (width 0.4) (layer "B.Cu") (net 9))
  (segment (start 121.647733 100.394338) (end 121.426111 100.172716) (width 0.127) (layer "B.Cu") (net 9))
  (segment (start 172.52 88.65) (end 172.52 88.176337) (width 0.2) (layer "B.Cu") (net 9))
  (segment (start 183.186328 86.880008) (end 183.186328 86.961328) (width 0.2) (layer "B.Cu") (net 9))
  (segment (start 251.635 74.695) (end 251.995071 74.334929) (width 0.2) (layer "B.Cu") (net 9))
  (segment (start 247.658 47.676) (end 247.658 46.902526) (width 0.2) (layer "B.Cu") (net 9))
  (segment (start 186.78 97.916336) (end 186.636328 98.060008) (width 0.2) (layer "B.Cu") (net 9))
  (segment (start 196.636328 96.686328) (end 196.636328 97.060008) (width 0.2) (layer "B.Cu") (net 9))
  (segment (start 256.11 103.84) (end 256.715 104.445) (width 0.4) (layer "B.Cu") (net 9))
  (segment (start 174.386328 54.575008) (end 174.386328 53.710008) (width 0.2) (layer "B.Cu") (net 9))
  (segment (start 254.175 77.775) (end 254.175 77.795) (width 0.4) (layer "B.Cu") (net 9))
  (segment (start 248.835 124.765) (end 249.095 124.765) (width 0.2) (layer "B.Cu") (net 9))
  (segment (start 176.65 91.046336) (end 176.636328 91.060008) (width 0.2) (layer "B.Cu") (net 9))
  (segment (start 248.45 82.23) (end 249.095 81.585) (width 0.4) (layer "B.Cu") (net 9))
  (segment (start 181.186328 88.936328) (end 181.310008 89.060008) (width 0.2) (layer "B.Cu") (net 9))
  (segment (start 121.11 95.28) (end 121.69 94.7) (width 0.2) (layer "B.Cu") (net 9))
  (segment (start 193.636328 95.738672) (end 193.636328 96.060008) (width 0.2) (layer "B.Cu") (net 9))
  (segment (start 255.75 96.52) (end 255.445 96.825) (width 0.4) (layer "B.Cu") (net 9))
  (segment (start 170.136328 60.145008) (end 170.136328 61.010008) (width 0.2) (layer "B.Cu") (net 9))
  (segment (start 163.805556 106.4205) (end 163.710531 106.325475) (width 0.15) (layer "B.Cu") (net 9))
  (segment (start 132.915 119.2) (end 133.015 119.3) (width 0.2) (layer "B.Cu") (net 9))
  (segment (start 184.4 80.47) (end 184.206828 80.47) (width 0.2) (layer "B.Cu") (net 9))
  (segment (start 193.85 99.5) (end 193.57 99.78) (width 0.2) (layer "B.Cu") (net 9))
  (segment (start 189.725 82.075) (end 190.675 82.075) (width 0.2) (layer "B.Cu") (net 9))
  (segment (start 174.07 98.95) (end 173.93 99.09) (width 0.2) (layer "B.Cu") (net 9))
  (segment (start 181.636328 92.060008) (end 181.366328 92.060008) (width 0.1) (layer "B.Cu") (net 9))
  (segment (start 252.845 122.225) (end 252.26 121.64) (width 0.4) (layer "B.Cu") (net 9))
  (segment (start 182.7 78.975) (end 182.7 78.104172) (width 0.2) (layer "B.Cu") (net 9))
  (segment (start 256.715 115.875) (end 256.685 115.875) (width 0.4) (layer "B.Cu") (net 9))
  (segment (start 183.775 98.725) (end 183.439992 99.060008) (width 0.2) (layer "B.Cu") (net 9))
  (segment (start 256.715 90.475) (end 256.685 90.475) (width 0.4) (layer "B.Cu") (net 9))
  (segment (start 245.91 86.04) (end 246.555 85.395) (width 0.4) (layer "B.Cu") (net 9))
  (segment (start 176.825 83) (end 177.555821 83) (width 0.2) (layer "B.Cu") (net 9))
  (segment (start 189.59 103.29) (end 189.906336 103.29) (width 0.2) (layer "B.Cu") (net 9))
  (segment (start 193.88 101.6) (end 193.85 101.6) (width 0.2) (layer "B.Cu") (net 9))
  (segment (start 121.676724 100.394338) (end 121.647733 100.394338) (width 0.127) (layer "B.Cu") (net 9))
  (segment (start 176 94.755) (end 176.224992 94.530008) (width 0.2) (layer "B.Cu") (net 9))
  (segment (start 199.235 111.865) (end 199.2 111.9) (width 0.2) (layer "B.Cu") (net 9))
  (segment (start 172.636328 99.060008) (end 172.681328 99.060008) (width 0.1) (layer "B.Cu") (net 9))
  (segment (start 124.175 97.95) (end 124.2 97.925) (width 0.127) (layer "B.Cu") (net 9))
  (segment (start 189.8 79.68) (end 190.195 79.68) (width 0.2) (layer "B.Cu") (net 9))
  (segment (start 248.45 116.52) (end 249.095 115.875) (width 0.4) (layer "B.Cu") (net 9))
  (segment (start 158.686328 89.495008) (end 158.686328 90.445008) (width 0.2) (layer "B.Cu") (net 9))
  (segment (start 193.459548 78.081816) (end 192.977732 77.6) (width 0.2) (layer "B.Cu") (net 9))
  (segment (start 256.1 113.96) (end 256.1 113.99) (width 0.4) (layer "B.Cu") (net 9))
  (segment (start 252.9 109.525) (end 252.3 110.125) (width 0.4) (layer "B.Cu") (net 9))
  (segment (start 253.56 103.8) (end 253.56 103.83) (width 0.4) (layer "B.Cu") (net 9))
  (segment (start 186.63 88.05368) (end 186.636328 88.060008) (width 0.2) (layer "B.Cu") (net 9))
  (segment (start 188.636328 94.280008) (end 188.866328 94.510008) (width 0.1) (layer "B.Cu") (net 9))
  (segment (start 187.285 86.3) (end 187.285 86.411336) (width 0.2) (layer "B.Cu") (net 9))
  (segment (start 237.95 93.25) (end 238.7 93.25) (width 0.2) (layer "B.Cu") (net 9))
  (segment (start 226.315 125.8) (end 226.3 125.815) (width 0.2) (layer "B.Cu") (net 9))
  (segment (start 196.52 96.57) (end 196.636328 96.686328) (width 0.2) (layer "B.Cu") (net 9))
  (segment (start 247.8 125.8) (end 248.835 124.765) (width 0.2) (layer "B.Cu") (net 9))
  (segment (start 120.34 90.01) (end 120.34 90.27) (width 0.1) (layer "B.Cu") (net 9))
  (segment (start 182.79 99.21368) (end 182.636328 99.060008) (width 0.2) (layer "B.Cu") (net 9))
  (segment (start 254.8 103.82) (end 255.445 103.175) (width 0.4) (layer "B.Cu") (net 9))
  (segment (start 162.4 121.05) (end 162.615 121.265) (width 0.2) (layer "B.Cu") (net 9))
  (segment (start 181.796328 52.933672) (end 181.8 52.93) (width 0.2) (layer "B.Cu") (net 9))
  (segment (start 182.186328 86.238672) (end 182.364992 86.060008) (width 0.2) (layer "B.Cu") (net 9))
  (segment (start 254.175 124.765) (end 254.115 124.765) (width 0.4) (layer "B.Cu") (net 9))
  (segment (start 182.186328 86.240008) (end 182.186328 86.238672) (width 0.2) (layer "B.Cu") (net 9))
  (segment (start 192.675 101.025) (end 192.22 101.025) (width 0.2) (layer "B.Cu") (net 9))
  (segment (start 254.175 89.875) (end 254.15 89.85) (width 0.3) (layer "B.Cu") (net 9))
  (segment (start 245.91 108.9) (end 246.555 108.255) (width 0.4) (layer "B.Cu") (net 9))
  (segment (start 190.7 82.05) (end 191.645828 82.05) (width 0.2) (layer "B.Cu") (net 9))
  (segment (start 182.189992 88.240008) (end 182.369992 88.060008) (width 0.2) (layer "B.Cu") (net 9))
  (segment (start 178.106328 93.590008) (end 177.636328 94.060008) (width 0.2) (layer "B.Cu") (net 9))
  (segment (start 255.445 81.585) (end 255.385 81.585) (width 0.4) (layer "B.Cu") (net 9))
  (segment (start 174.6 84.27) (end 174.6 84.05) (width 0.2) (layer "B.Cu") (net 9))
  (segment (start 193.775 95.6) (end 193.636328 95.738672) (width 0.2) (layer "B.Cu") (net 9))
  (segment (start 254.8 116.5) (end 255.445 117.145) (width 0.4) (layer "B.Cu") (net 9))
  (segment (start 132.215 103.165) (end 132.225 103.175) (width 0.127) (layer "B.Cu") (net 9))
  (segment (start 125.3175 90.57) (end 124.43 90.57) (width 0.1) (layer "B.Cu") (net 9))
  (segment (start 195.59632 77.65) (end 195.636328 77.690008) (width 0.2) (layer "B.Cu") (net 9))
  (segment (start 165.45 99.7) (end 165.715008 99.965008) (width 0.2) (layer "B.Cu") (net 9))
  (segment (start 194.2 81.73) (end 194.425 81.505) (width 0.2) (layer "B.Cu") (net 9))
  (segment (start 189.906336 103.29) (end 190.136328 103.060008) (width 0.2) (layer "B.Cu") (net 9))
  (segment (start 251.635 112.065) (end 251.615 112.065) (width 0.4) (layer "B.Cu") (net 9))
  (segment (start 252.865 105.715) (end 252.3 105.15) (width 0.4) (layer "B.Cu") (net 9))
  (segment (start 245.925 121.325) (end 245.285 121.965) (width 0.4) (layer "B.Cu") (net 9))
  (segment (start 165.9 110) (end 166.15 110.25) (width 0.2) (layer "B.Cu") (net 9))
  (segment (start 195.646328 53.531608) (end 195.646328 54.275008) (width 0.2) (layer "B.Cu") (net 9))
  (segment (start 184.94 77.25) (end 184.94 76.06) (width 0.2) (layer "B.Cu") (net 9))
  (segment (start 253.53 116.52) (end 254.175 115.875) (width 0.4) (layer "B.Cu") (net 9))
  (segment (start 257.03108 99.365) (end 256.715 99.365) (width 0.4) (layer "B.Cu") (net 9))
  (segment (start 252.905 76.505) (end 251.635 77.775) (width 0.2) (layer "B.Cu") (net 9))
  (segment (start 140 78.5) (end 140 79.25) (width 0.4) (layer "B.Cu") (net 9))
  (segment (start 182.369992 88.060008) (end 182.636328 88.060008) (width 0.2) (layer "B.Cu") (net 9))
  (segment (start 251.635 121.015) (end 252.26 121.64) (width 0.4) (layer "B.Cu") (net 9))
  (segment (start 165.885 116.3) (end 166.65 116.3) (width 0.2) (layer "B.Cu") (net 9))
  (segment (start 255.248574 88.575428) (end 255.248574 88.131426) (width 0.4) (layer "B.Cu") (net 9))
  (segment (start 250.365 76.505) (end 251.635 77.775) (width 0.2) (layer "B.Cu") (net 9))
  (segment (start 181.416328 82.410008) (end 181.005836 82.410008) (width 0.2) (layer "B.Cu") (net 9))
  (segment (start 179.5095 79.0405) (end 179.636328 79.0405) (width 0.2) (layer "B.Cu") (net 9))
  (segment (start 256.715 120.955) (end 256.685 120.955) (width 0.4) (layer "B.Cu") (net 9))
  (segment (start 186.976328 89.785008) (end 186.976328 89.776328) (width 0.2) (layer "B.Cu") (net 9))
  (segment (start 182.366328 93.060008) (end 182.186328 93.240008) (width 0.1) (layer "B.Cu") (net 9))
  (segment (start 252.915 94.285) (end 253.5 93.7) (width 0.4) (layer "B.Cu") (net 9))
  (segment (start 193.78 95.6) (end 193.775 95.6) (width 0.2) (layer "B.Cu") (net 9))
  (segment (start 121.0225 88.7675) (end 122.0225 88.7675) (width 0.1) (layer "B.Cu") (net 9))
  (segment (start 184.94 78.275) (end 184.94 77.25) (width 0.2) (layer "B.Cu") (net 9))
  (segment (start 156.186328 88.295008) (end 155.551328 88.295008) (width 0.2) (layer "B.Cu") (net 9))
  (segment (start 129.47 108.95) (end 129.61 108.81) (width 0.127) (layer "B.Cu") (net 9))
  (segment (start 256.1 124.15) (end 256.715 124.765) (width 0.4) (layer "B.Cu") (net 9))
  (segment (start 156.716328 89.130008) (end 156.686328 89.160008) (width 0.2) (layer "B.Cu") (net 9))
  (segment (start 193.591364 77.95) (end 194.5 77.95) (width 0.2) (layer "B.Cu") (net 9))
  (segment (start 192.080008 90.060008) (end 191.636328 90.060008) (width 0.2) (layer "B.Cu") (net 9))
  (segment (start 160.736328 89.825008) (end 159.876328 89.825008) (width 0.2) (layer "B.Cu") (net 9))
  (segment (start 152.950315 105.420185) (end 152.8305 105.54) (width 0.15) (layer "B.Cu") (net 9))
  (segment (start 185.335008 87.060008) (end 185.636328 87.060008) (width 0.2) (layer "B.Cu") (net 9))
  (segment (start 196 83.715844) (end 195.655836 84.060008) (width 0.2) (layer "B.Cu") (net 9))
  (segment (start 129.075 109.62) (end 129.075 110.685) (width 0.127) (layer "B.Cu") (net 9))
  (segment (start 181.186328 88.880008) (end 181.186328 88.936328) (width 0.2) (layer "B.Cu") (net 9))
  (segment (start 196.14 92.21) (end 195.78632 92.21) (width 0.2) (layer "B.Cu") (net 9))
  (segment (start 254.8 78.42) (end 255.445 77.775) (width 0.4) (layer "B.Cu") (net 9))
  (segment (start 188.366328 92.060008) (end 188.186328 91.880008) (width 0.1) (layer "B.Cu") (net 9))
  (segment (start 121.69 94.7) (end 122.175 94.7) (width 0.2) (layer "B.Cu") (net 9))
  (segment (start 179.925 82.73) (end 179.946828 82.73) (width 0.2) (layer "B.Cu") (net 9))
  (segment (start 173.93 99.09) (end 172.66632 99.09) (width 0.2) (layer "B.Cu") (net 9))
  (segment (start 244.64 94.91) (end 245.285 95.555) (width 0.4) (layer "B.Cu") (net 9))
  (segment (start 159.4005 101.4505) (end 159.941681 101.4505) (width 0.2) (layer "B.Cu") (net 9))
  (segment (start 256.1 108.91) (end 256.715 109.525) (width 0.4) (layer "B.Cu") (net 9))
  (segment (start 132.065 105.065) (end 132.25 105.25) (width 0.127) (layer "B.Cu") (net 9))
  (segment (start 125.315 88.1) (end 126.05 88.835) (width 0.1) (layer "B.Cu") (net 9))
  (segment (start 252.905 122.225) (end 252.845 122.225) (width 0.4) (layer "B.Cu") (net 9))
  (segment (start 184.94 76.06) (end 185.025 75.975) (width 0.2) (layer "B.Cu") (net 9))
  (segment (start 182.636328 93.060008) (end 182.366328 93.060008) (width 0.1) (layer "B.Cu") (net 9))
  (segment (start 252.905 90.505) (end 253.5 91.1) (width 0.4) (layer "B.Cu") (net 9))
  (segment (start 186.636328 94.060008) (end 186.636328 94.330008) (width 0.1) (layer "B.Cu") (net 9))
  (segment (start 193.175 85.575) (end 192.75 85.15) (width 0.2) (layer "B.Cu") (net 9))
  (segment (start 185.5 88.785) (end 184.911336 88.785) (width 0.2) (layer "B.Cu") (net 9))
  (segment (start 238.55 95.8) (end 238.45 95.9) (width 0.2) (layer "B.Cu") (net 9))
  (segment (start 178.16 97.75) (end 178.16 97.536336) (width 0.2) (layer "B.Cu") (net 9))
  (segment (start 193.459548 78.081816) (end 193.311328 78.230036) (width 0.2) (layer "B.Cu") (net 9))
  (segment (start 141.05 122.5) (end 141.05 121.25) (width 0.2) (layer "B.Cu") (net 9))
  (segment (start 160.736328 90.560008) (end 160.636328 90.660008) (width 0.2) (layer "B.Cu") (net 9))
  (segment (start 245.285 123.505) (end 244.67 124.12) (width 0.4) (layer "B.Cu") (net 9))
  (segment (start 198.7 58.3) (end 198.7 58.985) (width 0.2) (layer "B.Cu") (net 9))
  (segment (start 195.35 77.65) (end 195.59632 77.65) (width 0.2) (layer "B.Cu") (net 9))
  (segment (start 251.635 104.415) (end 252.2 103.85) (width 0.4) (layer "B.Cu") (net 9))
  (segment (start 244.64 79.67) (end 245.285 80.315) (width 0.4) (layer "B.Cu") (net 9))
  (segment (start 141.05 121.25) (end 141.1 121.2) (width 0.2) (layer "B.Cu") (net 9))
  (segment (start 117.725 95.935) (end 117.725 96.65) (width 0.127) (layer "B.Cu") (net 9))
  (segment (start 249.72 98.72) (end 250.365 99.365) (width 0.4) (layer "B.Cu") (net 9))
  (segment (start 182.775 98.175) (end 182.775 98.921336) (width 0.2) (layer "B.Cu") (net 9))
  (segment (start 244.64 106.34) (end 245.285 106.985) (width 0.4) (layer "B.Cu") (net 9))
  (segment (start 253.86 80) (end 254.175 80.315) (width 0.4) (layer "B.Cu") (net 9))
  (segment (start 161.934499 110.315501) (end 161.934499 109.165498) (width 0.1) (layer "B.Cu") (net 9))
  (segment (start 256.1 113.99) (end 256.715 114.605) (width 0.4) (layer "B.Cu") (net 9))
  (segment (start 135.55 109.95) (end 135.55 110.65) (width 0.12) (layer "B.Cu") (net 9))
  (segment (start 256.715 110.795) (end 256.685 110.795) (width 0.4) (layer "B.Cu") (net 9))
  (segment (start 253.56 113.96) (end 253.56 113.99) (width 0.4) (layer "B.Cu") (net 9))
  (segment (start 180.25 90.245) (end 179.82132 90.245) (width 0.2) (layer "B.Cu") (net 9))
  (segment (start 254.8 108.9) (end 255.445 108.255) (width 0.4) (layer "B.Cu") (net 9))
  (segment (start 252.905 113.305) (end 252.3 112.7) (width 0.4) (layer "B.Cu") (net 9))
  (segment (start 175.225 94.395) (end 175.225 94.471336) (width 0.2) (layer "B.Cu") (net 9))
  (segment (start 137.65 100.69) (end 137.89 100.69) (width 0.2) (layer "B.Cu") (net 9))
  (segment (start 192.45 95.625) (end 192.636328 95.438672) (width 0.2) (layer "B.Cu") (net 9))
  (segment (start 246.635 124.765) (end 246.555 124.765) (width 0.2) (layer "B.Cu") (net 9))
  (segment (start 237.95 90.55) (end 238.85 90.55) (width 0.2) (layer "B.Cu") (net 9))
  (segment (start 237.9 87.9) (end 237.95 87.85) (width 0.2) (layer "B.Cu") (net 9))
  (segment (start 193.33 85.575) (end 193.175 85.575) (width 0.2) (layer "B.Cu") (net 9))
  (segment (start 256.1 93.64) (end 256.1 93.67) (width 0.4) (layer "B.Cu") (net 9))
  (segment (start 154.3945 103.221529) (end 154.525 103.091029) (width 0.1) (layer "B.Cu") (net 9))
  (segment (start 184.186328 86.240008) (end 184.186328 86.213672) (width 0.2) (layer "B.Cu") (net 9))
  (segment (start 122.0225 88.7675) (end 122.09 88.7) (width 0.1) (layer "B.Cu") (net 9))
  (segment (start 244.64 113.96) (end 245.285 114.605) (width 0.4) (layer "B.Cu") (net 9))
  (segment (start 157.925 101.035) (end 157.84 101.035) (width 0.2) (layer "B.Cu") (net 9))
  (segment (start 170.02 102.37) (end 170.636328 102.986328) (width 0.15) (layer "B.Cu") (net 9))
  (segment (start 248.45 105.09) (end 249.095 104.445) (width 0.4) (layer "B.Cu") (net 9))
  (segment (start 256.715 105.715) (end 256.685 105.715) (width 0.4) (layer "B.Cu") (net 9))
  (segment (start 156.8945 103.2055) (end 157.025 103.075) (width 0.1) (layer "B.Cu") (net 9))
  (segment (start 253.535319 80) (end 252.905 79.369681) (width 0.2) (layer "B.Cu") (net 9))
  (segment (start 255.385 106.985) (end 254.8 106.4) (width 0.4) (layer "B.Cu") (net 9))
  (segment (start 193.57 99.78) (end 193.57 99.96) (width 0.2) (layer "B.Cu") (net 9))
  (segment (start 121.9 122.1) (end 123.2296 123.4296) (width 0.4) (layer "B.Cu") (net 9))
  (segment (start 238.65 122.565) (end 238.65 121.55) (width 0.2) (layer "B.Cu") (net 9))
  (segment (start 249.72 83.48) (end 250.365 84.125) (width 0.4) (layer "B.Cu") (net 9))
  (segment (start 152.949559 108.420941) (end 152.8305 108.54) (width 0.15) (layer "B.Cu") (net 9))
  (segment (start 181.796328 53.605008) (end 181.796328 52.940008) (width 0.2) (layer "B.Cu") (net 9))
  (segment (start 192.26 94.425) (end 192.26 94.39) (width 0.2) (layer "B.Cu") (net 9))
  (segment (start 187.285 86.411336) (end 186.636328 87.060008) (width 0.2) (layer "B.Cu") (net 9))
  (segment (start 187.366328 91.060008) (end 187.186328 91.240008) (width 0.1) (layer "B.Cu") (net 9))
  (segment (start 184.636328 93.060008) (end 184.686328 93.060008) (width 0.1) (layer "B.Cu") (net 9))
  (segment (start 163.815056 106.43) (end 163.710531 106.325475) (width 0.15) (layer "B.Cu") (net 9))
  (segment (start 154.414499 104.195501) (end 154.3945 104.175502) (width 0.1) (layer "B.Cu") (net 9))
  (segment (start 156.8945 104.175502) (end 156.914499 104.195501) (width 0.1) (layer "B.Cu") (net 9))
  (segment (start 253.55 80) (end 253.535319 80) (width 0.2) (layer "B.Cu") (net 9))
  (segment (start 170.136328 54.575008) (end 170.136328 53.710008) (width 0.2) (layer "B.Cu") (net 9))
  (segment (start 196 83.37) (end 196 83.715844) (width 0.2) (layer "B.Cu") (net 9))
  (segment (start 253.55 99.075) (end 253.885 99.075) (width 0.4) (layer "B.Cu") (net 9))
  (segment (start 251.615 112.065) (end 251.05 111.5) (width 0.4) (layer "B.Cu") (net 9))
  (segment (start 187.186328 88.238672) (end 187.364992 88.060008) (width 0.2) (layer "B.Cu") (net 9))
  (segment (start 196.42 100.525) (end 196.42 100.57) (width 0.2) (layer "B.Cu") (net 9))
  (segment (start 181.636328 61.155008) (end 181.636328 61.910008) (width 0.2) (layer "B.Cu") (net 9))
  (segment (start 245.91 101.28) (end 246.555 100.635) (width 0.4) (layer "B.Cu") (net 9))
  (segment (start 254.115 124.765) (end 253.53 124.18) (width 0.4) (layer "B.Cu") (net 9))
  (segment (start 194.425 81.290844) (end 194.655836 81.060008) (width 0.2) (layer "B.Cu") (net 9))
  (segment (start 245.91 97.47) (end 246.555 96.825) (width 0.4) (layer "B.Cu") (net 9))
  (segment (start 184.425 77.25) (end 184.2 77.025) (width 0.2) (layer "B.Cu") (net 9))
  (segment (start 129.075 109.62) (end 129.47 109.225) (width 0.127) (layer "B.Cu") (net 9))
  (segment (start 177.166328 94.530008) (end 177.636328 94.060008) (width 0.2) (layer "B.Cu") (net 9))
  (segment (start 249.72 102.53) (end 250.365 103.175) (width 0.4) (layer "B.Cu") (net 9))
  (segment (start 253.86 100.95) (end 254.175 100.635) (width 0.4) (layer "B.Cu") (net 9))
  (segment (start 138.015 82.25) (end 137.565 81.8) (width 0.4) (layer "B.Cu") (net 9))
  (segment (start 251.625 115.875) (end 251 115.25) (width 0.4) (layer "B.Cu") (net 9))
  (segment (start 183.300008 89.060008) (end 183.636328 89.060008) (width 0.2) (layer "B.Cu") (net 9))
  (segment (start 193.636328 87.461328) (end 193.636328 88.060008) (width 0.2) (layer "B.Cu") (net 9))
  (segment (start 125.3375 90.55) (end 125.3175 90.57) (width 0.1) (layer "B.Cu") (net 9))
  (segment (start 256.685 80.315) (end 256.1 80.9) (width 0.4) (layer "B.Cu") (net 9))
  (segment (start 255.445 106.985) (end 255.385 106.985) (width 0.4) (layer "B.Cu") (net 9))
  (segment (start 140 78.5) (end 140 77.7) (width 0.4) (layer "B.Cu") (net 9))
  (segment (start 255.62846 98.37846) (end 255.445 98.195) (width 0.4) (layer "B.Cu") (net 9))
  (segment (start 190.486328 91.060008) (end 190.096328 91.450008) (width 0.1) (layer "B.Cu") (net 9))
  (segment (start 192.636328 95.438672) (end 192.636328 95.060008) (width 0.2) (layer "B.Cu") (net 9))
  (segment (start 247.18 113.96) (end 247.825 114.605) (width 0.4) (layer "B.Cu") (net 9))
  (segment (start 196.52 96.55) (end 196.52 96.57) (width 0.2) (layer "B.Cu") (net 9))
  (segment (start 188.385008 89.060008) (end 188.636328 89.060008) (width 0.2) (layer "B.Cu") (net 9))
  (segment (start 173.1 98.37) (end 172.636328 98.833672) (width 0.2) (layer "B.Cu") (net 9))
  (segment (start 174.505 81.191336) (end 174.636328 81.060008) (width 0.2) (layer "B.Cu") (net 9))
  (segment (start 156.22 110.53) (end 156.434499 110.315501) (width 0.1) (layer "B.Cu") (net 9))
  (segment (start 181.364992 87.060008) (end 181.636328 87.060008) (width 0.2) (layer "B.Cu") (net 9))
  (segment (start 255.1 76.16) (end 255.445 76.505) (width 0.4) (layer "B.Cu") (net 9))
  (segment (start 256.715 80.315) (end 256.685 80.315) (width 0.4) (layer "B.Cu") (net 9))
  (segment (start 254.8 93.66) (end 255.445 93.015) (width 0.4) (layer "B.Cu") (net 9))
  (segment (start 194.425 81.505) (end 194.425 81.290844) (width 0.2) (layer "B.Cu") (net 9))
  (segment (start 245.285 76.505) (end 245.87 77.09) (width 0.4) (layer "B.Cu") (net 9))
  (segment (start 252.905 76.505) (end 252.905 76.495) (width 0.2) (layer "B.Cu") (net 9))
  (segment (start 172.52 88.176337) (end 172.636328 88.060009) (width 0.2) (layer "B.Cu") (net 9))
  (segment (start 178.187081 86.78) (end 178.467089 87.060008) (width 0.2) (layer "B.Cu") (net 9))
  (segment (start 161.235 99.575) (end 161.05 99.39) (width 0.15) (layer "B.Cu") (net 9))
  (segment (start 189.745 97.65) (end 189.925 97.83) (width 0.2) (layer "B.Cu") (net 9))
  (segment (start 187.32 83.32) (end 188.395844 83.32) (width 0.4) (layer "B.Cu") (net 9))
  (segment (start 164.6395 108.420941) (end 165.030941 108.420941) (width 0.2) (layer "B.Cu") (net 9))
  (segment (start 161.9 101.685) (end 162.9 101.685) (width 0.2) (layer "B.Cu") (net 9))
  (segment (start 176.395 90.495) (end 176.395 90.45) (width 0.2) (layer "B.Cu") (net 9))
  (segment (start 165.886328 54.575008) (end 165.886328 53.710008) (width 0.2) (layer "B.Cu") (net 9))
  (segment (start 256.1 124.12) (end 256.1 124.15) (width 0.4) (layer "B.Cu") (net 9))
  (segment (start 238.94 78.39) (end 238.94 78.04) (width 0.2) (layer "B.Cu") (net 9))
  (segment (start 187.364992 88.060008) (end 187.636328 88.060008) (width 0.2) (layer "B.Cu") (net 9))
  (segment (start 192.636328 94.801328) (end 192.636328 95.060008) (width 0.2) (layer "B.Cu") (net 9))
  (segment (start 186.636328 89.436328) (end 186.636328 89.060008) (width 0.2) (layer "B.Cu") (net 9))
  (segment (start 187.78 80.06) (end 187.5 80.34) (width 0.2) (layer "B.Cu") (net 9))
  (segment (start 158.59 103.445) (end 158.59 102.86) (width 0.15) (layer "B.Cu") (net 9))
  (segment (start 182.235 90.15) (end 182.235 90.335) (width 0.2) (layer "B.Cu") (net 9))
  (segment (start 250.365 76.505) (end 249.78 77.09) (width 0.4) (layer "B.Cu") (net 9))
  (segment (start 128.235 109.62) (end 129.075 109.62) (width 0.127) (layer "B.Cu") (net 9))
  (segment (start 120.736328 60.245008) (end 120.736328 60.830008) (width 0.2) (layer "B.Cu") (net 9))
  (segment (start 238.9 95.45) (end 238.9 93.05) (width 0.4) (layer "B.Cu") (net 9))
  (segment (start 244.64 87.29) (end 245.285 87.935) (width 0.4) (layer "B.Cu") (net 9))
  (segment (start 124.43 90.57) (end 123.6 91.4) (width 0.1) (layer "B.Cu") (net 9))
  (segment (start 253.56 106.33) (end 254.175 105.715) (width 0.4) (layer "B.Cu") (net 9))
  (segment (start 177.575 86.78) (end 178.187081 86.78) (width 0.2) (layer "B.Cu") (net 9))
  (segment (start 163.6 103.4) (end 163.6 102.78) (width 0.15) (layer "B.Cu") (net 9))
  (segment (start 256.715 75.235) (end 256.685 75.235) (width 0.4) (layer "B.Cu") (net 9))
  (segment (start 184.94 77.25) (end 184.425 77.25) (width 0.2) (layer "B.Cu") (net 9))
  (segment (start 238.2 79.75) (end 237.95 79.75) (width 0.2) (layer "B.Cu") (net 9))
  (segment (start 173.051328 57.710008) (end 172.186328 57.710008) (width 0.2) (layer "B.Cu") (net 9))
  (segment (start 183.439992 99.060008) (end 182.636328 99.060008) (width 0.2) (layer "B.Cu") (net 9))
  (segment (start 253.55 100.95) (end 253.86 100.95) (width 0.4) (layer "B.Cu") (net 9))
  (segment (start 164.6395 106.4205) (end 163.805556 106.4205) (width 0.15) (layer "B.Cu") (net 9))
  (segment (start 199.05 54.265) (end 199.05 53.55) (width 0.2) (layer "B.Cu") (net 9))
  (segment (start 256.07 96.52) (end 255.75 96.52) (width 0.4) (layer "B.Cu") (net 9))
  (segment (start 256.1 93.67) (end 256.715 94.285) (width 0.4) (layer "B.Cu") (net 9))
  (segment (start 247.175 121.35) (end 246.95 121.35) (width 0.4) (layer "B.Cu") (net 9))
  (segment (start 254.175 95.555) (end 254.175 95.575) (width 0.4) (layer "B.Cu") (net 9))
  (segment (start 252.905 90.475) (end 252.905 90.505) (width 0.4) (layer "B.Cu") (net 9))
  (segment (start 180.97 95.575) (end 181.15132 95.575) (width 0.2) (layer "B.Cu") (net 9))
  (segment (start 248.45 93.66) (end 249.095 93.015) (width 0.4) (layer "B.Cu") (net 9))
  (segment (start 251.635 85.4645) (end 251.1 85.9995) (width 0.4) (layer "B.Cu") (net 9))
  (segment (start 253.56 111.41) (end 254.175 110.795) (width 0.4) (layer "B.Cu") (net 9))
  (segment (start 164.551328 57.610008) (end 163.986328 57.610008) (width 0.2) (layer "B.Cu") (net 9))
  (segment (start 231.8 125.815) (end 232.485 125.815) (width 0.2) (layer "B.Cu") (net 9))
  (segment (start 252.845 117.145) (end 252.26 116.56) (width 0.4) (layer "B.Cu") (net 9))
  (segment (start 186.636328 94.330008) (end 186.816328 94.510008) (width 0.1) (layer "B.Cu") (net 9))
  (segment (start 163.414499 103.585501) (end 163.414499 104.195501) (width 0.15) (layer "B.Cu") (net 9))
  (segment (start 153.6895 105.420185) (end 152.950315 105.420185) (width 0.15) (layer "B.Cu") (net 9))
  (segment (start 166.306328 94.585008) (end 166.306328 93.830008) (width 0.2) (layer "B.Cu") (net 9))
  (segment (start 165.715008 99.965008) (end 166.306328 99.965008) (width 0.2) (layer "B.Cu") (net 9))
  (segment (start 256.1 78.4) (end 256.1 78.43) (width 0.4) (layer "B.Cu") (net 9))
  (segment (start 179.946828 82.73) (end 180.636328 82.0405) (width 0.2) (layer "B.Cu") (net 9))
  (segment (start 183.636328 94.060008) (end 183.366328 94.060008) (width 0.1) (layer "B.Cu") (net 9))
  (segment (start 119.31 90.8575) (end 119.05 91.1175) (width 0.1) (layer "B.Cu") (net 9))
  (segment (start 181.636328 61.910008) (end 182.315928 61.910008) (width 0.2) (layer "B.Cu") (net 9))
  (segment (start 254.175 94.285) (end 254.8 93.66) (width 0.2) (layer "B.Cu") (net 9))
  (segment (start 121.426111 99.926111) (end 120.999 99.499) (width 0.127) (layer "B.Cu") (net 9))
  (segment (start 257.45 101.14) (end 256.945 100.635) (width 0.4) (layer "B.Cu") (net 9))
  (segment (start 251.635 81.565) (end 252.25 80.95) (width 0.4) (layer "B.Cu") (net 9))
  (segment (start 246.84 119.4) (end 246.555 119.685) (width 0.4) (layer "B.Cu") (net 9))
  (segment (start 192.22 101.025) (end 191.92 100.725) (width 0.2) (layer "B.Cu") (net 9))
  (segment (start 248.45 86.04) (end 249.095 85.395) (width 0.4) (layer "B.Cu") (net 9))
  (segment (start 158.95 101.035) (end 158.985 101.035) (width 0.2) (layer "B.Cu") (net 9))
  (segment (start 183.245828 80.65) (end 183.636328 81.0405) (width 0.2) (layer "B.Cu") (net 9))
  (segment (start 251.635 108.56) (end 251.975 108.9) (width 0.4) (layer "B.Cu") (net 9))
  (segment (start 185.436328 57.494008) (end 184.676928 57.494008) (width 0.2) (layer "B.Cu") (net 9))
  (segment (start 256.09 101.57) (end 255.78 101.57) (width 0.4) (layer "B.Cu") (net 9))
  (segment (start 127.05 88.74397) (end 127.42 88.37397) (width 0.1) (layer "B.Cu") (net 9))
  (segment (start 158.934499 109.165498) (end 158.9145 109.145499) (width 0.1) (layer "B.Cu") (net 9))
  (segment (start 238.85 90.55) (end 238.9 90.6) (width 0.2) (layer "B.Cu") (net 9))
  (segment (start 120.31 89.98) (end 120.32 89.99) (width 0.1) (layer "B.Cu") (net 9))
  (segment (start 171.456766 78.493508) (end 171.413258 78.45) (width 0.127) (layer "B.Cu") (net 9))
  (segment (start 238.9 88.45) (end 238.9 90.6) (width 0.4) (layer "B.Cu") (net 9))
  (segment (start 178.536328 87.129247) (end 178.467089 87.060008) (width 0.2) (layer "B.Cu") (net 9))
  (segment (start 129.61 108.81) (end 130.08 108.81) (width 0.127) (layer "B.Cu") (net 9))
  (segment (start 158.05 132.775) (end 157.25 132.775) (width 0.2) (layer "B.Cu") (net 9))
  (segment (start 157.84 101.035) (end 157.35 101.525) (width 0.2) (layer "B.Cu") (net 9))
  (segment (start 181.366328 92.060008) (end 181.186328 91.880008) (width 0.1) (layer "B.Cu") (net 9))
  (segment (start 253.53 86.04) (end 254.175 85.395) (width 0.4) (layer "B.Cu") (net 9))
  (segment (start 165.9 109.235) (end 165.9 110) (width 0.2) (layer "B.Cu") (net 9))
  (segment (start 158.671328 90.460008) (end 158.671328 91.025008) (width 0.2) (layer "B.Cu") (net 9))
  (segment (start 178.97 78.55) (end 178.97 78.67) (width 0.2) (layer "B.Cu") (net 9))
  (segment (start 136.6 109.585) (end 135.915 109.585) (width 0.127) (layer "B.Cu") (net 9))
  (segment (start 254.175 90.475) (end 254.175 89.875) (width 0.3) (layer "B.Cu") (net 9))
  (segment (start 125.1 132.1) (end 125.1 130.3) (width 0.2) (layer "B.Cu") (net 9))
  (segment (start 172.65 85.37) (end 172.65 86.046336) (width 0.2) (layer "B.Cu") (net 9))
  (segment (start 188.985008 89.060008) (end 188.636328 89.060008) (width 0.2) (layer "B.Cu") (net 9))
  (segment (start 249.72 106.34) (end 250.365 106.985) (width 0.4) (layer "B.Cu") (net 9))
  (segment (start 251.635 115.875) (end 251.625 115.875) (width 0.4) (layer "B.Cu") (net 9))
  (segment (start 192.2 90.22) (end 192.975 90.22) (width 0.2) (layer "B.Cu") (net 9))
  (segment (start 187.986328 53.531608) (end 187.986328 54.275008) (width 0.2) (layer "B.Cu") (net 9))
  (segment (start 161.9145 104.195501) (end 161.9145 103.7055) (width 0.15) (layer "B.Cu") (net 9))
  (segment (start 196.025836 77.690008) (end 196.655836 77.060008) (width 0.2) (layer "B.Cu") (net 9))
  (segment (start 171.413258 78.45) (end 171.105 78.45) (width 0.127) (layer "B.Cu") (net 9))
  (segment (start 171.175 81.9695) (end 170.5 82.6445) (width 0.2) (layer "B.Cu") (net 9))
  (segment (start 249.72 113.96) (end 250.365 114.605) (width 0.4) (layer "B.Cu") (net 9))
  (segment (start 163.6 103.4) (end 163.414499 103.585501) (width 0.15) (layer "B.Cu") (net 9))
  (segment (start 188.395844 83.32) (end 188.655836 83.060008) (width 0.4) (layer "B.Cu") (net 9))
  (segment (start 246.555 75.145) (end 246.555 75.235) (width 0.2) (layer "B.Cu") (net 9))
  (segment (start 127.05 89.3375) (end 127.05 88.74397) (width 0.1) (layer "B.Cu") (net 9))
  (segment (start 251.635 89.205) (end 251.635 89.485) (width 0.4) (layer "B.Cu") (net 9))
  (segment (start 245.91 78.42) (end 246.555 77.775) (width 0.4) (layer "B.Cu") (net 9))
  (segment (start 183.186328 88.880008) (end 183.186328 88.946328) (width 0.2) (layer "B.Cu") (net 9))
  (segment (start 161.934499 109.165498) (end 161.9145 109.145499) (width 0.1) (layer "B.Cu") (net 9))
  (segment (start 158.985 101.035) (end 159.4005 101.4505) (width 0.2) (layer "B.Cu") (net 9))
  (segment (start 192.32532 88.749) (end 192.636328 89.060008) (width 0.2) (layer "B.Cu") (net 9))
  (segment (start 251.635 96.865) (end 251.1 97.4) (width 0.4) (layer "B.Cu") (net 9))
  (segment (start 191.645828 82.05) (end 191.655836 82.060008) (width 0.2) (layer "B.Cu") (net 9))
  (segment (start 254.175 94.285) (end 254.085 94.285) (width 0.2) (layer "B.Cu") (net 9))
  (segment (start 216.118 89.063) (end 216.919356 89.063) (width 0.2) (layer "B.Cu") (net 9))
  (segment (start 135.36 105.423485) (end 135.911328 104.872157) (width 0.127) (layer "B.Cu") (net 9))
  (segment (start 252.905 94.285) (end 252.915 94.285) (width 0.4) (layer "B.Cu") (net 9))
  (segment (start 187.5 80.34) (end 187.5 80.88) (width 0.2) (layer "B.Cu") (net 9))
  (segment (start 171.075 96.621336) (end 171.636328 96.060008) (width 0.2) (layer "B.Cu") (net 9))
  (segment (start 251.585 93.015) (end 251 93.6) (width 0.4) (layer "B.Cu") (net 9))
  (segment (start 251.635 93.015) (end 251.585 93.015) (width 0.4) (layer "B.Cu") (net 9))
  (segment (start 188.636328 92.060008) (end 188.366328 92.060008) (width 0.1) (layer "B.Cu") (net 9))
  (segment (start 172.66632 99.09) (end 172.636328 99.060008) (width 0.15) (layer "B.Cu") (net 9))
  (segment (start 244.64 98.72) (end 245.285 99.365) (width 0.4) (layer "B.Cu") (net 9))
  (segment (start 153.6895 108.420941) (end 152.949559 108.420941) (width 0.15) (layer "B.Cu") (net 9))
  (segment (start 192.658 97.07) (end 192.41 96.822) (width 0.2) (layer "B.Cu") (net 9))
  (segment (start 257.505991 98.890089) (end 257.03108 99.365) (width 0.4) (layer "B.Cu") (net 9))
  (segment (start 157.751328 79.045008) (end 158.236328 78.560008) (width 0.1) (layer "B.Cu") (net 9))
  (segment (start 256.685 115.875) (end 256.1 116.46) (width 0.4) (layer "B.Cu") (net 9))
  (segment (start 252.905 79.369681) (end 252.905 79.045) (width 0.2) (layer "B.Cu") (net 9))
  (segment (start 193.086328 53.531608) (end 193.086328 54.275008) (width 0.2) (layer "B.Cu") (net 9))
  (segment (start 253.681345 74.071345) (end 253.681345 73.491267) (width 0.2) (layer "B.Cu") (net 9))
  (segment (start 190.195 79.68) (end 190.655836 79.219164) (width 0.2) (layer "B.Cu") (net 9))
  (segment (start 156.434499 109.165498) (end 156.4145 109.145499) (width 0.1) (layer "B.Cu") (net 9))
  (segment (start 194.03 91.5) (end 194.03 91.666336) (width 0.2) (layer "B.Cu") (net 9))
  (segment (start 248.45 78.42) (end 249.095 77.775) (width 0.4) (layer "B.Cu") (net 9))
  (segment (start 158.414499 104.195501) (end 158.414499 103.620501) (width 0.15) (layer "B.Cu") (net 9))
  (segment (start 179.275 79.755) (end 179.275 79.275) (width 0.2) (layer "B.Cu") (net 9))
  (segment (start 184.206828 80.47) (end 183.636328 81.0405) (width 0.2) (layer "B.Cu") (net 9))
  (segment (start 216.919356 89.063) (end 216.932356 89.05) (width 0.2) (layer "B.Cu") (net 9))
  (segment (start 195.05 77.95) (end 195.35 77.65) (width 0.2) (layer "B.Cu") (net 9))
  (segment (start 164.6395 104.920059) (end 165.379941 104.920059) (width 0.15) (layer "B.Cu") (net 9))
  (segment (start 181.15132 95.575) (end 181.636328 96.060008) (width 0.2) (layer "B.Cu") (net 9))
  (segment (start 255.385 81.585) (end 254.8 81) (width 0.4) (layer "B.Cu") (net 9))
  (segment (start 252.905 109.525) (end 252.9 109.525) (width 0.4) (layer "B.Cu") (net 9))
  (segment (start 196.42 100.57) (end 196.636328 100.786328) (width 0.2) (layer "B.Cu") (net 9))
  (segment (start 179.275 79.275) (end 179.5095 79.0405) (width 0.2) (layer "B.Cu") (net 9))
  (segment (start 238.7 93.25) (end 238.9 93.05) (width 0.2) (layer "B.Cu") (net 9))
  (segment (start 181.310008 89.060008) (end 181.636328 89.060008) (width 0.2) (layer "B.Cu") (net 9))
  (segment (start 174.505 81.65) (end 174.505 81.191336) (width 0.2) (layer "B.Cu") (net 9))
  (segment (start 152.9 100.025) (end 152.875 100.05) (width 0.2) (layer "B.Cu") (net 9))
  (segment (start 120.999 99.499) (end 120.155 99.499) (width 0.127) (layer "B.Cu") (net 9))
  (segment (start 120.34 90.27) (end 120.54 90.47) (width 0.1) (layer "B.Cu") (net 9))
  (segment (start 183.366328 92.060008) (end 183.186328 91.880008) (width 0.1) (layer "B.Cu") (net 9))
  (segment (start 184.366328 91.060008) (end 184.186328 91.240008) (width 0.1) (layer "B.Cu") (net 9))
  (segment (start 192.7 101.05) (end 192.685 101.065) (width 0.2) (layer "B.Cu") (net 9))
  (segment (start 188.575844 83.14) (end 188.655836 83.060008) (width 0.2) (layer "B.Cu") (net 9))
  (segment (start 183.186328 88.946328) (end 183.300008 89.060008) (width 0.2) (layer "B.Cu") (net 9))
  (segment (start 196.636328 100.786328) (end 196.636328 101.060008) (width 0.2) (layer "B.Cu") (net 9))
  (segment (start 182.364992 86.060008) (end 182.636328 86.060008) (width 0.2) (layer "B.Cu") (net 9))
  (segment (start 256.1 83.48) (end 256.1 83.51) (width 0.4) (layer "B.Cu") (net 9))
  (segment (start 237.95 84.45) (end 237.95 85.175) (width 0.2) (layer "B.Cu") (net 9))
  (segment (start 126.65 104.2) (end 126.25 104.6) (width 0.2) (layer "B.Cu") (net 9))
  (segment (start 138.2 101) (end 138.2 101.4) (width 0.2) (layer "B.Cu") (net 9))
  (segment (start 247.18 106.34) (end 247.825 106.985) (width 0.4) (layer "B.Cu") (net 9))
  (segment (start 119.756328 60.235008) (end 118.781328 60.235008) (width 0.2) (layer "B.Cu") (net 9))
  (segment (start 192.2 90.18) (end 192.080008 90.060008) (width 0.2) (layer "B.Cu") (net 9))
  (segment (start 249.095 120.955) (end 249.095 120.995) (width 0.4) (layer "B.Cu") (net 9))
  (segment (start 136.2 121.45) (end 136.2 120.2) (width 0.2) (layer "B.Cu") (net 9))
  (segment (start 184.636328 91.060008) (end 184.366328 91.060008) (width 0.1) (layer "B.Cu") (net 9))
  (segment (start 245.91 105.09) (end 246.555 104.445) (width 0.4) (layer "B.Cu") (net 9))
  (segment (start 248.45 89.85) (end 249.095 89.205) (width 0.4) (layer "B.Cu") (net 9))
  (segment (start 131.425 103.165) (end 132.215 103.165) (width 0.127) (layer "B.Cu") (net 9))
  (segment (start 171.075 96.73) (end 171.075 96.621336) (width 0.2) (layer "B.Cu") (net 9))
  (segment (start 127.42 88.37397) (end 127.42 87.906531) (width 0.1) (layer "B.Cu") (net 9))
  (segment (start 186.816328 95.780008) (end 186.816328 94.510008) (width 0.2) (layer "B.Cu") (net 9))
  (segment (start 193.459548 78.081816) (end 193.591364 77.95) (width 0.2) (layer "B.Cu") (net 9))
  (segment (start 161.9 102.5495) (end 161.75 102.6995) (width 0.2) (layer "B.Cu") (net 9))
  (segment (start 186.786328 94.060008) (end 187.086328 93.760008) (width 0.1) (layer "B.Cu") (net 9))
  (segment (start 186.63 87.55) (end 186.63 88.05368) (width 0.2) (layer "B.Cu") (net 9))
  (segment (start 247.658 46.902526) (end 247.663369 46.897157) (width 0.2) (layer "B.Cu") (net 9))
  (segment (start 126.05 88.835) (end 126.05 89.3375) (width 0.1) (layer "B.Cu") (net 9))
  (segment (start 182.636328 90.736328) (end 182.636328 91.060008) (width 0.2) (layer "B.Cu") (net 9))
  (segment (start 194.235 88.725) (end 194.636328 88.323672) (width 0.2) (layer "B.Cu") (net 9))
  (segment (start 177.53 101.55) (end 177.040008 101.060008) (width 0.2) (layer "B.Cu") (net 9))
  (segment (start 192.41 96.822) (end 192.41 96.6) (width 0.2) (layer "B.Cu") (net 9))
  (segment (start 176.224992 94.530008) (end 177.166328 94.530008) (width 0.2) (layer "B.Cu") (net 9))
  (segment (start 121.857386 100.575) (end 121.676724 100.394338) (width 0.127) (layer "B.Cu") (net 9))
  (segment (start 157.025 103.075) (end 157.025 102.8) (width 0.1) (layer "B.Cu") (net 9))
  (segment (start 121.736328 61.280008) (end 121.186328 61.830008) (width 0.2) (layer "B.Cu") (net 9))
  (segment (start 185.436328 53.531608) (end 185.436328 54.275008) (width 0.2) (layer "B.Cu") (net 9))
  (segment (start 164.186328 54.575008) (end 164.186328 53.710008) (width 0.2) (layer "B.Cu") (net 9))
  (segment (start 254.085 94.285) (end 253.5 93.7) (width 0.2) (layer "B.Cu") (net 9))
  (segment (start 247.2 124.2) (end 246.635 124.765) (width 0.2) (layer "B.Cu") (net 9))
  (segment (start 189.086328 89.161328) (end 188.985008 89.060008) (width 0.2) (layer "B.Cu") (net 9))
  (segment (start 256.11 103.7495) (end 256.11 103.84) (width 0.4) (layer "B.Cu") (net 9))
  (segment (start 118.3875 91.1175) (end 118.37 91.1) (width 0.1) (layer "B.Cu") (net 9))
  (segment (start 186.77 96.62) (end 186.77 97.415) (width 0.2) (layer "B.Cu") (net 9))
  (segment (start 184.686328 93.060008) (end 185.086328 93.460008) (width 0.1) (layer "B.Cu") (net 9))
  (segment (start 182.7 78.104172) (end 182.636328 78.0405) (width 0.2) (layer "B.Cu") (net 9))
  (segment (start 178.106328 92.601328) (end 178.106328 93.590008) (width 0.2) (layer "B.Cu") (net 9))
  (segment (start 253.55 99.075) (end 253.55 98.74) (width 0.2) (layer "B.Cu") (net 9))
  (segment (start 256.1 78.43) (end 256.715 79.045) (width 0.4) (layer "B.Cu") (net 9))
  (segment (start 247.18 110.15) (end 247.825 110.795) (width 0.4) (layer "B.Cu") (net 9))
  (segment (start 187.21632 100.64) (end 187.636328 101.060008) (width 0.2) (layer "B.Cu") (net 9))
  (segment (start 179.82132 90.245) (end 179.636328 90.060008) (width 0.2) (layer "B.Cu") (net 9))
  (segment (start 157.751328 79.860008) (end 157.751328 79.045008) (width 0.1) (layer "B.Cu") (net 9))
  (segment (start 135.36 105.675) (end 135.36 105.423485) (width 0.127) (layer "B.Cu") (net 9))
  (segment (start 193.64 102.775) (end 193.64 102.06368) (width 0.2) (layer "B.Cu") (net 9))
  (segment (start 247.8 126.3) (end 247.8 125.8) (width 0.2) (layer "B.Cu") (net 9))
  (segment (start 125.55 122.45) (end 124.4 121.3) (width 0.2) (layer "B.Cu") (net 9))
  (segment (start 190.636328 91.060008) (end 190.486328 91.060008) (width 0.1) (layer "B.Cu") (net 9))
  (segment (start 192.795 93.855) (end 192.795 93.525) (width 0.2) (layer "B.Cu") (net 9))
  (segment (start 252.905 101.905) (end 252.93 101.905) (width 0.4) (layer "B.Cu") (net 9))
  (segment (start 251.635 104.445) (end 251.635 104.415) (width 0.4) (layer "B.Cu") (net 9))
  (segment (start 256.1 119.04) (end 256.1 119.07) (width 0.4) (layer "B.Cu") (net 9))
  (segment (start 247.795 76.505) (end 247.21 77.09) (width 0.4) (layer "B.Cu") (net 9))
  (segment (start 193.85 101.6) (end 193.636328 101.813672) (width 0.2) (layer "B.Cu") (net 9))
  (segment (start 125.55 122.5) (end 125.55 122.45) (width 0.2) (layer "B.Cu") (net 9))
  (segment (start 134.98 103.075) (end 135.776657 103.075) (width 0.127) (layer "B.Cu") (net 9))
  (segment (start 183.186328 86.961328) (end 183.285008 87.060008) (width 0.2) (layer "B.Cu") (net 9))
  (segment (start 256.685 85.395) (end 256.1 85.98) (width 0.4) (layer "B.Cu") (net 9))
  (segment (start 256.685 90.475) (end 256.1 91.06) (width 0.4) (layer "B.Cu") (net 9))
  (segment (start 232.485 125.815) (end 232.5 125.8) (width 0.2) (layer "B.Cu") (net 9))
  (segment (start 255.78 101.57) (end 255.445 101.905) (width 0.4) (layer "B.Cu") (net 9))
  (segment (start 191.707 88.749) (end 192.32532 88.749) (width 0.2) (layer "B.Cu") (net 9))
  (segment (start 132.6 119.2) (end 131.95 118.55) (width 0.2) (layer "B.Cu") (net 9))
  (segment (start 157.35 101.525) (end 157 101.525) (width 0.2) (layer "B.Cu") (net 9))
  (segment (start 251.635 100.635) (end 251.075 100.075) (width 0.4) (layer "B.Cu") (net 9))
  (segment (start 162.615 121.265) (end 162.615 122.25) (width 0.2) (layer "B.Cu") (net 9))
  (segment (start 247.18 91.1) (end 247.825 91.745) (width 0.4) (layer "B.Cu") (net 9))
  (segment (start 192.685 101.065) (end 192.685 101.7) (width 0.2) (layer "B.Cu") (net 9))
  (segment (start 186.311328 96.285008) (end 186.816328 95.780008) (width 0.2) (layer "B.Cu") (net 9))
  (segment (start 173.97 94.65) (end 174.22632 94.65) (width 0.2) (layer "B.Cu") (net 9))
  (segment (start 157.671328 89.130008) (end 156.716328 89.130008) (width 0.2) (layer "B.Cu") (net 9))
  (segment (start 140.8 132.1) (end 140.8 130.4) (width 0.2) (layer "B.Cu") (net 9))
  (segment (start 186.636328 94.060008) (end 186.786328 94.060008) (width 0.1) (layer "B.Cu") (net 9))
  (segment (start 244.64 110.15) (end 245.285 110.795) (width 0.4) (layer "B.Cu") (net 9))
  (segment (start 253.885 99.075) (end 254.175 99.365) (width 0.4) (layer "B.Cu") (net 9))
  (segment (start 173.225 91.545) (end 173.225 91.64868) (width 0.2) (layer "B.Cu") (net 9))
  (segment (start 253.53 111.41) (end 253.56 111.41) (width 0.4) (layer "B.Cu") (net 9))
  (segment (start 119.31 89.98) (end 119.31 90.8575) (width 0.1) (layer "B.Cu") (net 9))
  (segment (start 181.005836 82.410008) (end 180.636328 82.0405) (width 0.2) (layer "B.Cu") (net 9))
  (segment (start 152.839563 106.420437) (end 152.83 106.43) (width 0.15) (layer "B.Cu") (net 9))
  (segment (start 254.8 124.14) (end 255.445 123.495) (width 0.4) (layer "B.Cu") (net 9))
  (segment (start 121.186328 61.830008) (end 118.776328 61.830008) (width 0.2) (layer "B.Cu") (net 9))
  (segment (start 184.911336 88.785) (end 184.636328 89.060008) (width 0.2) (layer "B.Cu") (net 9))
  (segment (start 251.995071 74.334929) (end 251.995071 73.491267) (width 0.2) (layer "B.Cu") (net 9))
  (segment (start 172.8 86.65) (end 172.636328 86.486328) (width 0.2) (layer "B.Cu") (net 9))
  (segment (start 186.196328 92.500008) (end 186.636328 92.060008) (width 0.2) (layer "B.Cu") (net 9))
  (segment (start 172.61 78.06) (end 172.176492 78.493508) (width 0.127) (layer "B.Cu") (net 9))
  (segment (start 171.836328 60.145008) (end 171.836328 61.010008) (width 0.2) (layer "B.Cu") (net 9))
  (segment (start 188.186328 88.861328) (end 188.385008 89.060008) (width 0.2) (layer "B.Cu") (net 9))
  (segment (start 253.56 108.91) (end 254.175 109.525) (width 0.4) (layer "B.Cu") (net 9))
  (segment (start 249.72 87.29) (end 250.365 87.935) (width 0.4) (layer "B.Cu") (net 9))
  (segment (start 245.925 119.375) (end 245.925 119.055) (width 0.4) (layer "B.Cu") (net 9))
  (segment (start 182.775 98.921336) (end 182.636328 99.060008) (width 0.2) (layer "B.Cu") (net 9))
  (segment (start 227.75 125.8) (end 226.315 125.8) (width 0.2) (layer "B.Cu") (net 9))
  (segment (start 194.03 91.666336) (end 193.636328 92.060008) (width 0.2) (layer "B.Cu") (net 9))
  (segment (start 167.586328 54.575008) (end 167.586328 53.710008) (width 0.2) (layer "B.Cu") (net 9))
  (segment (start 251.635 120.955) (end 251.635 121.015) (width 0.4) (layer "B.Cu") (net 9))
  (segment (start 136.2 120.2) (end 136.16751 120.16751) (width 0.2) (layer "B.Cu") (net 9))
  (segment (start 124.7 88.1) (end 125.315 88.1) (width 0.2) (layer "B.Cu") (net 9))
  (segment (start 190.7 82.55368) (end 190.886328 82.740008) (width 0.2) (layer "B.Cu") (net 9))
  (segment (start 175.636328 97.360008) (end 175.636328 98.060008) (width 0.2) (layer "B.Cu") (net 9))
  (segment (start 245.285 121.965) (end 245.285 122.225) (width 0.4) (layer "B.Cu") (net 9))
  (segment (start 255.29129 86.03634) (end 255.29129 86.51129) (width 0.4) (layer "B.Cu") (net 9))
  (segment (start 249.095 74.305) (end 249.095 75.235) (width 0.2) (layer "B.Cu") (net 9))
  (segment (start 192.7 101.05) (end 192.675 101.025) (width 0.2) (layer "B.Cu") (net 9))
  (segment (start 193.52 87.375) (end 193.55 87.375) (width 0.2) (layer "B.Cu") (net 9))
  (segment (start 253.55 80) (end 253.86 80) (width 0.4) (layer "B.Cu") (net 9))
  (segment (start 249.7675 117.8175) (end 250.365 118.415) (width 0.4) (layer "B.Cu") (net 9))
  (segment (start 194.5 77.95) (end 195.05 77.95) (width 0.2) (layer "B.Cu") (net 9))
  (segment (start 192.75 85.15) (end 192.66 85.15) (width 0.2) (layer "B.Cu") (net 9))
  (segment (start 135.915 109.585) (end 135.55 109.95) (width 0.127) (layer "B.Cu") (net 9))
  (segment (start 122.885 117.55) (end 123.65 117.55) (width 0.4) (layer "B.Cu") (net 9))
  (segment (start 182.886328 53.531608) (end 182.886328 54.275008) (width 0.2) (layer "B.Cu") (net 9))
  (segment (start 192.445 95.625) (end 192.45 95.625) (width 0.2) (layer "B.Cu") (net 9))
  (segment (start 245.285 123.495) (end 245.285 123.505) (width 0.4) (layer "B.Cu") (net 9))
  (segment (start 158.934499 110.315501) (end 158.934499 109.165498) (width 0.1) (layer "B.Cu") (net 9))
  (segment (start 181.796328 52.940008) (end 181.796328 52.933672) (width 0.2) (layer "B.Cu") (net 9))
  (segment (start 182.92 80.65) (end 183.245828 80.65) (width 0.2) (layer "B.Cu") (net 9))
  (segment (start 245.91 112.71) (end 246.555 112.065) (width 0.4) (layer "B.Cu") (net 9))
  (segment (start 184.335 90.135) (end 183.636328 89.436328) (width 0.2) (layer "B.Cu") (net 9))
  (segment (start 255.445 98.195) (end 255.445 98.095) (width 0.4) (layer "B.Cu") (net 9))
  (segment (start 185.611328 96.285008) (end 186.311328 96.285008) (width 0.2) (layer "B.Cu") (net 9))
  (segment (start 238.65 121.55) (end 238.6 121.5) (width 0.2) (layer "B.Cu") (net 9))
  (segment (start 193.311328 78.230036) (end 193.311328 78.965008) (width 0.2) (layer "B.Cu") (net 9))
  (segment (start 225.515 125.815) (end 225.5 125.8) (width 0.2) (layer "B.Cu") (net 9))
  (segment (start 183.636328 92.060008) (end 183.366328 92.060008) (width 0.1) (layer "B.Cu") (net 9))
  (segment (start 183.366328 94.060008) (end 183.186328 93.880008) (width 0.1) (layer "B.Cu") (net 9))
  (segment (start 252.905 105.715) (end 252.865 105.715) (width 0.4) (layer "B.Cu") (net 9))
  (segment (start 187.66 103.1) (end 188.5 103.1) (width 0.2) (layer "B.Cu") (net 9))
  (segment (start 193.64 102.06368) (end 193.636328 102.060008) (width 0.2) (layer "B.Cu") (net 9))
  (segment (start 175.225 94.471336) (end 174.636328 95.060008) (width 0.2) (layer "B.Cu") (net 9))
  (segment (start 132.6 119.2) (end 132.915 119.2) (width 0.2) (layer "B.Cu") (net 9))
  (segment (start 121.636328 54.175008) (end 121.636328 53.670008) (width 0.2) (layer "B.Cu") (net 9))
  (segment (start 190.02 78.7) (end 190.295828 78.7) (width 0.2) (layer "B.Cu") (net 9))
  (segment (start 182.693328 61.532608) (end 182.693328 59.975408) (width 0.2) (layer "B.Cu") (net 9))
  (segment (start 137.565 81.8) (end 135.846336 81.8) (width 0.4) (layer "B.Cu") (net 9))
  (segment (start 252.26 119.06) (end 252.905 118.415) (width 0.4) (layer "B.Cu") (net 9))
  (segment (start 245.77 74.36) (end 246.555 75.145) (width 0.2) (layer "B.Cu") (net 9))
  (segment (start 162.1 103.52) (end 162.1 103.23) (width 0.15) (layer "B.Cu") (net 9))
  (segment (start 199.235 111.1) (end 199.235 111.865) (width 0.2) (layer "B.Cu") (net 9))
  (segment (start 155.551328 88.295008) (end 155.536328 88.310008) (width 0.2) (layer "B.Cu") (net 9))
  (segment (start 256.1 83.51) (end 256.715 84.125) (width 0.4) (layer "B.Cu") (net 9))
  (segment (start 251.635 81.585) (end 251.635 81.565) (width 0.4) (layer "B.Cu") (net 9))
  (segment (start 249.095 120.995) (end 249.725 121.625) (width 0.4) (layer "B.Cu") (net 9))
  (segment (start 153.615 100.025) (end 152.9 100.025) (width 0.2) (layer "B.Cu") (net 9))
  (segment (start 131.425 105.065) (end 132.065 105.065) (width 0.127) (layer "B.Cu") (net 9))
  (segment (start 254.175 89.205) (end 254.175 89.825) (width 0.3) (layer "B.Cu") (net 9))
  (segment (start 256.044979 98.37846) (end 255.62846 98.37846) (width 0.4) (layer "B.Cu") (net 9))
  (segment (start 182.315928 61.910008) (end 182.693328 61.532608) (width 0.2) (layer "B.Cu") (net 9))
  (segment (start 162.9 101.685) (end 163.765 101.685) (width 0.2) (layer "B.Cu") (net 9))
  (segment (start 185.625 90.025) (end 185.7 90.025) (width 0.2) (layer "B.Cu") (net 9))
  (segment (start 193.55 87.375) (end 193.636328 87.461328) (width 0.2) (layer "B.Cu") (net 9))
  (segment (start 249.115 119.685) (end 249.745 119.055) (width 0.4) (layer "B.Cu") (net 9))
  (segment (start 183.285008 87.060008) (end 183.636328 87.060008) (width 0.2) (layer "B.Cu") (net 9))
  (segment (start 182.045 77.475) (end 182.070828 77.475) (width 0.2) (layer "B.Cu") (net 9))
  (segment (start 255.445 122.225) (end 255.385 122.225) (width 0.4) (layer "B.Cu") (net 9))
  (segment (start 129.47 109.225) (end 129.47 108.95) (width 0.127) (layer "B.Cu") (net 9))
  (segment (start 182.235 90.335) (end 182.636328 90.736328) (width 0.2) (layer "B.Cu") (net 9))
  (segment (start 180.95 96.38) (end 181.316336 96.38) (width 0.2) (layer "B.Cu") (net 9))
  (segment (start 178.536328 88.260008) (end 178.536328 87.129247) (width 0.2) (layer "B.Cu") (net 9))
  (segment (start 156.8945 103.2055) (end 156.8945 104.175502) (width 0.1) (layer "B.Cu") (net 9))
  (segment (start 251.635 124.765) (end 251.635 125.745) (width 0.2) (layer "B.Cu") (net 9))
  (segment (start 248.31 73.52) (end 249.095 74.305) (width 0.2) (layer "B.Cu") (net 9))
  (segment (start 247.18 83.48) (end 247.825 84.125) (width 0.4) (layer "B.Cu") (net 9))
  (segment (start 247.18 94.91) (end 247.825 95.555) (width 0.4) (layer "B.Cu") (net 9))
  (segment (start 120.626328 54.175008) (end 120.626328 53.670008) (width 0.2) (layer "B.Cu") (net 9))
  (segment (start 181.234992 86.930008) (end 181.364992 87.060008) (width 0.2) (layer "B.Cu") (net 9))
  (segment (start 171.175 81.67) (end 171.175 81.9695) (width 0.2) (layer "B.Cu") (net 9))
  (segment (start 255.445 91.745) (end 255.385 91.745) (width 0.4) (layer "B.Cu") (net 9))
  (segment (start 154.525 103.091029) (end 154.525 102.8) (width 0.1) (layer "B.Cu") (net 9))
  (segment (start 254.175 89.825) (end 254.15 89.85) (width 0.3) (layer "B.Cu") (net 9))
  (segment (start 257.1055 95.555) (end 256.715 95.555) (width 0.4) (layer "B.Cu") (net 9))
  (segment (start 118.781328 60.235008) (end 118.776328 60.240008) (width 0.2) (layer "B.Cu") (net 9))
  (segment (start 190.295828 78.7) (end 190.655836 79.060008) (width 0.2) (layer "B.Cu") (net 9))
  (segment (start 250.37 123.495) (end 251 124.125) (width 0.4) (layer "B.Cu") (net 9))
  (segment (start 249.72 79.67) (end 250.365 80.315) (width 0.4) (layer "B.Cu") (net 9))
  (segment (start 250.365 123.495) (end 250.37 123.495) (width 0.4) (layer "B.Cu") (net 9))
  (segment (start 252.905 117.145) (end 252.845 117.145) (width 0.4) (layer "B.Cu") (net 9))
  (segment (start 153.215 79.1) (end 153.215 79.993126) (width 0.2) (layer "B.Cu") (net 9))
  (segment (start 247.825 122.2) (end 248.425 121.6) (width 0.4) (layer "B.Cu") (net 9))
  (segment (start 253.2 76.2) (end 253.2 75.9) (width 0.4) (layer "B.Cu") (net 9))
  (segment (start 186.976328 89.776328) (end 186.636328 89.436328) (width 0.2) (layer "B.Cu") (net 9))
  (segment (start 250.365 122.225) (end 250.4 122.225) (width 0.4) (layer "B.Cu") (net 9))
  (segment (start 172.636328 86.486328) (end 172.636328 86.060008) (width 0.2) (layer "B.Cu") (net 9))
  (segment (start 254.175 77.795) (end 254.8 78.42) (width 0.4) (layer "B.Cu") (net 9))
  (segment (start 251.635 85.395) (end 251.635 85.4645) (width 0.4) (layer "B.Cu") (net 9))
  (segment (start 182.636328 91.060008) (end 182.366328 91.060008) (width 0.1) (layer "B.Cu") (net 9))
  (segment (start 121.11 95.49) (end 121.11 95.28) (width 0.2) (layer "B.Cu") (net 9))
  (segment (start 186.136328 92.500008) (end 186.196328 92.500008) (width 0.2) (layer "B.Cu") (net 9))
  (segment (start 135.846336 81.8) (end 135.836328 81.810008) (width 0.4) (layer "B.Cu") (net 9))
  (segment (start 160.425 102.8) (end 160.425 104.185001) (width 0.1) (layer "B.Cu") (net 9))
  (segment (start 254.115 119.685) (end 253.53 119.1) (width 0.4) (layer "B.Cu") (net 9))
  (segment (start 172.176492 78.493508) (end 171.456766 78.493508) (width 0.127) (layer "B.Cu") (net 9))
  (segment (start 192.977732 77.6) (end 192.82 77.6) (width 0.2) (layer "B.Cu") (net 9))
  (segment (start 195.636328 77.690008) (end 196.025836 77.690008) (width 0.2) (layer "B.Cu") (net 9))
  (segment (start 177.53 101.56) (end 177.53 101.55) (width 0.2) (layer "B.Cu") (net 9))
  (segment (start 120.496328 61.070008) (end 118.776328 61.070008) (width 0.2) (layer "B.Cu") (net 9))
  (segment (start 249.5 117.8175) (end 249.7675 117.8175) (width 0.4) (layer "B.Cu") (net 9))
  (segment (start 252.905 76.495) (end 253.2 76.2) (width 0.4) (layer "B.Cu") (net 9))
  (segment (start 181.2 86.930008) (end 181.234992 86.930008) (width 0.2) (layer "B.Cu") (net 9))
  (segment (start 256.715 85.395) (end 256.685 85.395) (width 0.4) (layer "B.Cu") (net 9))
  (segment (start 158.72 110.53) (end 158.934499 110.315501) (width 0.1) (layer "B.Cu") (net 9))
  (segment (start 192.2 90.22) (end 192.2 90.18) (width 0.2) (layer "B.Cu") (net 9))
  (segment (start 247.175 119.4) (end 246.84 119.4) (width 0.4) (layer "B.Cu") (net 9))
  (segment (start 253.534926 83.898226) (end 253.7617 84.125) (width 0.4) (layer "B.Cu") (net 9))
  (segment (start 256.1 88.56) (end 256.1 88.59) (width 0.4) (layer "B.Cu") (net 9))
  (segment (start 256.685 110.795) (end 256.1 111.38) (width 0.4) (layer "B.Cu") (net 9))
  (segment (start 174.33 102.6) (end 174.25 102.6) (width 0.2) (layer "B.Cu") (net 9))
  (segment (start 256.1 108.88) (end 256.1 108.91) (width 0.4) (layer "B.Cu") (net 9))
  (segment (start 184.636328 93.060008) (end 184.366328 93.060008) (width 0.1) (layer "B.Cu") (net 9))
  (segment (start 158.414499 103.620501) (end 158.59 103.445) (width 0.15) (layer "B.Cu") (net 9))
  (segment (start 192.7 99) (end 192.7 98.88) (width 0.2) (layer "B.Cu") (net 9))
  (segment (start 256.1 88.59) (end 256.715 89.205) (width 0.4) (layer "B.Cu") (net 9))
  (segment (start 240.615 121.2) (end 239.9 121.2) (width 0.2) (layer "B.Cu") (net 9))
  (segment (start 165.379941 104.920059) (end 165.4 104.9) (width 0.15) (layer "B.Cu") (net 9))
  (segment (start 256.945 100.635) (end 256.715 100.635) (width 0.4) (layer "B.Cu") (net 9))
  (segment (start 192.26 94.425) (end 192.636328 94.801328) (width 0.2) (layer "B.Cu") (net 9))
  (segment (start 251.635 96.825) (end 251.635 96.865) (width 0.4) (layer "B.Cu") (net 9))
  (segment (start 251.635 125.745) (end 251.65 125.76) (width 0.2) (layer "B.Cu") (net 9))
  (segment (start 170.636328 102.986328) (end 170.636328 103.060008) (width 0.15) (layer "B.Cu") (net 9))
  (segment (start 181.316336 96.38) (end 181.636328 96.060008) (width 0.2) (layer "B.Cu") (net 9))
  (segment (start 193.88 99.5) (end 193.85 99.5) (width 0.2) (layer "B.Cu") (net 9))
  (segment (start 182.693328 59.975408) (end 182.886328 59.782408) (width 0.2) (layer "B.Cu") (net 9))
  (segment (start 174.7 80.996336) (end 174.636328 81.060008) (width 0.2) (layer "B.Cu") (net 9))
  (segment (start 254.8 83.5) (end 255.445 82.855) (width 0.4) (layer "B.Cu") (net 9))
  (segment (start 161.9145 103.7055) (end 162.1 103.52) (width 0.15) (layer "B.Cu") (net 9))
  (segment (start 184.339992 86.060008) (end 184.636328 86.060008) (width 0.2) (layer "B.Cu") (net 9))
  (segment (start 246.95 121.35) (end 246.555 120.955) (width 0.4) (layer "B.Cu") (net 9))
  (segment (start 253.53 106.33) (end 253.56 106.33) (width 0.4) (layer "B.Cu") (net 9))
  (segment (start 247.18 79.67) (end 247.825 80.315) (width 0.4) (layer "B.Cu") (net 9))
  (segment (start 256.685 105.715) (end 256.1 106.3) (width 0.4) (layer "B.Cu") (net 9))
  (segment (start 137.89 100.69) (end 138.2 101) (width 0.2) (layer "B.Cu") (net 9))
  (segment (start 251.635 75.235) (end 251.635 74.695) (width 0.2) (layer "B.Cu") (net 9))
  (segment (start 180.636328 93.060008) (end 180.636328 93.690008) (width 0.1) (layer "B.Cu") (net 9))
  (segment (start 245.91 93.66) (end 246.555 93.015) (width 0.4) (layer "B.Cu") (net 9))
  (segment (start 252.905 113.335) (end 252.905 113.305) (width 0.4) (layer "B.Cu") (net 9))
  (segment (start 186.92 100.64) (end 187.21632 100.64) (width 0.2) (layer "B.Cu") (net 9))
  (segment (start 170.02 102.3) (end 170.02 102.37) (width 0.15) (layer "B.Cu") (net 9))
  (segment (start 190.536328 53.531608) (end 190.536328 54.275008) (width 0.2) (layer "B.Cu") (net 9))
  (segment (start 254.175 74.565) (end 253.681345 74.071345) (width 0.2) (layer "B.Cu") (net 9))
  (segment (start 254.8 119.06) (end 255.445 118.415) (width 0.4) (layer "B.Cu") (net 9))
  (segment (start 192.26 94.39) (end 192.795 93.855) (width 0.2) (layer "B.Cu") (net 9))
  (segment (start 119.05 91.1175) (end 118.3875 91.1175) (width 0.1) (layer "B.Cu") (net 9))
  (segment (start 245.91 89.85) (end 246.555 89.205) (width 0.4) (layer "B.Cu") (net 9))
  (segment (start 154.3945 104.175502) (end 154.3945 103.221529) (width 0.1) (layer "B.Cu") (net 9))
  (segment (start 161.72 110.53) (end 161.934499 110.315501) (width 0.1) (layer "B.Cu") (net 9))
  (segment (start 174.22632 94.65) (end 174.636328 95.060008) (width 0.2) (layer "B.Cu") (net 9))
  (segment (start 238.65 125.215) (end 238.115 125.215) (width 0.2) (layer "B.Cu") (net 9))
  (segment (start 247.18 98.72) (end 247.825 99.365) (width 0.4) (layer "B.Cu") (net 9))
  (segment (start 160.425 104.185001) (end 160.4145 104.195501) (width 0.1) (layer "B.Cu") (net 9))
  (segment (start 250.4 122.225) (end 250.925 121.7) (width 0.4) (layer "B.Cu") (net 9))
  (segment (start 247.446369 118.036369) (end 247.825 118.415) (width 0.4) (layer "B.Cu") (net 9))
  (segment (start 257.54 95.1205) (end 257.1055 95.555) (width 0.4) (layer "B.Cu") (net 9))
  (segment (start 244.64 102.53) (end 245.285 103.175) (width 0.4) (layer "B.Cu") (net 9))
  (segment (start 122.15 100.575) (end 121.857386 100.575) (width 0.127) (layer "B.Cu") (net 9))
  (segment (start 185.7 90.025) (end 186.636328 90.961328) (width 0.2) (layer "B.Cu") (net 9))
  (segment (start 192.7 98.88) (end 192.47 98.65) (width 0.2) (layer "B.Cu") (net 9))
  (segment (start 165.45 99.4) (end 165.45 99.7) (width 0.2) (layer "B.Cu") (net 9))
  (segment (start 186.78 97.425) (end 186.78 97.916336) (width 0.2) (layer "B.Cu") (net 9))
  (segment (start 171.836328 54.575008) (end 171.836328 53.710008) (width 0.2) (layer "B.Cu") (net 9))
  (segment (start 255.29129 86.51129) (end 255.445 86.665) (width 0.4) (layer "B.Cu") (net 9))
  (segment (start 244.64 83.48) (end 245.285 84.125) (width 0.4) (layer "B.Cu") (net 9))
  (segment (start 184.335 90.15) (end 184.335 90.135) (width 0.2) (layer "B.Cu") (net 9))
  (segment (start 248.45 108.9) (end 249.095 108.255) (width 0.4) (layer "B.Cu") (net 9))
  (segment (start 183.636328 101.336328) (end 183.636328 101.060008) (width 0.2) (layer "B.Cu") (net 9))
  (segment (start 198.7 58.985) (end 198.685 59) (width 0.2) (layer "B.Cu") (net 9))
  (segment (start 252.93 101.905) (end 253.5 102.475) (width 0.4) (layer "B.Cu") (net 9))
  (segment (start 178.05 92.545) (end 178.106328 92.601328) (width 0.2) (layer "B.Cu") (net 9))
  (segment (start 171.105 78.45) (end 171.075 78.42) (width 0.127) (layer "B.Cu") (net 9))
  (segment (start 253.56 103.83) (end 254.175 104.445) (width 0.4) (layer "B.Cu") (net 9))
  (segment (start 183.636328 89.436328) (end 183.636328 89.060008) (width 0.2) (layer "B.Cu") (net 9))
  (segment (start 160.736328 89.825008) (end 160.736328 90.560008) (width 0.2) (layer "B.Cu") (net 9))
  (segment (start 187.976328 57.468608) (end 187.216928 57.468608) (width 0.2) (layer "B.Cu") (net 9))
  (segment (start 135.595 97.37) (end 136.4645 97.37) (width 0.127) (layer "B.Cu") (net 9))
  (segment (start 165.845 109.235) (end 165.9 109.235) (width 0.2) (layer "B.Cu") (net 9))
  (segment (start 249.72 91.1) (end 250.365 91.745) (width 0.4) (layer "B.Cu") (net 9))
  (segment (start 161.05 99.39) (end 161.05 98.7) (width 0.15) (layer "B.Cu") (net 9))
  (segment (start 164.186328 60.145008) (end 164.186328 61.010008) (width 0.2) (layer "B.Cu") (net 9))
  (segment (start 187.186328 88.240008) (end 187.186328 88.238672) (width 0.2) (layer "B.Cu") (net 9))
  (segment (start 156.434499 110.315501) (end 156.434499 109.165498) (width 0.1) (layer "B.Cu") (net 9))
  (segment (start 121.9 121.3) (end 121.9 122.1) (width 0.4) (layer "B.Cu") (net 9))
  (segment (start 255.385 112.065) (end 254.8 111.48) (width 0.4) (layer "B.Cu") (net 9))
  (segment (start 247.825 122.225) (end 247.825 122.2) (width 0.4) (layer "B.Cu") (net 9))
  (segment (start 190.40632 97.83) (end 190.636328 98.060008) (width 0.2) (layer "B.Cu") (net 9))
  (segment (start 123.2296 123.4296) (end 123.2296 127.25) (width 0.4) (layer "B.Cu") (net 9))
  (segment (start 183.855 98.725) (end 183.775 98.725) (width 0.2) (layer "B.Cu") (net 9))
  (segment (start 189.925 97.83) (end 190.40632 97.83) (width 0.2) (layer "B.Cu") (net 9))
  (segment (start 188.636328 94.060008) (end 188.636328 94.280008) (width 0.1) (layer "B.Cu") (net 9))
  (segment (start 254.175 120.955) (end 254.175 121.015) (width 0.4) (layer "B.Cu") (net 9))
  (segment (start 184.366328 93.060008) (end 184.186328 93.240008) (width 0.1) (layer "B.Cu") (net 9))
  (segment (start 172.65 86.046336) (end 172.636328 86.060008) (width 0.2) (layer "B.Cu") (net 9))
  (segment (start 254.175 95.575) (end 253.6 96.15) (width 0.4) (layer "B.Cu") (net 9))
  (segment (start 192.975 90.22) (end 193.1 90.345) (width 0.2) (layer "B.Cu") (net 9))
  (segment (start 177.040008 101.060008) (end 176.636328 101.060008) (width 0.2) (layer "B.Cu") (net 9))
  (segment (start 248.45 112.71) (end 249.095 112.065) (width 0.4) (layer "B.Cu") (net 9))
  (segment (start 248.45 97.47) (end 249.095 96.825) (width 0.4) (layer "B.Cu") (net 9))
  (segment (start 127.425 104.2) (end 126.65 104.2) (width 0.2) (layer "B.Cu") (net 9))
  (segment (start 256.685 75.235) (end 256.1 75.82) (width 0.4) (layer "B.Cu") (net 9))
  (segment (start 192.878528 57.468608) (end 192.119128 57.468608) (width 0.2) (layer "B.Cu") (net 9))
  (segment (start 247.825 76.505) (end 247.795 76.505) (width 0.4) (layer "B.Cu") (net 9))
  (segment (start 149 126.075598) (end 149 125.579783) (width 0.1) (layer "F.Cu") (net 10))
  (segment (start 149.179 126.931) (end 149.28 126.83) (width 0.1) (layer "F.Cu") (net 10))
  (segment (start 144.712134 125.3) (end 143.65 124.237866) (width 0.1) (layer "F.Cu") (net 10))
  (segment (start 140.905 111.1825) (end 141.03 111.0575) (width 0.1) (layer "F.Cu") (net 10))
  (segment (start 149.6 129.05) (end 149.2 128.65) (width 0.1) (layer "F.Cu") (net 10))
  (segment (start 143.65 124.237866) (end 143.65 120.087866) (width 0.1) (layer "F.Cu") (net 10))
  (segment (start 149.2 128) (end 148.96 127.76) (width 0.1) (layer "F.Cu") (net 10))
  (segment (start 148.699999 130.27125) (end 148.699999 130.508411) (width 0.1) (layer "F.Cu") (net 10))
  (segment (start 149 125.579783) (end 148.720217 125.3) (width 0.1) (layer "F.Cu") (net 10))
  (segment (start 148.6 129.545) (end 148.6 130.171251) (width 0.1) (layer "F.Cu") (net 10))
  (segment (start 149.6 129.41) (end 149.6 129.05) (width 0.1) (layer "F.Cu") (net 10))
  (segment (start 149.2 128.65) (end 149.2 128) (width 0.1) (layer "F.Cu") (net 10))
  (segment (start 149.179 127.351) (end 149.179 126.931) (width 0.1) (layer "F.Cu") (net 10))
  (segment (start 142.912134 119.35) (end 141.562134 119.35) (width 0.1) (layer "F.Cu") (net 10))
  (segment (start 140.45 116.262134) (end 140.905 115.807134) (width 0.1) (layer "F.Cu") (net 10))
  (segment (start 143.65 120.087866) (end 142.912134 119.35) (width 0.1) (layer "F.Cu") (net 10))
  (segment (start 149.6 130.235) (end 149.875 130.51) (width 0.1) (layer "F.Cu") (net 10))
  (segment (start 148.96 127.76) (end 148.96 127.57) (width 0.1) (layer "F.Cu") (net 10))
  (segment (start 141.562134 119.35) (end 140.45 118.237866) (width 0.1) (layer "F.Cu") (net 10))
  (segment (start 149.6 129.545) (end 149.6 130.235) (width 0.1) (layer "F.Cu") (net 10))
  (segment (start 148.720217 125.3) (end 144.712134 125.3) (width 0.1) (layer "F.Cu") (net 10))
  (segment (start 148.699999 130.508411) (end 148.5 130.70841) (width 0.1) (layer "F.Cu") (net 10))
  (segment (start 149.28 126.355598) (end 149 126.075598) (width 0.1) (layer "F.Cu") (net 10))
  (segment (start 148.6 130.171251) (end 148.699999 130.27125) (width 0.1) (layer "F.Cu") (net 10))
  (segment (start 140.905 115.807134) (end 140.905 111.1825) (width 0.1) (layer "F.Cu") (net 10))
  (segment (start 140.45 118.237866) (end 140.45 116.262134) (width 0.1) (layer "F.Cu") (net 10))
  (segment (start 148.96 127.57) (end 149.179 127.351) (width 0.1) (layer "F.Cu") (net 10))
  (segment (start 149.28 126.83) (end 149.28 126.355598) (width 0.1) (layer "F.Cu") (net 10))
  (via (at 149.875 130.51) (size 0.5) (drill 0.2) (layers "F.Cu" "B.Cu") (net 10))
  (via (at 148.5 130.70841) (size 0.5) (drill 0.2) (layers "F.Cu" "B.Cu") (net 10))
  (segment (start 149.64341 130.27841) (end 149.875 130.51) (width 0.1) (layer "In9.Cu") (net 10))
  (segment (start 148.5 130.70841) (end 148.93 130.27841) (width 0.1) (layer "In9.Cu") (net 10))
  (segment (start 148.93 130.27841) (end 149.64341 130.27841) (width 0.1) (layer "In9.Cu") (net 10))
  (segment (start 149.1 129.545) (end 149.1 130.185) (width 0.1) (layer "F.Cu") (net 11))
  (segment (start 149 130.50841) (end 149.2 130.70841) (width 0.1) (layer "F.Cu") (net 11))
  (segment (start 148.595949 125.6) (end 144.587866 125.6) (width 0.1) (layer "F.Cu") (net 11))
  (segment (start 143.35 124.362134) (end 143.35 120.212134) (width 0.1) (layer "F.Cu") (net 11))
  (segment (start 140.655 111.1825) (end 140.53 111.0575) (width 0.1) (layer "F.Cu") (net 11))
  (segment (start 148.519 126.919) (end 148.419999 126.819999) (width 0.1) (layer "F.Cu") (net 11))
  (segment (start 148.419999 126.355599) (end 148.7 126.075598) (width 0.1) (layer "F.Cu") (net 11))
  (segment (start 148.1 129.05) (end 148.5 128.65) (width 0.1) (layer "F.Cu") (net 11))
  (segment (start 148.7 125.704051) (end 148.595949 125.6) (width 0.1) (layer "F.Cu") (net 11))
  (segment (start 148.5 128) (end 148.74 127.76) (width 0.1) (layer "F.Cu") (net 11))
  (segment (start 149.1 130.185) (end 149 130.285) (width 0.1) (layer "F.Cu") (net 11))
  (segment (start 142.787866 119.65) (end 141.437866 119.65) (width 0.1) (layer "F.Cu") (net 11))
  (segment (start 148.1 129.41) (end 148.1 129.05) (width 0.1) (layer "F.Cu") (net 11))
  (segment (start 148.5 128.65) (end 148.5 128) (width 0.1) (layer "F.Cu") (net 11))
  (segment (start 148.419999 126.819999) (end 148.419999 126.355599) (width 0.1) (layer "F.Cu") (net 11))
  (segment (start 144.587866 125.6) (end 143.35 124.362134) (width 0.1) (layer "F.Cu") (net 11))
  (segment (start 140.15 118.362134) (end 140.15 116.137866) (width 0.1) (layer "F.Cu") (net 11))
  (segment (start 148.1 130.26) (end 147.85 130.51) (width 0.1) (layer "F.Cu") (net 11))
  (segment (start 141.437866 119.65) (end 140.15 118.362134) (width 0.1) (layer "F.Cu") (net 11))
  (segment (start 148.74 127.58) (end 148.519 127.359) (width 0.1) (layer "F.Cu") (net 11))
  (segment (start 143.35 120.212134) (end 142.787866 119.65) (width 0.1) (layer "F.Cu") (net 11))
  (segment (start 148.7 126.075598) (end 148.7 125.704051) (width 0.1) (layer "F.Cu") (net 11))
  (segment (start 148.74 127.76) (end 148.74 127.58) (width 0.1) (layer "F.Cu") (net 11))
  (segment (start 148.519 127.359) (end 148.519 126.919) (width 0.1) (layer "F.Cu") (net 11))
  (segment (start 140.655 115.632866) (end 140.655 111.1825) (width 0.1) (layer "F.Cu") (net 11))
  (segment (start 140.15 116.137866) (end 140.655 115.632866) (width 0.1) (layer "F.Cu") (net 11))
  (segment (start 149 130.285) (end 149 130.50841) (width 0.1) (layer "F.Cu") (net 11))
  (segment (start 148.1 129.545) (end 148.1 130.26) (width 0.1) (layer "F.Cu") (net 11))
  (via (at 147.85 130.51) (size 0.5) (drill 0.2) (layers "F.Cu" "B.Cu") (net 11))
  (via (at 149.2 130.70841) (size 0.5) (drill 0.2) (layers "F.Cu" "B.Cu") (net 11))
  (segment (start 147.85 130.51) (end 148.08159 130.27841) (width 0.1) (layer "In2.Cu") (net 11))
  (segment (start 148.08159 130.27841) (end 148.77 130.27841) (width 0.1) (layer "In2.Cu") (net 11))
  (segment (start 148.77 130.27841) (end 149.2 130.70841) (width 0.1) (layer "In2.Cu") (net 11))
  (segment (start 148.536328 113.137157) (end 149.146328 113.137157) (width 0.1) (layer "F.Cu") (net 12))
  (segment (start 189.136328 92.560008) (end 189.636328 93.060008) (width 0.1) (layer "F.Cu") (net 12))
  (segment (start 228.09 81.45) (end 228.745 81.45) (width 0.12) (layer "F.Cu") (net 12))
  (segment (start 233.55 81.45) (end 229.993 81.45) (width 0.12) (layer "F.Cu") (net 12))
  (segment (start 227.76 81.78) (end 228.09 81.45) (width 0.12) (layer "F.Cu") (net 12))
  (segment (start 228.745 81.45) (end 229.993 81.45) (width 0.12) (layer "F.Cu") (net 12))
  (via (at 149.161328 113.122157) (size 0.5) (drill 0.2) (layers "F.Cu" "B.Cu") (net 12))
  (via (at 227.76 81.78) (size 0.5) (drill 0.2) (layers "F.Cu" "B.Cu") (net 12))
  (via (at 189.636328 93.060008) (size 0.5) (drill 0.2) (layers "F.Cu" "B.Cu") (net 12))
  (segment (start 188.622358 92.640008) (end 189.216328 92.640008) (width 0.1) (layer "In5.Cu") (net 12))
  (segment (start 188.2 92.21765) (end 188.622358 92.640008) (width 0.1) (layer "In5.Cu") (net 12))
  (segment (start 159.825 102.3) (end 169.802366 102.3) (width 0.1) (layer "In5.Cu") (net 12))
  (segment (start 169.802366 102.3) (end 170.622358 101.480008) (width 0.1) (layer "In5.Cu") (net 12))
  (segment (start 158.48603 103.21) (end 158.915 103.21) (width 0.1) (layer "In5.Cu") (net 12))
  (segment (start 158.915 103.21) (end 159.825 102.3) (width 0.1) (layer "In5.Cu") (net 12))
  (segment (start 173.216328 101.073978) (end 173.216328 94.883672) (width 0.1) (layer "In5.Cu") (net 12))
  (segment (start 172.810298 101.480008) (end 173.216328 101.073978) (width 0.1) (layer "In5.Cu") (net 12))
  (segment (start 153.675 102.375) (end 157.65103 102.375) (width 0.1) (layer "In5.Cu") (net 12))
  (segment (start 188.2 92.02971) (end 188.2 92.21765) (width 0.1) (layer "In5.Cu") (net 12))
  (segment (start 189.216328 92.640008) (end 189.636328 93.060008) (width 0.1) (layer "In5.Cu") (net 12))
  (segment (start 170.622358 101.480008) (end 172.810298 101.480008) (width 0.1) (layer "In5.Cu") (net 12))
  (segment (start 157.65103 102.375) (end 158.48603 103.21) (width 0.1) (layer "In5.Cu") (net 12))
  (segment (start 149.161328 113.122157) (end 151.5 110.783485) (width 0.1) (layer "In5.Cu") (net 12))
  (segment (start 176.55 91.55) (end 187.72029 91.55) (width 0.1) (layer "In5.Cu") (net 12))
  (segment (start 151.5 104.55) (end 153.675 102.375) (width 0.1) (layer "In5.Cu") (net 12))
  (segment (start 173.216328 94.883672) (end 176.55 91.55) (width 0.1) (layer "In5.Cu") (net 12))
  (segment (start 187.72029 91.55) (end 188.2 92.02971) (width 0.1) (layer "In5.Cu") (net 12))
  (segment (start 151.5 110.783485) (end 151.5 104.55) (width 0.1) (layer "In5.Cu") (net 12))
  (segment (start 191.944448 90.5) (end 191.81444 90.630008) (width 0.12) (layer "In7.Cu") (net 12))
  (segment (start 227.35 82.19) (end 227.35 87.15) (width 0.12) (layer "In7.Cu") (net 12))
  (segment (start 227.76 81.78) (end 227.35 82.19) (width 0.12) (layer "In7.Cu") (net 12))
  (segment (start 227.35 87.15) (end 224 90.5) (width 0.12) (layer "In7.Cu") (net 12))
  (segment (start 224 90.5) (end 191.944448 90.5) (width 0.12) (layer "In7.Cu") (net 12))
  (segment (start 189.2 90.888224) (end 189.2 92.62368) (width 0.12) (layer "In7.Cu") (net 12))
  (segment (start 191.81444 90.630008) (end 189.458216 90.630008) (width 0.12) (layer "In7.Cu") (net 12))
  (segment (start 189.458216 90.630008) (end 189.2 90.888224) (width 0.12) (layer "In7.Cu") (net 12))
  (segment (start 189.636328 93.060008) (end 189.206328 92.630008) (width 0.12) (layer "In7.Cu") (net 12))
  (segment (start 228.745 81.95) (end 229.993 81.95) (width 0.12) (layer "F.Cu") (net 13))
  (segment (start 230.46 81.95) (end 229.993 81.95) (width 0.12) (layer "F.Cu") (net 13))
  (segment (start 228.4 81.95) (end 228.745 81.95) (width 0.12) (layer "F.Cu") (net 13))
  (segment (start 231.96 83.45) (end 230.46 81.95) (width 0.12) (layer "F.Cu") (net 13))
  (segment (start 233.55 83.45) (end 231.96 83.45) (width 0.12) (layer "F.Cu") (net 13))
  (segment (start 148.541328 109.832157) (end 150.74632 109.832157) (width 0.15) (layer "F.Cu") (net 13))
  (segment (start 189.136328 90.560008) (end 189.636328 91.060008) (width 0.1) (layer "F.Cu") (net 13))
  (segment (start 227.97 82.38) (end 228.4 81.95) (width 0.12) (layer "F.Cu") (net 13))
  (segment (start 150.74632 109.832157) (end 150.786328 109.872165) (width 0.15) (layer "F.Cu") (net 13))
  (via (at 150.786328 109.872165) (size 0.5) (drill 0.2) (layers "F.Cu" "B.Cu") (net 13))
  (via (at 227.97 82.38) (size 0.5) (drill 0.2) (layers "F.Cu" "B.Cu") (net 13))
  (via (at 189.636328 91.060008) (size 0.5) (drill 0.2) (layers "F.Cu" "B.Cu") (net 13))
  (segment (start 176.216328 90.863688) (end 176.440008 90.640008) (width 0.1) (layer "In5.Cu") (net 13))
  (segment (start 157.688015 101.95) (end 157.778015 101.86) (width 0.1) (layer "In5.Cu") (net 13))
  (segment (start 150.786328 109.872165) (end 150.775 109.860837) (width 0.1) (layer "In5.Cu") (net 13))
  (segment (start 176.440008 90.640008) (end 189.216328 90.640008) (width 0.1) (layer "In5.Cu") (net 13))
  (segment (start 176.216328 91.083672) (end 176.216328 90.863688) (width 0.1) (layer "In5.Cu") (net 13))
  (segment (start 171.819992 100.480008) (end 172.2 100.1) (width 0.1) (layer "In5.Cu") (net 13))
  (segment (start 169.242366 101.86) (end 170.622358 100.480008) (width 0.1) (layer "In5.Cu") (net 13))
  (segment (start 157.778015 101.86) (end 169.242366 101.86) (width 0.1) (layer "In5.Cu") (net 13))
  (segment (start 172.2 100.1) (end 172.2 95.1) (width 0.1) (layer "In5.Cu") (net 13))
  (segment (start 153.15 101.95) (end 157.688015 101.95) (width 0.1) (layer "In5.Cu") (net 13))
  (segment (start 170.622358 100.480008) (end 171.819992 100.480008) (width 0.1) (layer "In5.Cu") (net 13))
  (segment (start 172.2 95.1) (end 176.216328 91.083672) (width 0.1) (layer "In5.Cu") (net 13))
  (segment (start 150.775 104.325) (end 153.15 101.95) (width 0.1) (layer "In5.Cu") (net 13))
  (segment (start 150.775 109.860837) (end 150.775 104.325) (width 0.1) (layer "In5.Cu") (net 13))
  (segment (start 189.216328 90.640008) (end 189.636328 91.060008) (width 0.1) (layer "In5.Cu") (net 13))
  (segment (start 224.856159 91) (end 192.5 91) (width 0.12) (layer "In7.Cu") (net 13))
  (segment (start 228.05 87.806159) (end 224.856159 91) (width 0.12) (layer "In7.Cu") (net 13))
  (segment (start 192.009992 91.490008) (end 190.066328 91.490008) (width 0.12) (layer "In7.Cu") (net 13))
  (segment (start 192.5 91) (end 192.009992 91.490008) (width 0.12) (layer "In7.Cu") (net 13))
  (segment (start 190.066328 91.490008) (end 189.636328 91.060008) (width 0.12) (layer "In7.Cu") (net 13))
  (segment (start 227.97 82.38) (end 228.05 82.46) (width 0.12) (layer "In7.Cu") (net 13))
  (segment (start 228.05 82.46) (end 228.05 87.806159) (width 0.12) (layer "In7.Cu") (net 13))
  (segment (start 230.459 78.951) (end 229.993 78.951) (width 0.12) (layer "F.Cu") (net 14))
  (segment (start 148.541328 111.982157) (end 149.521328 111.982157) (width 0.15) (layer "F.Cu") (net 14))
  (segment (start 231.959 77.451) (end 230.459 78.951) (width 0.12) (layer "F.Cu") (net 14))
  (segment (start 227.83 80.12) (end 227.83 79.41) (width 0.12) (layer "F.Cu") (net 14))
  (segment (start 228.289 78.951) (end 228.745 78.951) (width 0.12) (layer "F.Cu") (net 14))
  (segment (start 191.136328 88.560008) (end 190.636328 89.060008) (width 0.127) (layer "F.Cu") (net 14))
  (segment (start 229.993 78.951) (end 228.745 78.951) (width 0.12) (layer "F.Cu") (net 14))
  (segment (start 233.55 77.451) (end 231.959 77.451) (width 0.12) (layer "F.Cu") (net 14))
  (segment (start 227.83 79.41) (end 228.289 78.951) (width 0.12) (layer "F.Cu") (net 14))
  (via (at 190.636328 89.060008) (size 0.5) (drill 0.2) (layers "F.Cu" "B.Cu") (net 14))
  (via (at 227.83 80.12) (size 0.5) (drill 0.2) (layers "F.Cu" "B.Cu") (net 14))
  (via (at 149.536328 111.997157) (size 0.5) (drill 0.2) (layers "F.Cu" "B.Cu") (net 14))
  (segment (start 190.206328 88.630008) (end 176.472358 88.630008) (width 0.1) (layer "In5.Cu") (net 14))
  (segment (start 149.536328 111.997157) (end 149.536328 109.786328) (width 0.1) (layer "In5.Cu") (net 14))
  (segment (start 170.9 94.1) (end 170.9 96.959992) (width 0.1) (layer "In5.Cu") (net 14))
  (segment (start 149.332843 108.167157) (end 149 108.5) (width 0.1) (layer "In5.Cu") (net 14))
  (segment (start 152.205694 100.794306) (end 149.581328 103.418672) (width 0.1) (layer "In5.Cu") (net 14))
  (segment (start 190.636328 89.060008) (end 190.206328 88.630008) (width 0.1) (layer "In5.Cu") (net 14))
  (segment (start 170.216328 97.643664) (end 170.216328 98.483672) (width 0.1) (layer "In5.Cu") (net 14))
  (segment (start 176.216328 88.886038) (end 176.216328 89.1) (width 0.1) (layer "In5.Cu") (net 14))
  (segment (start 167.905694 100.794306) (end 152.205694 100.794306) (width 0.1) (layer "In5.Cu") (net 14))
  (segment (start 170.9 96.959992) (end 170.216328 97.643664) (width 0.1) (layer "In5.Cu") (net 14))
  (segment (start 175.83632 89.480008) (end 175.519992 89.480008) (width 0.1) (layer "In5.Cu") (net 14))
  (segment (start 175.519992 89.480008) (end 170.9 94.1) (width 0.1) (layer "In5.Cu") (net 14))
  (segment (start 149 108.5) (end 149 109.25) (width 0.1) (layer "In5.Cu") (net 14))
  (segment (start 170.216328 98.483672) (end 167.905694 100.794306) (width 0.1) (layer "In5.Cu") (net 14))
  (segment (start 176.216328 89.1) (end 175.83632 89.480008) (width 0.1) (layer "In5.Cu") (net 14))
  (segment (start 149 109.25) (end 149.536328 109.786328) (width 0.1) (layer "In5.Cu") (net 14))
  (segment (start 176.472358 88.630008) (end 176.216328 88.886038) (width 0.1) (layer "In5.Cu") (net 14))
  (segment (start 149.335298 108.167157) (end 149.332843 108.167157) (width 0.1) (layer "In5.Cu") (net 14))
  (segment (start 149.581328 103.418672) (end 149.581328 107.921127) (width 0.1) (layer "In5.Cu") (net 14))
  (segment (start 149.581328 107.921127) (end 149.335298 108.167157) (width 0.1) (layer "In5.Cu") (net 14))
  (segment (start 226.5 86.453663) (end 222.953663 90) (width 0.12) (layer "In7.Cu") (net 14))
  (segment (start 226.5 82.28) (end 226.5 86.453663) (width 0.12) (layer "In7.Cu") (net 14))
  (segment (start 227.43 81.35) (end 226.5 82.28) (width 0.12) (layer "In7.Cu") (net 14))
  (segment (start 191.61184 89.41184) (end 190.98816 89.41184) (width 0.12) (layer "In7.Cu") (net 14))
  (segment (start 190.98816 89.41184) (end 190.636328 89.060008) (width 0.12) (layer "In7.Cu") (net 14))
  (segment (start 192.2 90) (end 191.61184 89.41184) (width 0.12) (layer "In7.Cu") (net 14))
  (segment (start 227.83 80.12) (end 228.33 80.62) (width 0.12) (layer "In7.Cu") (net 14))
  (segment (start 228.33 81.08) (end 228.06 81.35) (width 0.12) (layer "In7.Cu") (net 14))
  (segment (start 228.06 81.35) (end 227.43 81.35) (width 0.12) (layer "In7.Cu") (net 14))
  (segment (start 228.33 80.62) (end 228.33 81.08) (width 0.12) (layer "In7.Cu") (net 14))
  (segment (start 222.953663 90) (end 192.2 90) (width 0.12) (layer "In7.Cu") (net 14))
  (segment (start 228.418 79.452) (end 228.745 79.452) (width 0.12) (layer "F.Cu") (net 15))
  (segment (start 227.86 80.88) (end 228.27 80.47) (width 0.12) (layer "F.Cu") (net 15))
  (segment (start 228.27 80.47) (end 228.27 79.6) (width 0.12) (layer "F.Cu") (net 15))
  (segment (start 228.27 79.6) (end 228.418 79.452) (width 0.12) (layer "F.Cu") (net 15))
  (segment (start 150.039179 110.907157) (end 150.136328 110.810008) (width 0.1) (layer "F.Cu") (net 15))
  (segment (start 190.136328 88.560008) (end 189.636328 89.060008) (width 0.127) (layer "F.Cu") (net 15))
  (segment (start 233.55 79.45) (end 229.995 79.45) (width 0.12) (layer "F.Cu") (net 15))
  (segment (start 228.745 79.452) (end 229.993 79.452) (width 0.12) (layer "F.Cu") (net 15))
  (segment (start 229.995 79.45) (end 229.993 79.452) (width 0.12) (layer "F.Cu") (net 15))
  (segment (start 148.541328 110.907157) (end 150.039179 110.907157) (width 0.1) (layer "F.Cu") (net 15))
  (via (at 189.636328 89.060008) (size 0.5) (drill 0.2) (layers "F.Cu" "B.Cu") (net 15))
  (via (at 227.86 80.88) (size 0.5) (drill 0.2) (layers "F.Cu" "B.Cu") (net 15))
  (via (at 150.136328 110.810008) (size 0.5) (drill 0.2) (layers "F.Cu" "B.Cu") (net 15))
  (segment (start 159.5695 101.0305) (end 160.4305 101.0305) (width 0.1) (layer "In5.Cu") (net 15))
  (segment (start 175.2 90.75) (end 176.309992 89.640008) (width 0.1) (layer "In5.Cu") (net 15))
  (segment (start 173.5 92.55) (end 173.740306 92.55) (width 0.1) (layer "In5.Cu") (net 15))
  (segment (start 164.9 101.3) (end 168.601544 101.3) (width 0.1) (layer "In5.Cu") (net 15))
  (segment (start 171.216328 94.833672) (end 173.5 92.55) (width 0.1) (layer "In5.Cu") (net 15))
  (segment (start 163.561 101.3) (end 163.8305 101.0305) (width 0.1) (layer "In5.Cu") (net 15))
  (segment (start 150.136328 108.94447) (end 150.156828 108.92397) (width 0.1) (layer "In5.Cu") (net 15))
  (segment (start 150.156828 108.92397) (end 150.156828 108.57603) (width 0.1) (layer "In5.Cu") (net 15))
  (segment (start 157.3 101) (end 157.6 101.3) (width 0.1) (layer "In5.Cu") (net 15))
  (segment (start 159.3 101.3) (end 159.5695 101.0305) (width 0.1) (layer "In5.Cu") (net 15))
  (segment (start 170.421536 99.480008) (end 170.810298 99.480008) (width 0.1) (layer "In5.Cu") (net 15))
  (segment (start 189.056328 89.640008) (end 189.636328 89.060008) (width 0.1) (layer "In5.Cu") (net 15))
  (segment (start 171.216328 99.073978) (end 171.216328 94.833672) (width 0.1) (layer "In5.Cu") (net 15))
  (segment (start 152.95 101.45) (end 156.2 101.45) (width 0.1) (layer "In5.Cu") (net 15))
  (segment (start 160.4305 101.0305) (end 160.7 101.3) (width 0.1) (layer "In5.Cu") (net 15))
  (segment (start 170.810298 99.480008) (end 171.216328 99.073978) (width 0.1) (layer "In5.Cu") (net 15))
  (segment (start 150.156828 108.57603) (end 150.136328 108.55553) (width 0.1) (layer "In5.Cu") (net 15))
  (segment (start 150.136328 103.938672) (end 152.175 101.9) (width 0.1) (layer "In5.Cu") (net 15))
  (segment (start 164.6305 101.0305) (end 164.9 101.3) (width 0.1) (layer "In5.Cu") (net 15))
  (segment (start 176.309992 89.640008) (end 189.056328 89.640008) (width 0.1) (layer "In5.Cu") (net 15))
  (segment (start 168.601544 101.3) (end 170.421536 99.480008) (width 0.1) (layer "In5.Cu") (net 15))
  (segment (start 173.740306 92.55) (end 175.2 91.090306) (width 0.1) (layer "In5.Cu") (net 15))
  (segment (start 163.8305 101.0305) (end 164.6305 101.0305) (width 0.1) (layer "In5.Cu") (net 15))
  (segment (start 160.7 101.3) (end 163.561 101.3) (width 0.1) (layer "In5.Cu") (net 15))
  (segment (start 156.2 101.45) (end 156.65 101) (width 0.1) (layer "In5.Cu") (net 15))
  (segment (start 152.175 101.9) (end 152.5 101.9) (width 0.1) (layer "In5.Cu") (net 15))
  (segment (start 152.5 101.9) (end 152.95 101.45) (width 0.1) (layer "In5.Cu") (net 15))
  (segment (start 175.2 91.090306) (end 175.2 90.75) (width 0.1) (layer "In5.Cu") (net 15))
  (segment (start 156.65 101) (end 157.3 101) (width 0.1) (layer "In5.Cu") (net 15))
  (segment (start 150.136328 110.810008) (end 150.136328 108.94447) (width 0.1) (layer "In5.Cu") (net 15))
  (segment (start 157.6 101.3) (end 159.3 101.3) (width 0.1) (layer "In5.Cu") (net 15))
  (segment (start 150.136328 108.55553) (end 150.136328 103.938672) (width 0.1) (layer "In5.Cu") (net 15))
  (segment (start 192.4 89.5) (end 191.7 88.8) (width 0.12) (layer "In7.Cu") (net 15))
  (segment (start 191.7 88.8) (end 191.15 88.8) (width 0.12) (layer "In7.Cu") (net 15))
  (segment (start 225.5295 85.6705) (end 221.7 89.5) (width 0.12) (layer "In7.Cu") (net 15))
  (segment (start 191.15 88.8) (end 190.875 88.525) (width 0.12) (layer "In7.Cu") (net 15))
  (segment (start 226.47 80.88) (end 225.5295 81.8205) (width 0.12) (layer "In7.Cu") (net 15))
  (segment (start 227.86 80.88) (end 226.47 80.88) (width 0.12) (layer "In7.Cu") (net 15))
  (segment (start 190.171336 88.525) (end 189.636328 89.060008) (width 0.12) (layer "In7.Cu") (net 15))
  (segment (start 225.5295 81.8205) (end 225.5295 85.6705) (width 0.12) (layer "In7.Cu") (net 15))
  (segment (start 190.875 88.525) (end 190.171336 88.525) (width 0.12) (layer "In7.Cu") (net 15))
  (segment (start 221.7 89.5) (end 192.4 89.5) (width 0.12) (layer "In7.Cu") (net 15))
  (segment (start 161.863477 96.797157) (end 162.586328 96.797157) (width 0.2) (layer "F.Cu") (net 16))
  (segment (start 164.15 103.72) (end 163.9 103.97) (width 0.2) (layer "F.Cu") (net 16))
  (segment (start 164.14 103.13) (end 164.15 103.14) (width 0.2) (layer "F.Cu") (net 16))
  (segment (start 164.15 103.14) (end 164.15 103.72) (width 0.2) (layer "F.Cu") (net 16))
  (via (at 162.586328 96.797157) (size 0.5) (drill 0.2) (layers "F.Cu" "B.Cu") (net 16))
  (via (at 164.14 103.13) (size 0.5) (drill 0.2) (layers "F.Cu" "B.Cu") (net 16))
  (segment (start 161.96 97.423485) (end 161.96 100.19) (width 0.15) (layer "In7.Cu") (net 16))
  (segment (start 162.586328 96.797157) (end 161.96 97.423485) (width 0.15) (layer "In7.Cu") (net 16))
  (segment (start 161.96 100.19) (end 164.14 102.37) (width 0.15) (layer "In7.Cu") (net 16))
  (segment (start 164.14 102.37) (end 164.14 103.13) (width 0.15) (layer "In7.Cu") (net 16))
  (segment (start 166.301328 96.520008) (end 166.301328 95.560008) (width 0.2) (layer "B.Cu") (net 16))
  (segment (start 163.9 103.37) (end 163.9 104.181) (width 0.15) (layer "B.Cu") (net 16))
  (segment (start 162.586328 96.797157) (end 166.024179 96.797157) (width 0.2) (layer "B.Cu") (net 16))
  (segment (start 164.14 103.13) (end 163.9 103.37) (width 0.15) (layer "B.Cu") (net 16))
  (segment (start 166.024179 96.797157) (end 166.301328 96.520008) (width 0.2) (layer "B.Cu") (net 16))
  (segment (start 163.9 104.181) (end 163.914501 104.195501) (width 0.15) (layer "B.Cu") (net 16))
  (segment (start 151.35 106.455) (end 151.35 106.4) (width 0.2) (layer "F.Cu") (net 17))
  (segment (start 151.35 106.4) (end 151.77 105.98) (width 0.2) (layer "F.Cu") (net 17))
  (segment (start 151.77 105.98) (end 152.37 105.98) (width 0.2) (layer "F.Cu") (net 17))
  (segment (start 162.763477 97.797157) (end 162.786328 97.820008) (width 0.2) (layer "F.Cu") (net 17))
  (segment (start 161.863477 97.797157) (end 162.763477 97.797157) (width 0.2) (layer "F.Cu") (net 17))
  (via (at 162.786328 97.820008) (size 0.5) (drill 0.2) (layers "F.Cu" "B.Cu") (net 17))
  (via (at 152.37 105.98) (size 0.5) (drill 0.2) (layers "F.Cu" "B.Cu") (net 17))
  (segment (start 155.955167 98.440841) (end 156.836008 97.56) (width 0.15) (layer "In7.Cu") (net 17))
  (segment (start 153.76 100.665) (end 155.955167 98.469833) (width 0.15) (layer "In7.Cu") (net 17))
  (segment (start 153.76 105.75) (end 153.76 100.665) (width 0.15) (layer "In7.Cu") (net 17))
  (segment (start 160.87 97.56) (end 162.13 96.3) (width 0.15) (layer "In7.Cu") (net 17))
  (segment (start 163.2 96.6) (end 163.2 97.406336) (width 0.15) (layer "In7.Cu") (net 17))
  (segment (start 162.9 96.3) (end 163.2 96.6) (width 0.15) (layer "In7.Cu") (net 17))
  (segment (start 162.13 96.3) (end 162.9 96.3) (width 0.15) (layer "In7.Cu") (net 17))
  (segment (start 153.525 105.985) (end 153.76 105.75) (width 0.15) (layer "In7.Cu") (net 17))
  (segment (start 155.955167 98.469833) (end 155.955167 98.440841) (width 0.15) (layer "In7.Cu") (net 17))
  (segment (start 152.375 105.985) (end 153.525 105.985) (width 0.15) (layer "In7.Cu") (net 17))
  (segment (start 156.836008 97.56) (end 160.87 97.56) (width 0.15) (layer "In7.Cu") (net 17))
  (segment (start 152.37 105.98) (end 152.375 105.985) (width 0.15) (layer "In7.Cu") (net 17))
  (segment (start 163.2 97.406336) (end 162.786328 97.820008) (width 0.15) (layer "In7.Cu") (net 17))
  (segment (start 166.306328 98.995008) (end 166.306328 98.025008) (width 0.2) (layer "B.Cu") (net 17))
  (segment (start 162.786328 97.820008) (end 165.186328 97.820008) (width 0.2) (layer "B.Cu") (net 17))
  (segment (start 165.386328 98.020008) (end 166.301328 98.020008) (width 0.2) (layer "B.Cu") (net 17))
  (segment (start 165.186328 97.820008) (end 165.386328 98.020008) (width 0.2) (layer "B.Cu") (net 17))
  (segment (start 153.6895 105.920311) (end 153.624811 105.985) (width 0.15) (layer "B.Cu") (net 17))
  (segment (start 152.375 105.985) (end 152.37 105.98) (width 0.15) (layer "B.Cu") (net 17))
  (segment (start 153.624811 105.985) (end 152.375 105.985) (width 0.15) (layer "B.Cu") (net 17))
  (segment (start 192.136328 89.560008) (end 191.64 89.06368) (width 0.12) (layer "F.Cu") (net 18))
  (segment (start 191.231148 88.075) (end 190.625 88.075) (width 0.12) (layer "F.Cu") (net 18))
  (segment (start 224.78 85.75) (end 224.78 86.75) (width 0.12) (layer "F.Cu") (net 18))
  (segment (start 224.78 86.88) (end 224.78 86.75) (width 0.12) (layer "F.Cu") (net 18))
  (segment (start 226.697 79.092) (end 226.697 80.353) (width 0.12) (layer "F.Cu") (net 18))
  (segment (start 222.62 84.695) (end 222.975 85.05) (width 0.12) (layer "F.Cu") (net 18))
  (segment (start 225.957624 81.092376) (end 224.147624 81.092376) (width 0.12) (layer "F.Cu") (net 18))
  (segment (start 226.697 80.353) (end 225.957624 81.092376) (width 0.12) (layer "F.Cu") (net 18))
  (segment (start 191.64 89.06368) (end 191.64 88.483852) (width 0.12) (layer "F.Cu") (net 18))
  (segment (start 224.147624 81.092376) (end 222.62 82.62) (width 0.12) (layer "F.Cu") (net 18))
  (segment (start 222.62 82.62) (end 222.62 84.695) (width 0.12) (layer "F.Cu") (net 18))
  (segment (start 191.64 88.483852) (end 191.231148 88.075) (width 0.12) (layer "F.Cu") (net 18))
  (segment (start 222.975 85.05) (end 224.08 85.05) (width 0.12) (layer "F.Cu") (net 18))
  (segment (start 224.08 85.05) (end 224.78 85.75) (width 0.12) (layer "F.Cu") (net 18))
  (via (at 222.975 85.05) (size 0.5) (drill 0.2) (layers "F.Cu" "B.Cu") (net 18))
  (via (at 190.625 88.075) (size 0.5) (drill 0.2) (layers "F.Cu" "B.Cu") (net 18))
  (segment (start 215.15 87.575) (end 217.7 85.025) (width 0.12) (layer "In7.Cu") (net 18))
  (segment (start 191.63 87.07) (end 198.345 87.07) (width 0.12) (layer "In7.Cu") (net 18))
  (segment (start 198.345 87.07) (end 198.85 87.575) (width 0.12) (layer "In7.Cu") (net 18))
  (segment (start 190.625 88.075) (end 191.63 87.07) (width 0.12) (layer "In7.Cu") (net 18))
  (segment (start 198.85 87.575) (end 215.15 87.575) (width 0.12) (layer "In7.Cu") (net 18))
  (segment (start 217.7 85.025) (end 222.95 85.025) (width 0.12) (layer "In7.Cu") (net 18))
  (segment (start 222.95 85.025) (end 222.975 85.05) (width 0.12) (layer "In7.Cu") (net 18))
  (segment (start 236.252 119.541) (end 237.1005 119.541) (width 0.1) (layer "F.Cu") (net 19))
  (segment (start 173.136328 101.560008) (end 172.636328 102.060008) (width 0.1) (layer "F.Cu") (net 19))
  (via (at 172.636328 102.060008) (size 0.5) (drill 0.2) (layers "F.Cu" "B.Cu") (net 19))
  (via (at 237.1005 119.541) (size 0.5) (drill 0.2) (layers "F.Cu" "B.Cu") (net 19))
  (segment (start 172.636328 102.060008) (end 172.636328 103.836328) (width 0.1) (layer "In9.Cu") (net 19))
  (segment (start 173.6 104.8) (end 187.4 104.8) (width 0.1) (layer "In9.Cu") (net 19))
  (segment (start 236.5915 120.05) (end 223.999273 120.05) (width 0.1) (layer "In9.Cu") (net 19))
  (segment (start 218.707454 108.560008) (end 222.941949 112.794504) (width 0.1) (layer "In9.Cu") (net 19))
  (segment (start 172.636328 103.836328) (end 173.6 104.8) (width 0.1) (layer "In9.Cu") (net 19))
  (segment (start 237.1005 119.541) (end 236.5915 120.05) (width 0.1) (layer "In9.Cu") (net 19))
  (segment (start 223.999273 120.05) (end 222.943777 118.994504) (width 0.1) (layer "In9.Cu") (net 19))
  (segment (start 191.160008 108.560008) (end 218.707454 108.560008) (width 0.1) (layer "In9.Cu") (net 19))
  (segment (start 187.4 104.8) (end 191.160008 108.560008) (width 0.1) (layer "In9.Cu") (net 19))
  (segment (start 222.943777 118.994504) (end 222.943777 112.794504) (width 0.1) (layer "In9.Cu") (net 19))
  (segment (start 222.40532 117.001) (end 222.364328 116.960008) (width 0.1) (layer "F.Cu") (net 20))
  (segment (start 172.136328 102.560008) (end 171.636328 103.060008) (width 0.1) (layer "F.Cu") (net 20))
  (segment (start 223.9155 117.001) (end 222.40532 117.001) (width 0.1) (layer "F.Cu") (net 20))
  (via (at 222.364328 116.960008) (size 0.5) (drill 0.2) (layers "F.Cu" "B.Cu") (net 20))
  (via (at 171.636328 103.060008) (size 0.5) (drill 0.2) (layers "F.Cu" "B.Cu") (net 20))
  (segment (start 222.4 113) (end 222.4 116.95) (width 0.1) (layer "In9.Cu") (net 20))
  (segment (start 191.060008 109.060008) (end 218.457454 109.060008) (width 0.1) (layer "In9.Cu") (net 20))
  (segment (start 218.457454 109.060008) (end 222.391949 112.994504) (width 0.1) (layer "In9.Cu") (net 20))
  (segment (start 173.175 105.2) (end 187.2 105.2) (width 0.1) (layer "In9.Cu") (net 20))
  (segment (start 171.636328 103.060008) (end 171.636328 103.661328) (width 0.1) (layer "In9.Cu") (net 20))
  (segment (start 187.2 105.2) (end 191.060008 109.060008) (width 0.1) (layer "In9.Cu") (net 20))
  (segment (start 171.636328 103.661328) (end 173.175 105.2) (width 0.1) (layer "In9.Cu") (net 20))
  (segment (start 223.403336 118.271) (end 222.917 118.271) (width 0.1) (layer "F.Cu") (net 21))
  (segment (start 175.136328 101.560008) (end 174.636328 102.060008) (width 0.1) (layer "F.Cu") (net 21))
  (segment (start 223.9155 118.271) (end 223.403336 118.271) (width 0.1) (layer "F.Cu") (net 21))
  (via (at 223.403336 118.271) (size 0.5) (drill 0.2) (layers "F.Cu" "B.Cu") (net 21))
  (via (at 174.636328 102.060008) (size 0.5) (drill 0.2) (layers "F.Cu" "B.Cu") (net 21))
  (segment (start 219.309281 107.560008) (end 191.360008 107.560008) (width 0.1) (layer "In9.Cu") (net 21))
  (segment (start 224.443777 112.694504) (end 219.309281 107.560008) (width 0.1) (layer "In9.Cu") (net 21))
  (segment (start 174.6 104) (end 174.086328 103.486328) (width 0.1) (layer "In9.Cu") (net 21))
  (segment (start 174.086328 103.486328) (end 174.086328 102.610008) (width 0.1) (layer "In9.Cu") (net 21))
  (segment (start 191.360008 107.560008) (end 187.8 104) (width 0.1) (layer "In9.Cu") (net 21))
  (segment (start 174.086328 102.610008) (end 174.636328 102.060008) (width 0.1) (layer "In9.Cu") (net 21))
  (segment (start 223.432785 118.255496) (end 224.443777 117.244504) (width 0.1) (layer "In9.Cu") (net 21))
  (segment (start 187.8 104) (end 174.6 104) (width 0.1) (layer "In9.Cu") (net 21))
  (segment (start 224.443777 117.244504) (end 224.443777 112.694504) (width 0.1) (layer "In9.Cu") (net 21))
  (segment (start 237.073336 117.001) (end 237.949 117.001) (width 0.1) (layer "F.Cu") (net 22))
  (segment (start 174.65 103.046336) (end 174.65 103.15) (width 0.1) (layer "F.Cu") (net 22))
  (segment (start 236.252 117.001) (end 237.073336 117.001) (width 0.1) (layer "F.Cu") (net 22))
  (segment (start 175.136328 102.560008) (end 174.65 103.046336) (width 0.1) (layer "F.Cu") (net 22))
  (via (at 174.65 103.15) (size 0.5) (drill 0.2) (layers "F.Cu" "B.Cu") (net 22))
  (via (at 237.073336 117.001) (size 0.5) (drill 0.2) (layers "F.Cu" "B.Cu") (net 22))
  (segment (start 229.634769 116.985496) (end 237.102785 116.985496) (width 0.1) (layer "In9.Cu") (net 22))
  (segment (start 219.707454 107.060008) (end 229.632941 116.985496) (width 0.1) (layer "In9.Cu") (net 22))
  (segment (start 174.8 103.6) (end 188 103.6) (width 0.1) (layer "In9.Cu") (net 22))
  (segment (start 191.460008 107.060008) (end 219.707454 107.060008) (width 0.1) (layer "In9.Cu") (net 22))
  (segment (start 174.65 103.15) (end 174.65 103.45) (width 0.1) (layer "In9.Cu") (net 22))
  (segment (start 174.65 103.45) (end 174.8 103.6) (width 0.1) (layer "In9.Cu") (net 22))
  (segment (start 188 103.6) (end 191.460008 107.060008) (width 0.1) (layer "In9.Cu") (net 22))
  (segment (start 192.646336 87.05) (end 192.136328 87.560008) (width 0.12) (layer "F.Cu") (net 23))
  (segment (start 197.225 87.05) (end 192.646336 87.05) (width 0.12) (layer "F.Cu") (net 23))
  (segment (start 197.675 87.5) (end 197.225 87.05) (width 0.12) (layer "F.Cu") (net 23))
  (segment (start 218.8 87.85) (end 219.65 87.85) (width 0.12) (layer "F.Cu") (net 23))
  (segment (start 219.65 87.85) (end 219.65 86.765) (width 0.12) (layer "F.Cu") (net 23))
  (segment (start 219.65 86.765) (end 219.665 86.75) (width 0.12) (layer "F.Cu") (net 23))
  (via (at 197.675 87.5) (size 0.5) (drill 0.2) (layers "F.Cu" "B.Cu") (net 23))
  (via (at 218.8 87.85) (size 0.5) (drill 0.2) (layers "F.Cu" "B.Cu") (net 23))
  (segment (start 198.25 88.125) (end 215.9 88.125) (width 0.12) (layer "In7.Cu") (net 23))
  (segment (start 197.675 87.5) (end 197.675 87.55) (width 0.12) (layer "In7.Cu") (net 23))
  (segment (start 218.275 87.325) (end 218.8 87.85) (width 0.12) (layer "In7.Cu") (net 23))
  (segment (start 216.7 87.325) (end 218.275 87.325) (width 0.12) (layer "In7.Cu") (net 23))
  (segment (start 197.675 87.55) (end 198.25 88.125) (width 0.12) (layer "In7.Cu") (net 23))
  (segment (start 215.9 88.125) (end 216.7 87.325) (width 0.12) (layer "In7.Cu") (net 23))
  (segment (start 197.245 88.07) (end 197.7 88.525) (width 0.12) (layer "F.Cu") (net 24))
  (segment (start 195.64632 88.07) (end 197.245 88.07) (width 0.12) (layer "F.Cu") (net 24))
  (segment (start 221.75 87.86) (end 221.74 87.85) (width 0.12) (layer "F.Cu") (net 24))
  (segment (start 221.75 88.6) (end 221.75 87.86) (width 0.12) (layer "F.Cu") (net 24))
  (segment (start 221.74 87.85) (end 221.74 86.75) (width 0.12) (layer "F.Cu") (net 24))
  (segment (start 195.64632 88.07) (end 195.136328 87.560008) (width 0.12) (layer "F.Cu") (net 24))
  (via (at 197.7 88.525) (size 0.5) (drill 0.2) (layers "F.Cu" "B.Cu") (net 24))
  (via (at 221.75 88.6) (size 0.5) (drill 0.2) (layers "F.Cu" "B.Cu") (net 24))
  (segment (start 198.05 88.875) (end 197.7 88.525) (width 0.12) (layer "In7.Cu") (net 24))
  (segment (start 203.055 88.62) (end 202.545 89.13) (width 0.12) (layer "In7.Cu") (net 24))
  (segment (start 201.175944 89.13) (end 200.920944 88.875) (width 0.12) (layer "In7.Cu") (net 24))
  (segment (start 200.920944 88.875) (end 198.05 88.875) (width 0.12) (layer "In7.Cu") (net 24))
  (segment (start 202.545 89.13) (end 201.175944 89.13) (width 0.12) (layer "In7.Cu") (net 24))
  (segment (start 221.75 88.6) (end 221.73 88.62) (width 0.12) (layer "In7.Cu") (net 24))
  (segment (start 221.73 88.62) (end 203.055 88.62) (width 0.12) (layer "In7.Cu") (net 24))
  (segment (start 190.136328 94.571554) (end 189.648539 95.059343) (width 0.1) (layer "F.Cu") (net 25))
  (segment (start 190.136328 94.560008) (end 190.136328 94.571554) (width 0.1) (layer "F.Cu") (net 25))
  (via (at 237.1 124.34) (size 0.5) (drill 0.2) (layers "F.Cu" "B.Cu") (net 25))
  (via (at 209.97 103.71) (size 0.5) (drill 0.2) (layers "F.Cu" "B.Cu") (net 25))
  (via (at 189.648539 95.059343) (size 0.5) (drill 0.2) (layers "F.Cu" "B.Cu") (net 25))
  (segment (start 237.1 114.8) (end 236.2 114.8) (width 0.1) (layer "In9.Cu") (net 25))
  (segment (start 220.5 105.4) (end 218.4465 105.4) (width 0.1) (layer "In9.Cu") (net 25))
  (segment (start 238.21 122.89) (end 238.21 121.14) (width 0.1) (layer "In9.Cu") (net 25))
  (segment (start 238.3 121.05) (end 238.3 116) (width 0.1) (layer "In9.Cu") (net 25))
  (segment (start 236.2 114.8) (end 235.8 114.4) (width 0.1) (layer "In9.Cu") (net 25))
  (segment (start 238.3 116) (end 237.1 114.8) (width 0.1) (layer "In9.Cu") (net 25))
  (segment (start 218.4465 105.4) (end 217.9465 104.9) (width 0.1) (layer "In9.Cu") (net 25))
  (segment (start 237.1 124.34) (end 237.1 124) (width 0.1) (layer "In9.Cu") (net 25))
  (segment (start 237.1 124) (end 238.21 122.89) (width 0.1) (layer "In9.Cu") (net 25))
  (segment (start 229.5 114.4) (end 220.5 105.4) (width 0.1) (layer "In9.Cu") (net 25))
  (segment (start 211.16 104.9) (end 209.97 103.71) (width 0.1) (layer "In9.Cu") (net 25))
  (segment (start 238.21 121.14) (end 238.3 121.05) (width 0.1) (layer "In9.Cu") (net 25))
  (segment (start 235.8 114.4) (end 229.5 114.4) (width 0.1) (layer "In9.Cu") (net 25))
  (segment (start 217.9465 104.9) (end 211.16 104.9) (width 0.1) (layer "In9.Cu") (net 25))
  (segment (start 189.648539 95.059343) (end 190.202828 95.613632) (width 0.1) (layer "B.Cu") (net 25))
  (segment (start 237.65 123.8) (end 238.585 123.8) (width 0.1) (layer "B.Cu") (net 25))
  (segment (start 208.5375 103.6875) (end 209.9475 103.6875) (width 0.1) (layer "B.Cu") (net 25))
  (segment (start 209.9475 103.6875) (end 209.97 103.71) (width 0.1) (layer "B.Cu") (net 25))
  (segment (start 190.202828 95.613632) (end 190.202828 96.532828) (width 0.1) (layer "B.Cu") (net 25))
  (segment (start 193.185 99.779314) (end 193.11 99.854314) (width 0.1) (layer "B.Cu") (net 25))
  (segment (start 193.185 104.185) (end 194.8 105.8) (width 0.1) (layer "B.Cu") (net 25))
  (segment (start 193.11 100.23) (end 193.185 100.305) (width 0.1) (layer "B.Cu") (net 25))
  (segment (start 193.11 99.854314) (end 193.11 100.23) (width 0.1) (layer "B.Cu") (net 25))
  (segment (start 192.88 97.56) (end 193.185 97.865) (width 0.1) (layer "B.Cu") (net 25))
  (segment (start 194.8 105.8) (end 206.425 105.8) (width 0.1) (layer "B.Cu") (net 25))
  (segment (start 237.65 123.8) (end 237.64 123.8) (width 0.1) (layer "B.Cu") (net 25))
  (segment (start 190.202828 96.532828) (end 191.23 97.56) (width 0.1) (layer "B.Cu") (net 25))
  (segment (start 193.185 97.865) (end 193.185 99.779314) (width 0.1) (layer "B.Cu") (net 25))
  (segment (start 193.185 100.305) (end 193.185 104.185) (width 0.1) (layer "B.Cu") (net 25))
  (segment (start 191.23 97.56) (end 192.88 97.56) (width 0.1) (layer "B.Cu") (net 25))
  (segment (start 206.425 105.8) (end 208.5375 103.6875) (width 0.1) (layer "B.Cu") (net 25))
  (segment (start 237.64 123.8) (end 237.1 124.34) (width 0.1) (layer "B.Cu") (net 25))
  (segment (start 165.429992 86.76635) (end 165.429992 86.473666) (width 0.1) (layer "F.Cu") (net 26))
  (segment (start 164.379992 86.473666) (end 164.379992 86.76635) (width 0.1) (layer "F.Cu") (net 26))
  (segment (start 157.686328 92.620008) (end 157.686328 87.603672) (width 0.1) (layer "F.Cu") (net 26))
  (segment (start 158.669992 86.620008) (end 163.533651 86.620008) (width 0.1) (layer "F.Cu") (net 26))
  (segment (start 157.686328 87.603672) (end 158.669992 86.620008) (width 0.1) (layer "F.Cu") (net 26))
  (segment (start 165.079992 86.473666) (end 165.079992 86.76635) (width 0.1) (layer "F.Cu") (net 26))
  (segment (start 164.526333 86.912691) (end 164.583651 86.912691) (width 0.1) (layer "F.Cu") (net 26))
  (segment (start 169.126328 84.560008) (end 171.136328 84.560008) (width 0.1) (layer "F.Cu") (net 26))
  (segment (start 165.783651 86.620008) (end 165.783651 86.76635) (width 0.1) (layer "F.Cu") (net 26))
  (segment (start 163.679992 86.766349) (end 163.679992 86.76635) (width 0.1) (layer "F.Cu") (net 26))
  (segment (start 165.779992 86.473666) (end 165.779992 86.620008) (width 0.1) (layer "F.Cu") (net 26))
  (segment (start 165.929992 86.912691) (end 165.98731 86.912691) (width 0.1) (layer "F.Cu") (net 26))
  (segment (start 166.279992 86.620008) (end 167.066328 86.620008) (width 0.1) (layer "F.Cu") (net 26))
  (segment (start 164.876333 86.327325) (end 164.933651 86.327325) (width 0.1) (layer "F.Cu") (net 26))
  (segment (start 166.133651 86.76635) (end 166.133651 86.766349) (width 0.1) (layer "F.Cu") (net 26))
  (segment (start 164.176333 86.327325) (end 164.233651 86.327325) (width 0.1) (layer "F.Cu") (net 26))
  (segment (start 163.826333 86.912691) (end 163.883651 86.912691) (width 0.1) (layer "F.Cu") (net 26))
  (segment (start 165.226333 86.912691) (end 165.283651 86.912691) (width 0.1) (layer "F.Cu") (net 26))
  (segment (start 164.029992 86.76635) (end 164.029992 86.473666) (width 0.1) (layer "F.Cu") (net 26))
  (segment (start 165.576333 86.327325) (end 165.633651 86.327325) (width 0.1) (layer "F.Cu") (net 26))
  (segment (start 167.066328 86.620008) (end 169.126328 84.560008) (width 0.1) (layer "F.Cu") (net 26))
  (segment (start 164.729992 86.76635) (end 164.729992 86.473666) (width 0.1) (layer "F.Cu") (net 26))
  (segment (start 165.779992 86.620008) (end 165.783651 86.620008) (width 0.1) (layer "F.Cu") (net 26))
  (via (at 157.711328 87.535008) (size 0.5) (drill 0.2) (layers "F.Cu" "B.Cu") (net 26))
  (arc (start 165.283651 86.912691) (mid 165.38713 86.869829) (end 165.429992 86.76635) (width 0.1) (layer "F.Cu") (net 26))
  (arc (start 164.029992 86.473666) (mid 164.072854 86.370187) (end 164.176333 86.327325) (width 0.1) (layer "F.Cu") (net 26))
  (arc (start 165.633651 86.327325) (mid 165.73713 86.370187) (end 165.779992 86.473666) (width 0.1) (layer "F.Cu") (net 26))
  (arc (start 164.933651 86.327325) (mid 165.03713 86.370187) (end 165.079992 86.473666) (width 0.1) (layer "F.Cu") (net 26))
  (arc (start 163.533651 86.620008) (mid 163.63713 86.66287) (end 163.679992 86.766349) (width 0.1) (layer "F.Cu") (net 26))
  (arc (start 165.429992 86.473666) (mid 165.472854 86.370187) (end 165.576333 86.327325) (width 0.1) (layer "F.Cu") (net 26))
  (arc (start 165.079992 86.76635) (mid 165.122854 86.869829) (end 165.226333 86.912691) (width 0.1) (layer "F.Cu") (net 26))
  (arc (start 164.233651 86.327325) (mid 164.33713 86.370187) (end 164.379992 86.473666) (width 0.1) (layer "F.Cu") (net 26))
  (arc (start 163.883651 86.912691) (mid 163.98713 86.869829) (end 164.029992 86.76635) (width 0.1) (layer "F.Cu") (net 26))
  (arc (start 165.783651 86.76635) (mid 165.826513 86.869829) (end 165.929992 86.912691) (width 0.1) (layer "F.Cu") (net 26))
  (arc (start 166.133651 86.766349) (mid 166.176513 86.66287) (end 166.279992 86.620008) (width 0.1) (layer "F.Cu") (net 26))
  (arc (start 164.729992 86.473666) (mid 164.772854 86.370187) (end 164.876333 86.327325) (width 0.1) (layer "F.Cu") (net 26))
  (arc (start 163.679992 86.76635) (mid 163.722854 86.869829) (end 163.826333 86.912691) (width 0.1) (layer "F.Cu") (net 26))
  (arc (start 164.379992 86.76635) (mid 164.422854 86.869829) (end 164.526333 86.912691) (width 0.1) (layer "F.Cu") (net 26))
  (arc (start 165.98731 86.912691) (mid 166.090789 86.869829) (end 166.133651 86.76635) (width 0.1) (layer "F.Cu") (net 26))
  (arc (start 164.583651 86.912691) (mid 164.68713 86.869829) (end 164.729992 86.76635) (width 0.1) (layer "F.Cu") (net 26))
  (segment (start 157.686328 86.805008) (end 157.686328 87.474306) (width 0.2) (layer "B.Cu") (net 26))
  (segment (start 157.671328 88.160008) (end 157.671328 87.575008) (width 0.2) (layer "B.Cu") (net 26))
  (segment (start 157.671328 87.575008) (end 157.711328 87.535008) (width 0.2) (layer "B.Cu") (net 26))
  (segment (start 169.20568 85.103168) (end 169.175576 85.073064) (width 0.1) (layer "F.Cu") (net 27))
  (segment (start 166.896328 87.160008) (end 166.896328 87.013721) (width 0.1) (layer "F.Cu") (net 27))
  (segment (start 167.250042 87.306294) (end 167.250042 87.306295) (width 0.1) (layer "F.Cu") (net 27))
  (segment (start 169.235785 85.875735) (end 169.235784 85.875735) (width 0.1) (layer "F.Cu") (net 27))
  (segment (start 168.988298 85.875735) (end 168.988298 85.875734) (width 0.1) (layer "F.Cu") (net 27))
  (segment (start 166.400042 87.160008) (end 159.496328 87.160008) (width 0.1) (layer "F.Cu") (net 27))
  (segment (start 167.93814 86.063012) (end 167.938141 86.063012) (width 0.1) (layer "F.Cu") (net 27))
  (segment (start 171.686327 85.010009) (end 169.546327 85.010009) (width 0.1) (layer "F.Cu") (net 27))
  (segment (start 168.433115 85.815524) (end 168.433115 85.815525) (width 0.1) (layer "F.Cu") (net 27))
  (segment (start 166.900042 87.306294) (end 166.900042 87.160008) (width 0.1) (layer "F.Cu") (net 27))
  (segment (start 158.186328 88.470008) (end 158.186328 92.620008) (width 0.1) (layer "F.Cu") (net 27))
  (segment (start 166.750042 86.867435) (end 166.692614 86.867435) (width 0.1) (layer "F.Cu") (net 27))
  (segment (start 166.546328 87.013721) (end 166.546328 87.013722) (width 0.1) (layer "F.Cu") (net 27))
  (segment (start 168.740811 86.370709) (end 168.74081 86.370709) (width 0.1) (layer "F.Cu") (net 27))
  (segment (start 167.720759 86.835579) (end 167.396328 87.160008) (width 0.1) (layer "F.Cu") (net 27))
  (segment (start 159.496328 87.160008) (end 158.186328 88.470008) (width 0.1) (layer "F.Cu") (net 27))
  (segment (start 166.900042 87.306295) (end 166.900042 87.306294) (width 0.1) (layer "F.Cu") (net 27))
  (segment (start 168.988298 85.875734) (end 168.680602 85.568038) (width 0.1) (layer "F.Cu") (net 27))
  (segment (start 168.433115 85.815525) (end 168.740811 86.123221) (width 0.1) (layer "F.Cu") (net 27))
  (segment (start 168.928088 85.320551) (end 169.235785 85.628247) (width 0.1) (layer "F.Cu") (net 27))
  (segment (start 167.99835 86.865683) (end 167.99835 86.865682) (width 0.1) (layer "F.Cu") (net 27))
  (segment (start 166.900042 87.160008) (end 166.896328 87.160008) (width 0.1) (layer "F.Cu") (net 27))
  (segment (start 167.99835 86.865682) (end 167.968247 86.835579) (width 0.1) (layer "F.Cu") (net 27))
  (segment (start 168.245837 86.865683) (end 168.245836 86.865683) (width 0.1) (layer "F.Cu") (net 27))
  (segment (start 168.928088 85.32055) (end 168.928088 85.320551) (width 0.1) (layer "F.Cu") (net 27))
  (segment (start 168.433114 85.568038) (end 168.433115 85.568038) (width 0.1) (layer "F.Cu") (net 27))
  (segment (start 168.493324 86.370709) (end 168.493324 86.370708) (width 0.1) (layer "F.Cu") (net 27))
  (segment (start 167.938141 86.310499) (end 168.245837 86.618195) (width 0.1) (layer "F.Cu") (net 27))
  (segment (start 169.546327 85.010009) (end 169.453168 85.103168) (width 0.1) (layer "F.Cu") (net 27))
  (segment (start 167.938141 86.310498) (end 167.938141 86.310499) (width 0.1) (layer "F.Cu") (net 27))
  (segment (start 168.493324 86.370708) (end 168.185628 86.063012) (width 0.1) (layer "F.Cu") (net 27))
  (segment (start 167.103756 87.452581) (end 167.046328 87.452581) (width 0.1) (layer "F.Cu") (net 27))
  (segment (start 172.136328 84.560008) (end 171.686327 85.010009) (width 0.1) (layer "F.Cu") (net 27))
  (via (at 158.686328 87.970008) (size 0.5) (drill 0.2) (layers "F.Cu" "B.Cu") (net 27))
  (arc (start 166.692614 86.867435) (mid 166.589174 86.910281) (end 166.546328 87.013721) (width 0.1) (layer "F.Cu") (net 27))
  (arc (start 168.185628 86.063012) (mid 168.061884 86.011756) (end 167.93814 86.063012) (width 0.1) (layer "F.Cu") (net 27))
  (arc (start 166.896328 87.013721) (mid 166.853482 86.910281) (end 166.750042 86.867435) (width 0.1) (layer "F.Cu") (net 27))
  (arc (start 168.740811 86.123221) (mid 168.792067 86.246965) (end 168.740811 86.370709) (width 0.1) (layer "F.Cu") (net 27))
  (arc (start 168.433115 85.568038) (mid 168.381859 85.691781) (end 168.433115 85.815524) (width 0.1) (layer "F.Cu") (net 27))
  (arc (start 167.938141 86.063012) (mid 167.886885 86.186755) (end 167.938141 86.310498) (width 0.1) (layer "F.Cu") (net 27))
  (arc (start 168.245837 86.618195) (mid 168.297093 86.741939) (end 168.245837 86.865683) (width 0.1) (layer "F.Cu") (net 27))
  (arc (start 167.046328 87.452581) (mid 166.942888 87.409735) (end 166.900042 87.306295) (width 0.1) (layer "F.Cu") (net 27))
  (arc (start 167.250042 87.306295) (mid 167.207196 87.409735) (end 167.103756 87.452581) (width 0.1) (layer "F.Cu") (net 27))
  (arc (start 168.245836 86.865683) (mid 168.122094 86.916938) (end 167.99835 86.865683) (width 0.1) (layer "F.Cu") (net 27))
  (arc (start 169.175576 85.073064) (mid 169.051832 85.021808) (end 168.928088 85.073064) (width 0.1) (layer "F.Cu") (net 27))
  (arc (start 168.928088 85.073064) (mid 168.876832 85.196807) (end 168.928088 85.32055) (width 0.1) (layer "F.Cu") (net 27))
  (arc (start 167.396328 87.160008) (mid 167.292888 87.202854) (end 167.250042 87.306294) (width 0.1) (layer "F.Cu") (net 27))
  (arc (start 168.680602 85.568038) (mid 168.556858 85.516782) (end 168.433114 85.568038) (width 0.1) (layer "F.Cu") (net 27))
  (arc (start 168.74081 86.370709) (mid 168.617068 86.421964) (end 168.493324 86.370709) (width 0.1) (layer "F.Cu") (net 27))
  (arc (start 169.235784 85.875735) (mid 169.112042 85.92699) (end 168.988298 85.875735) (width 0.1) (layer "F.Cu") (net 27))
  (arc (start 167.968247 86.835579) (mid 167.844503 86.784323) (end 167.720759 86.835579) (width 0.1) (layer "F.Cu") (net 27))
  (arc (start 169.453168 85.103168) (mid 169.329424 85.154424) (end 169.20568 85.103168) (width 0.1) (layer "F.Cu") (net 27))
  (arc (start 169.235785 85.628247) (mid 169.287041 85.751991) (end 169.235785 85.875735) (width 0.1) (layer "F.Cu") (net 27))
  (arc (start 166.546328 87.013722) (mid 166.503482 87.117162) (end 166.400042 87.160008) (width 0.1) (layer "F.Cu") (net 27))
  (segment (start 158.686328 88.525008) (end 158.686328 87.970008) (width 0.2) (layer "B.Cu") (net 27))
  (segment (start 158.686328 87.255008) (end 158.686328 87.970008) (width 0.2) (layer "B.Cu") (net 27))
  (segment (start 175.136328 82.560008) (end 174.636328 82.060008) (width 0.1) (layer "F.Cu") (net 28))
  (segment (start 155.009179 95.797157) (end 154.399179 95.797157) (width 0.1) (layer "F.Cu") (net 28))
  (segment (start 154.399179 95.797157) (end 153.886328 96.310008) (width 0.1) (layer "F.Cu") (net 28))
  (via blind (at 174.636328 82.060008) (size 0.5) (drill 0.2) (layers "F.Cu" "In2.Cu") (net 28))
  (via (at 153.886328 96.310008) (size 0.5) (drill 0.2) (layers "F.Cu" "B.Cu") (net 28))
  (segment (start 174.230298 82.060008) (end 173.57029 81.4) (width 0.1) (layer "In2.Cu") (net 28))
  (segment (start 162.2 91.496336) (end 160.136328 93.560008) (width 0.1) (layer "In2.Cu") (net 28))
  (segment (start 171.4 81.4) (end 171.3 81.3) (width 0.1) (layer "In2.Cu") (net 28))
  (segment (start 160.136328 93.560008) (end 156.282775 93.560008) (width 0.1) (layer "In2.Cu") (net 28))
  (segment (start 174.636328 82.060008) (end 174.230298 82.060008) (width 0.1) (layer "In2.Cu") (net 28))
  (segment (start 156.282775 93.560008) (end 153.886328 95.956455) (width 0.1) (layer "In2.Cu") (net 28))
  (segment (start 173.57029 81.4) (end 171.4 81.4) (width 0.1) (layer "In2.Cu") (net 28))
  (segment (start 153.886328 95.956455) (end 153.886328 96.310008) (width 0.1) (layer "In2.Cu") (net 28))
  (segment (start 171.3 81.3) (end 165.2 81.3) (width 0.1) (layer "In2.Cu") (net 28))
  (segment (start 162.2 84.3) (end 162.2 91.496336) (width 0.1) (layer "In2.Cu") (net 28))
  (segment (start 165.2 81.3) (end 162.2 84.3) (width 0.1) (layer "In2.Cu") (net 28))
  (segment (start 153.896328 96.320008) (end 153.886328 96.310008) (width 0.2) (layer "B.Cu") (net 28))
  (segment (start 154.401328 96.320008) (end 153.896328 96.320008) (width 0.2) (layer "B.Cu") (net 28))
  (segment (start 155.98 84.55) (end 164 84.55) (width 0.1) (layer "F.Cu") (net 29))
  (segment (start 166.989992 81.560008) (end 171.136328 81.560008) (width 0.1) (layer "F.Cu") (net 29))
  (segment (start 154.61 91.22) (end 154.61 85.92) (width 0.1) (layer "F.Cu") (net 29))
  (segment (start 153.436328 93.210008) (end 153.436328 92.393672) (width 0.1) (layer "F.Cu") (net 29))
  (segment (start 153.436328 92.393672) (end 154.61 91.22) (width 0.1) (layer "F.Cu") (net 29))
  (segment (start 164 84.55) (end 166.989992 81.560008) (width 0.1) (layer "F.Cu") (net 29))
  (segment (start 153.523477 93.297157) (end 153.436328 93.210008) (width 0.1) (layer "F.Cu") (net 29))
  (segment (start 154.61 85.92) (end 155.98 84.55) (width 0.1) (layer "F.Cu") (net 29))
  (segment (start 155.009179 93.297157) (end 153.523477 93.297157) (width 0.1) (layer "F.Cu") (net 29))
  (via (at 153.436328 93.210008) (size 0.5) (drill 0.2) (layers "F.Cu" "B.Cu") (net 29))
  (segment (start 153.436328 93.210008) (end 153.436328 92.555008) (width 0.1) (layer "B.Cu") (net 29))
  (segment (start 155.686328 95.274306) (end 155.886328 95.274306) (width 0.1) (layer "F.Cu") (net 30))
  (segment (start 155.663477 95.297157) (end 155.686328 95.274306) (width 0.1) (layer "F.Cu") (net 30))
  (segment (start 155.009179 95.297157) (end 155.663477 95.297157) (width 0.1) (layer "F.Cu") (net 30))
  (segment (start 174.136328 82.560008) (end 173.636328 82.060008) (width 0.1) (layer "F.Cu") (net 30))
  (via (at 155.886328 95.274306) (size 0.5) (drill 0.2) (layers "F.Cu" "B.Cu") (net 30))
  (via blind (at 173.636328 82.060008) (size 0.5) (drill 0.2) (layers "F.Cu" "In2.Cu") (net 30))
  (segment (start 165.825 81.675) (end 172.226183 81.675) (width 0.1) (layer "In2.Cu") (net 30))
  (segment (start 155.886328 95.274306) (end 156.600626 94.560008) (width 0.1) (layer "In2.Cu") (net 30))
  (segment (start 159.886328 94.560008) (end 162.8 91.646336) (width 0.1) (layer "In2.Cu") (net 30))
  (segment (start 173.636328 82.036328) (end 173.636328 82.060008) (width 0.1) (layer "In2.Cu") (net 30))
  (segment (start 162.8 91.646336) (end 162.8 84.7) (width 0.1) (layer "In2.Cu") (net 30))
  (segment (start 172.226183 81.675) (end 172.261175 81.640008) (width 0.1) (layer "In2.Cu") (net 30))
  (segment (start 172.261175 81.640008) (end 173.240008 81.640008) (width 0.1) (layer "In2.Cu") (net 30))
  (segment (start 173.240008 81.640008) (end 173.636328 82.036328) (width 0.1) (layer "In2.Cu") (net 30))
  (segment (start 162.8 84.7) (end 165.825 81.675) (width 0.1) (layer "In2.Cu") (net 30))
  (segment (start 156.600626 94.560008) (end 159.886328 94.560008) (width 0.1) (layer "In2.Cu") (net 30))
  (segment (start 155.886328 95.274306) (end 155.886328 94.665008) (width 0.2) (layer "B.Cu") (net 30))
  (segment (start 156.386328 95.774306) (end 155.886328 95.274306) (width 0.2) (layer "B.Cu") (net 30))
  (segment (start 163.363477 95.297157) (end 163.386328 95.274306) (width 0.15) (layer "F.Cu") (net 31))
  (segment (start 161.863477 95.297157) (end 163.363477 95.297157) (width 0.15) (layer "F.Cu") (net 31))
  (segment (start 169.360008 83.560008) (end 171.136328 83.560008) (width 0.1) (layer "F.Cu") (net 31))
  (segment (start 169.35 83.55) (end 169.360008 83.560008) (width 0.1) (layer "F.Cu") (net 31))
  (via (at 163.386328 95.274306) (size 0.5) (drill 0.2) (layers "F.Cu" "B.Cu") (net 31))
  (via blind (at 169.35 83.55) (size 0.5) (drill 0.2) (layers "F.Cu" "In2.Cu") (net 31))
  (segment (start 165.2 93.996336) (end 165.2 86.3) (width 0.1) (layer "In2.Cu") (net 31))
  (segment (start 167.711374 83.975641) (end 167.711376 83.97564) (width 0.1) (layer "In2.Cu") (net 31))
  (segment (start 167.95 83.55) (end 169.35 83.55) (width 0.1) (layer "In2.Cu") (net 31))
  (segment (start 167.852796 83.97564) (end 167.852797 83.975639) (width 0.1) (layer "In2.Cu") (net 31))
  (segment (start 165.2 86.3) (end 167.547158 83.952845) (width 0.1) (layer "In2.Cu") (net 31))
  (segment (start 167.852796 83.834218) (end 167.83 83.811422) (width 0.1) (layer "In2.Cu") (net 31))
  (segment (start 163.386328 95.274306) (end 163.92203 95.274306) (width 0.1) (layer "In2.Cu") (net 31))
  (segment (start 163.92203 95.274306) (end 165.2 93.996336) (width 0.1) (layer "In2.Cu") (net 31))
  (segment (start 167.83 83.67) (end 167.95 83.55) (width 0.1) (layer "In2.Cu") (net 31))
  (segment (start 167.688579 83.952846) (end 167.711374 83.975641) (width 0.1) (layer "In2.Cu") (net 31))
  (arc (start 167.83 83.811422) (mid 167.800711 83.740711) (end 167.83 83.67) (width 0.1) (layer "In2.Cu") (net 31))
  (arc (start 167.547158 83.952845) (mid 167.617869 83.923556) (end 167.688579 83.952846) (width 0.1) (layer "In2.Cu") (net 31))
  (arc (start 167.852797 83.975639) (mid 167.882086 83.904928) (end 167.852796 83.834218) (width 0.1) (layer "In2.Cu") (net 31))
  (arc (start 167.711376 83.97564) (mid 167.782085 84.00493) (end 167.852796 83.97564) (width 0.1) (layer "In2.Cu") (net 31))
  (segment (start 162.863477 94.797157) (end 162.886328 94.774306) (width 0.15) (layer "F.Cu") (net 32))
  (segment (start 161.863477 94.797157) (end 162.863477 94.797157) (width 0.15) (layer "F.Cu") (net 32))
  (segment (start 175.136328 83.560008) (end 174.636328 83.060008) (width 0.1) (layer "F.Cu") (net 32))
  (via (at 162.886328 94.774306) (size 0.5) (drill 0.2) (layers "F.Cu" "B.Cu") (net 32))
  (via blind (at 174.636328 83.060008) (size 0.5) (drill 0.2) (layers "F.Cu" "In2.Cu") (net 32))
  (segment (start 164.6 93.726636) (end 164.6 85.9) (width 0.1) (layer "In2.Cu") (net 32))
  (segment (start 164.6 85.9) (end 167.439992 83.060008) (width 0.1) (layer "In2.Cu") (net 32))
  (segment (start 163.55233 94.774306) (end 164.6 93.726636) (width 0.1) (layer "In2.Cu") (net 32))
  (segment (start 171.705 83.575) (end 172.219992 83.060008) (width 0.1) (layer "In2.Cu") (net 32))
  (segment (start 162.886328 94.774306) (end 163.55233 94.774306) (width 0.1) (layer "In2.Cu") (net 32))
  (segment (start 172.219992 83.060008) (end 174.636328 83.060008) (width 0.1) (layer "In2.Cu") (net 32))
  (segment (start 170.075 83.575) (end 171.705 83.575) (width 0.1) (layer "In2.Cu") (net 32))
  (segment (start 167.439992 83.060008) (end 169.560008 83.060008) (width 0.1) (layer "In2.Cu") (net 32))
  (segment (start 169.560008 83.060008) (end 170.075 83.575) (width 0.1) (layer "In2.Cu") (net 32))
  (segment (start 163.363477 94.297157) (end 163.386328 94.274306) (width 0.15) (layer "F.Cu") (net 33))
  (segment (start 161.863477 94.297157) (end 163.363477 94.297157) (width 0.15) (layer "F.Cu") (net 33))
  (segment (start 176.136328 83.560008) (end 175.636328 83.060008) (width 0.127) (layer "F.Cu") (net 33))
  (via (at 163.386328 94.274306) (size 0.5) (drill 0.2) (layers "F.Cu" "B.Cu") (net 33))
  (via blind (at 175.636328 83.060008) (size 0.5) (drill 0.2) (layers "F.Cu" "In2.Cu") (net 33))
  (segment (start 166.667259 83.014038) (end 166.664999 83.011778) (width 0.1) (layer "In2.Cu") (net 33))
  (segment (start 166.859992 82.640008) (end 169.660008 82.640008) (width 0.1) (layer "In2.Cu") (net 33))
  (segment (start 164 85.5) (end 166.311447 83.188556) (width 0.1) (layer "In2.Cu") (net 33))
  (segment (start 171.756 82.564) (end 175.14032 82.564) (width 0.1) (layer "In2.Cu") (net 33))
  (segment (start 166.667259 83.190814) (end 166.667258 83.190815) (width 0.1) (layer "In2.Cu") (net 33))
  (segment (start 163.386328 94.274306) (end 164 93.660634) (width 0.1) (layer "In2.Cu") (net 33))
  (segment (start 166.664999 83.011778) (end 166.665 83.011778) (width 0.1) (layer "In2.Cu") (net 33))
  (segment (start 175.14032 82.564) (end 175.636328 83.060008) (width 0.1) (layer "In2.Cu") (net 33))
  (segment (start 166.665 82.835) (end 166.859992 82.640008) (width 0.1) (layer "In2.Cu") (net 33))
  (segment (start 170.27 83.25) (end 171.07 83.25) (width 0.1) (layer "In2.Cu") (net 33))
  (segment (start 171.07 83.25) (end 171.756 82.564) (width 0.1) (layer "In2.Cu") (net 33))
  (segment (start 166.488224 83.188555) (end 166.490483 83.190814) (width 0.1) (layer "In2.Cu") (net 33))
  (segment (start 164 93.660634) (end 164 85.5) (width 0.1) (layer "In2.Cu") (net 33))
  (segment (start 169.660008 82.640008) (end 170.27 83.25) (width 0.1) (layer "In2.Cu") (net 33))
  (arc (start 166.311447 83.188556) (mid 166.399835 83.151944) (end 166.488224 83.188555) (width 0.1) (layer "In2.Cu") (net 33))
  (arc (start 166.665 83.011778) (mid 166.628387 82.92339) (end 166.665 82.835) (width 0.1) (layer "In2.Cu") (net 33))
  (arc (start 166.490483 83.190814) (mid 166.578871 83.227426) (end 166.667259 83.190814) (width 0.1) (layer "In2.Cu") (net 33))
  (arc (start 166.667258 83.190815) (mid 166.70387 83.102427) (end 166.667259 83.014038) (width 0.1) (layer "In2.Cu") (net 33))
  (segment (start 163.163477 93.297157) (end 163.186328 93.274306) (width 0.15) (layer "F.Cu") (net 34))
  (segment (start 173.136328 82.560008) (end 172.636328 82.060008) (width 0.1) (layer "F.Cu") (net 34))
  (segment (start 161.863477 93.297157) (end 163.163477 93.297157) (width 0.15) (layer "F.Cu") (net 34))
  (via (at 163.186328 93.274306) (size 0.5) (drill 0.2) (layers "F.Cu" "B.Cu") (net 34))
  (via blind (at 172.636328 82.060008) (size 0.5) (drill 0.2) (layers "F.Cu" "In2.Cu") (net 34))
  (segment (start 163.4 93.060634) (end 163.4 85.1) (width 0.1) (layer "In2.Cu") (net 34))
  (segment (start 163.4 85.1) (end 165.392539 83.107463) (width 0.1) (layer "In2.Cu") (net 34))
  (segment (start 165.650261 83.117697) (end 165.650261 83.117698) (width 0.1) (layer "In2.Cu") (net 34))
  (segment (start 165.629789 82.602252) (end 165.629789 82.602251) (width 0.1) (layer "In2.Cu") (net 34))
  (segment (start 166.25 82.25) (end 169.925 82.25) (width 0.1) (layer "In2.Cu") (net 34))
  (segment (start 169.925 82.25) (end 170.114992 82.060008) (width 0.1) (layer "In2.Cu") (net 34))
  (segment (start 166.135 82.365) (end 166.25 82.25) (width 0.1) (layer "In2.Cu") (net 34))
  (segment (start 165.877277 82.354765) (end 165.887512 82.365) (width 0.1) (layer "In2.Cu") (net 34))
  (segment (start 163.186328 93.274306) (end 163.4 93.060634) (width 0.1) (layer "In2.Cu") (net 34))
  (segment (start 165.640027 83.107463) (end 165.650261 83.117697) (width 0.1) (layer "In2.Cu") (net 34))
  (segment (start 165.897747 83.117698) (end 165.897748 83.117698) (width 0.1) (layer "In2.Cu") (net 34))
  (segment (start 170.114992 82.060008) (end 172.636328 82.060008) (width 0.1) (layer "In2.Cu") (net 34))
  (segment (start 165.897748 82.87021) (end 165.629789 82.602252) (width 0.1) (layer "In2.Cu") (net 34))
  (arc (start 165.897748 83.117698) (mid 165.949004 82.993954) (end 165.897748 82.87021) (width 0.1) (layer "In2.Cu") (net 34))
  (arc (start 165.650261 83.117698) (mid 165.774005 83.168953) (end 165.897747 83.117698) (width 0.1) (layer "In2.Cu") (net 34))
  (arc (start 165.392539 83.107463) (mid 165.516283 83.056207) (end 165.640027 83.107463) (width 0.1) (layer "In2.Cu") (net 34))
  (arc (start 165.629789 82.602251) (mid 165.578533 82.478508) (end 165.629789 82.354765) (width 0.1) (layer "In2.Cu") (net 34))
  (arc (start 165.887512 82.365) (mid 166.011256 82.416256) (end 166.135 82.365) (width 0.1) (layer "In2.Cu") (net 34))
  (arc (start 165.629789 82.354765) (mid 165.753533 82.303509) (end 165.877277 82.354765) (width 0.1) (layer "In2.Cu") (net 34))
  (segment (start 162.965 88.68396) (end 162.965 89.53604) (width 0.1) (layer "F.Cu") (net 35))
  (segment (start 170.594992 86.560008) (end 168.295 88.86) (width 0.1) (layer "F.Cu") (net 35))
  (segment (start 163.665 88.68396) (end 163.665 89.53604) (width 0.1) (layer "F.Cu") (net 35))
  (segment (start 162.44 88.86) (end 161.64 88.86) (width 0.1) (layer "F.Cu") (net 35))
  (segment (start 162.615 89.53604) (end 162.615 89.035) (width 0.1) (layer "F.Cu") (net 35))
  (segment (start 161.186328 89.313672) (end 161.186328 92.620008) (width 0.1) (layer "F.Cu") (net 35))
  (segment (start 164.365 89.035) (end 164.365 89.53604) (width 0.1) (layer "F.Cu") (net 35))
  (segment (start 171.136328 86.560008) (end 170.594992 86.560008) (width 0.1) (layer "F.Cu") (net 35))
  (segment (start 164.015 89.53604) (end 164.015 88.68396) (width 0.1) (layer "F.Cu") (net 35))
  (segment (start 163.315 89.53604) (end 163.315 88.68396) (width 0.1) (layer "F.Cu") (net 35))
  (segment (start 168.295 88.86) (end 164.54 88.86) (width 0.1) (layer "F.Cu") (net 35))
  (segment (start 161.64 88.86) (end 161.186328 89.313672) (width 0.1) (layer "F.Cu") (net 35))
  (arc (start 162.79 89.71104) (mid 162.666256 89.659784) (end 162.615 89.53604) (width 0.1) (layer "F.Cu") (net 35))
  (arc (start 162.615 89.035) (mid 162.563744 88.911256) (end 162.44 88.86) (width 0.1) (layer "F.Cu") (net 35))
  (arc (start 164.365 89.53604) (mid 164.313744 89.659784) (end 164.19 89.71104) (width 0.1) (layer "F.Cu") (net 35))
  (arc (start 163.315 88.68396) (mid 163.263744 88.560216) (end 163.14 88.50896) (width 0.1) (layer "F.Cu") (net 35))
  (arc (start 164.19 89.71104) (mid 164.066256 89.659784) (end 164.015 89.53604) (width 0.1) (layer "F.Cu") (net 35))
  (arc (start 164.015 88.68396) (mid 163.963744 88.560216) (end 163.84 88.50896) (width 0.1) (layer "F.Cu") (net 35))
  (arc (start 163.49 89.71104) (mid 163.366256 89.659784) (end 163.315 89.53604) (width 0.1) (layer "F.Cu") (net 35))
  (arc (start 163.84 88.50896) (mid 163.716256 88.560216) (end 163.665 88.68396) (width 0.1) (layer "F.Cu") (net 35))
  (arc (start 163.14 88.50896) (mid 163.016256 88.560216) (end 162.965 88.68396) (width 0.1) (layer "F.Cu") (net 35))
  (arc (start 164.54 88.86) (mid 164.416256 88.911256) (end 164.365 89.035) (width 0.1) (layer "F.Cu") (net 35))
  (arc (start 162.965 89.53604) (mid 162.913744 89.659784) (end 162.79 89.71104) (width 0.1) (layer "F.Cu") (net 35))
  (arc (start 163.665 89.53604) (mid 163.613744 89.659784) (end 163.49 89.71104) (width 0.1) (layer "F.Cu") (net 35))
  (segment (start 162.763477 95.797157) (end 162.786328 95.774306) (width 0.15) (layer "F.Cu") (net 36))
  (segment (start 161.863477 95.797157) (end 162.763477 95.797157) (width 0.15) (layer "F.Cu") (net 36))
  (segment (start 173.136328 84.560008) (end 172.65 85.046336) (width 0.1) (layer "F.Cu") (net 36))
  (segment (start 172.65 85.046336) (end 172.65 85.075) (width 0.1) (layer "F.Cu") (net 36))
  (via (at 162.786328 95.774306) (size 0.5) (drill 0.2) (layers "F.Cu" "B.Cu") (net 36))
  (via blind (at 172.65 85.075) (size 0.5) (drill 0.2) (layers "F.Cu" "In2.Cu") (net 36))
  (segment (start 165.78 94.416336) (end 164.42203 95.774306) (width 0.1) (layer "In2.Cu") (net 36))
  (segment (start 172.65 85.075) (end 171.635008 84.060008) (width 0.1) (layer "In2.Cu") (net 36))
  (segment (start 168.359999 84.4582) (end 168.36206 84.460261) (width 0.1) (layer "In2.Cu") (net 36))
  (segment (start 165.78 86.72) (end 165.78 94.416336) (width 0.1) (layer "In2.Cu") (net 36))
  (segment (start 167.723604 84.776399) (end 167.723603 84.776398) (width 0.1) (layer "In2.Cu") (net 36))
  (segment (start 171.635008 84.060008) (end 168.439992 84.060008) (width 0.1) (layer "In2.Cu") (net 36))
  (segment (start 168.36 84.4582) (end 168.359999 84.4582) (width 0.1) (layer "In2.Cu") (net 36))
  (segment (start 168.043862 84.778459) (end 168.041802 84.776399) (width 0.1) (layer "In2.Cu") (net 36))
  (segment (start 164.42203 95.774306) (end 162.786328 95.774306) (width 0.1) (layer "In2.Cu") (net 36))
  (segment (start 167.723603 84.776398) (end 165.78 86.72) (width 0.1) (layer "In2.Cu") (net 36))
  (segment (start 168.439992 84.060008) (end 168.36 84.14) (width 0.1) (layer "In2.Cu") (net 36))
  (arc (start 168.36206 84.460261) (mid 168.427961 84.61936) (end 168.36206 84.778459) (width 0.1) (layer "In2.Cu") (net 36))
  (arc (start 168.36206 84.778459) (mid 168.202961 84.84436) (end 168.043862 84.778459) (width 0.1) (layer "In2.Cu") (net 36))
  (arc (start 168.36 84.14) (mid 168.294098 84.299101) (end 168.36 84.4582) (width 0.1) (layer "In2.Cu") (net 36))
  (arc (start 168.041802 84.776399) (mid 167.882703 84.710498) (end 167.723604 84.776399) (width 0.1) (layer "In2.Cu") (net 36))
  (segment (start 160.686328 88.160008) (end 160.186328 88.660008) (width 0.1) (layer "F.Cu") (net 37))
  (segment (start 166.871326 88.01144) (end 166.871326 88.382144) (width 0.1) (layer "F.Cu") (net 37))
  (segment (start 168.485919 87.622927) (end 168.452588 87.589596) (width 0.1) (layer "F.Cu") (net 37))
  (segment (start 168.238431 88.117902) (end 168.196326 88.160008) (width 0.1) (layer "F.Cu") (net 37))
  (segment (start 165.821326 88.382144) (end 165.821326 88.01144) (width 0.1) (layer "F.Cu") (net 37))
  (segment (start 168.929886 87.112299) (end 169.192015 87.374429) (width 0.1) (layer "F.Cu") (net 37))
  (segment (start 168.205101 87.837082) (end 168.2051 87.837083) (width 0.1) (layer "F.Cu") (net 37))
  (segment (start 165.672758 87.862872) (end 165.619894 87.862872) (width 0.1) (layer "F.Cu") (net 37))
  (segment (start 166.372758 87.862872) (end 166.319894 87.862872) (width 0.1) (layer "F.Cu") (net 37))
  (segment (start 168.238429 88.1179) (end 168.23843 88.1179) (width 0.1) (layer "F.Cu") (net 37))
  (segment (start 169.192015 87.584535) (end 169.192014 87.584537) (width 0.1) (layer "F.Cu") (net 37))
  (segment (start 166.171326 88.01144) (end 166.171326 88.382144) (width 0.1) (layer "F.Cu") (net 37))
  (segment (start 165.471326 88.01144) (end 165.471326 88.382144) (width 0.1) (layer "F.Cu") (net 37))
  (segment (start 169.70568 86.403168) (end 169.70568 86.403167) (width 0.1) (layer "F.Cu") (net 37))
  (segment (start 168.485919 87.622928) (end 168.485919 87.622927) (width 0.1) (layer "F.Cu") (net 37))
  (segment (start 167.221326 88.382144) (end 167.221326 88.335008) (width 0.1) (layer "F.Cu") (net 37))
  (segment (start 169.424862 86.369837) (end 169.424862 86.369836) (width 0.1) (layer "F.Cu") (net 37))
  (segment (start 167.221326 88.335008) (end 167.221326 88.01144) (width 0.1) (layer "F.Cu") (net 37))
  (segment (start 167.571326 88.335008) (end 167.571326 88.382144) (width 0.1) (layer "F.Cu") (net 37))
  (segment (start 169.70568 86.403167) (end 169.672349 86.369836) (width 0.1) (layer "F.Cu") (net 37))
  (segment (start 160.686328 88.160008) (end 164.622758 88.160008) (width 0.1) (layer "F.Cu") (net 37))
  (segment (start 169.192014 87.584537) (end 169.154635 87.621917) (width 0.1) (layer "F.Cu") (net 37))
  (segment (start 168.196326 88.160008) (end 167.746326 88.160008) (width 0.1) (layer "F.Cu") (net 37))
  (segment (start 169.686989 87.089561) (end 169.64961 87.126941) (width 0.1) (layer "F.Cu") (net 37))
  (segment (start 168.929887 87.112298) (end 168.929886 87.112299) (width 0.1) (layer "F.Cu") (net 37))
  (segment (start 172.136328 86.560008) (end 171.586329 86.010009) (width 0.1) (layer "F.Cu") (net 37))
  (segment (start 164.972758 87.862872) (end 164.919894 87.862872) (width 0.1) (layer "F.Cu") (net 37))
  (segment (start 168.73442 87.621917) (end 168.734422 87.621918) (width 0.1) (layer "F.Cu") (net 37))
  (segment (start 168.929888 86.864812) (end 168.929887 86.864812) (width 0.1) (layer "F.Cu") (net 37))
  (segment (start 168.23843 88.1179) (end 168.238431 88.117902) (width 0.1) (layer "F.Cu") (net 37))
  (segment (start 171.586329 86.010009) (end 170.346327 86.010009) (width 0.1) (layer "F.Cu") (net 37))
  (segment (start 168.2051 87.837083) (end 168.23843 87.870413) (width 0.1) (layer "F.Cu") (net 37))
  (segment (start 166.521326 88.382144) (end 166.521326 88.01144) (width 0.1) (layer "F.Cu") (net 37))
  (segment (start 170.346327 86.010009) (end 169.953168 86.403168) (width 0.1) (layer "F.Cu") (net 37))
  (segment (start 168.944529 87.621917) (end 168.944527 87.621916) (width 0.1) (layer "F.Cu") (net 37))
  (segment (start 168.734422 87.621918) (end 168.733407 87.622928) (width 0.1) (layer "F.Cu") (net 37))
  (segment (start 165.121326 88.382144) (end 165.121326 88.01144) (width 0.1) (layer "F.Cu") (net 37))
  (segment (start 169.424862 86.617322) (end 169.424861 86.617323) (width 0.1) (layer "F.Cu") (net 37))
  (segment (start 160.186328 88.660008) (end 160.186328 92.620008) (width 0.1) (layer "F.Cu") (net 37))
  (segment (start 169.424861 86.617323) (end 169.68699 86.879453) (width 0.1) (layer "F.Cu") (net 37))
  (segment (start 169.439502 87.12694) (end 169.177375 86.864813) (width 0.1) (layer "F.Cu") (net 37))
  (segment (start 167.072758 87.862872) (end 167.019894 87.862872) (width 0.1) (layer "F.Cu") (net 37))
  (segment (start 169.68699 87.089559) (end 169.686989 87.089561) (width 0.1) (layer "F.Cu") (net 37))
  (segment (start 169.439504 87.126941) (end 169.439502 87.12694) (width 0.1) (layer "F.Cu") (net 37))
  (segment (start 168.205101 87.589597) (end 168.205101 87.589596) (width 0.1) (layer "F.Cu") (net 37))
  (via (at 160.736328 88.160008) (size 0.5) (drill 0.2) (layers "F.Cu" "B.Cu") (net 37))
  (arc (start 167.746326 88.160008) (mid 167.622582 88.211264) (end 167.571326 88.335008) (width 0.1) (layer "F.Cu") (net 37))
  (arc (start 164.919894 87.862872) (mid 164.814841 87.906387) (end 164.771326 88.01144) (width 0.1) (layer "F.Cu") (net 37))
  (arc (start 164.771326 88.01144) (mid 164.727811 88.116493) (end 164.622758 88.160008) (width 0.1) (layer "F.Cu") (net 37))
  (arc (start 166.871326 88.382144) (mid 166.82007 88.505888) (end 166.696326 88.557144) (width 0.1) (layer "F.Cu") (net 37))
  (arc (start 165.296326 88.557144) (mid 165.172582 88.505888) (end 165.121326 88.382144) (width 0.1) (layer "F.Cu") (net 37))
  (arc (start 166.696326 88.557144) (mid 166.572582 88.505888) (end 166.521326 88.382144) (width 0.1) (layer "F.Cu") (net 37))
  (arc (start 169.64961 87.126941) (mid 169.544556 87.170454) (end 169.439504 87.126941) (width 0.1) (layer "F.Cu") (net 37))
  (arc (start 168.23843 87.870413) (mid 168.289686 87.994157) (end 168.238429 88.1179) (width 0.1) (layer "F.Cu") (net 37))
  (arc (start 168.929887 86.864812) (mid 168.878631 86.988555) (end 168.929887 87.112298) (width 0.1) (layer "F.Cu") (net 37))
  (arc (start 167.571326 88.382144) (mid 167.52007 88.505888) (end 167.396326 88.557144) (width 0.1) (layer "F.Cu") (net 37))
  (arc (start 169.154635 87.621917) (mid 169.049581 87.66543) (end 168.944529 87.621917) (width 0.1) (layer "F.Cu") (net 37))
  (arc (start 167.396326 88.557144) (mid 167.272582 88.505888) (end 167.221326 88.382144) (width 0.1) (layer "F.Cu") (net 37))
  (arc (start 167.221326 88.01144) (mid 167.177811 87.906387) (end 167.072758 87.862872) (width 0.1) (layer "F.Cu") (net 37))
  (arc (start 166.171326 88.382144) (mid 166.12007 88.505888) (end 165.996326 88.557144) (width 0.1) (layer "F.Cu") (net 37))
  (arc (start 165.619894 87.862872) (mid 165.514841 87.906387) (end 165.471326 88.01144) (width 0.1) (layer "F.Cu") (net 37))
  (arc (start 168.733407 87.622928) (mid 168.609663 87.674184) (end 168.485919 87.622928) (width 0.1) (layer "F.Cu") (net 37))
  (arc (start 166.319894 87.862872) (mid 166.214841 87.906387) (end 166.171326 88.01144) (width 0.1) (layer "F.Cu") (net 37))
  (arc (start 169.192015 87.374429) (mid 169.235528 87.479483) (end 169.192015 87.584535) (width 0.1) (layer "F.Cu") (net 37))
  (arc (start 165.121326 88.01144) (mid 165.077811 87.906387) (end 164.972758 87.862872) (width 0.1) (layer "F.Cu") (net 37))
  (arc (start 165.821326 88.01144) (mid 165.777811 87.906387) (end 165.672758 87.862872) (width 0.1) (layer "F.Cu") (net 37))
  (arc (start 168.944527 87.621916) (mid 168.839473 87.578402) (end 168.73442 87.621917) (width 0.1) (layer "F.Cu") (net 37))
  (arc (start 169.424862 86.369836) (mid 169.373606 86.493579) (end 169.424862 86.617322) (width 0.1) (layer "F.Cu") (net 37))
  (arc (start 169.177375 86.864813) (mid 169.053632 86.813556) (end 168.929888 86.864812) (width 0.1) (layer "F.Cu") (net 37))
  (arc (start 167.019894 87.862872) (mid 166.914841 87.906387) (end 166.871326 88.01144) (width 0.1) (layer "F.Cu") (net 37))
  (arc (start 165.471326 88.382144) (mid 165.42007 88.505888) (end 165.296326 88.557144) (width 0.1) (layer "F.Cu") (net 37))
  (arc (start 169.953168 86.403168) (mid 169.829424 86.454424) (end 169.70568 86.403168) (width 0.1) (layer "F.Cu") (net 37))
  (arc (start 168.452588 87.589596) (mid 168.328844 87.53834) (end 168.205101 87.589597) (width 0.1) (layer "F.Cu") (net 37))
  (arc (start 168.205101 87.589596) (mid 168.153845 87.713339) (end 168.205101 87.837082) (width 0.1) (layer "F.Cu") (net 37))
  (arc (start 166.521326 88.01144) (mid 166.477811 87.906387) (end 166.372758 87.862872) (width 0.1) (layer "F.Cu") (net 37))
  (arc (start 169.672349 86.369836) (mid 169.548605 86.31858) (end 169.424862 86.369837) (width 0.1) (layer "F.Cu") (net 37))
  (arc (start 165.996326 88.557144) (mid 165.872582 88.505888) (end 165.821326 88.382144) (width 0.1) (layer "F.Cu") (net 37))
  (arc (start 169.68699 86.879453) (mid 169.730503 86.984507) (end 169.68699 87.089559) (width 0.1) (layer "F.Cu") (net 37))
  (segment (start 160.736328 88.160008) (end 160.736328 87.710008) (width 0.2) (layer "B.Cu") (net 37))
  (segment (start 160.736328 88.855008) (end 160.736328 88.160008) (width 0.2) (layer "B.Cu") (net 37))
  (segment (start 158.596328 85.690008) (end 157.186328 87.100008) (width 0.1) (layer "F.Cu") (net 38))
  (segment (start 168.263958 84.98893) (end 168.257558 84.995331) (width 0.1) (layer "F.Cu") (net 38))
  (segment (start 161.720288 86.1) (end 161.310296 85.690008) (width 0.1) (layer "F.Cu") (net 38))
  (segment (start 167.955357 84.121044) (end 167.955358 84.121043) (width 0.1) (layer "F.Cu") (net 38))
  (segment (start 168.267156 84.15) (end 168.267157 84.15) (width 0.1) (layer "F.Cu") (net 38))
  (segment (start 167.981114 84.995331) (end 167.981116 84.99533) (width 0.1) (layer "F.Cu") (net 38))
  (segment (start 172.136328 83.560008) (end 171.696336 84) (width 0.1) (layer "F.Cu") (net 38))
  (segment (start 167.955358 84.403885) (end 167.984314 84.432841) (width 0.1) (layer "F.Cu") (net 38))
  (segment (start 171.696336 84) (end 168.7 84) (width 0.1) (layer "F.Cu") (net 38))
  (segment (start 157.186328 87.100008) (end 157.186328 92.620008) (width 0.1) (layer "F.Cu") (net 38))
  (segment (start 167.418627 85.28137) (end 166.6 86.1) (width 0.1) (layer "F.Cu") (net 38))
  (segment (start 161.310296 85.690008) (end 158.596328 85.690008) (width 0.1) (layer "F.Cu") (net 38))
  (segment (start 167.418626 85.281371) (end 167.418627 85.28137) (width 0.1) (layer "F.Cu") (net 38))
  (segment (start 166.6 86.1) (end 161.720288 86.1) (width 0.1) (layer "F.Cu") (net 38))
  (segment (start 167.389672 84.68673) (end 167.389671 84.68673) (width 0.1) (layer "F.Cu") (net 38))
  (segment (start 168.267157 84.15) (end 168.2382 84.121043) (width 0.1) (layer "F.Cu") (net 38))
  (segment (start 168.7 84) (end 168.55 84.15) (width 0.1) (layer "F.Cu") (net 38))
  (segment (start 167.389671 84.969572) (end 167.418627 84.998528) (width 0.1) (layer "F.Cu") (net 38))
  (segment (start 167.981116 84.99533) (end 167.672514 84.68673) (width 0.1) (layer "F.Cu") (net 38))
  (segment (start 167.984314 84.432841) (end 168.263958 84.712486) (width 0.1) (layer "F.Cu") (net 38))
  (via (at 157.186328 90.460008) (size 0.5) (drill 0.2) (layers "F.Cu" "B.Cu") (net 38))
  (arc (start 168.257558 84.995331) (mid 168.119337 85.052583) (end 167.981114 84.995331) (width 0.1) (layer "F.Cu") (net 38))
  (arc (start 168.55 84.15) (mid 168.408578 84.208579) (end 168.267156 84.15) (width 0.1) (layer "F.Cu") (net 38))
  (arc (start 167.672514 84.68673) (mid 167.531093 84.628152) (end 167.389672 84.68673) (width 0.1) (layer "F.Cu") (net 38))
  (arc (start 167.955358 84.121043) (mid 167.89678 84.262464) (end 167.955358 84.403885) (width 0.1) (layer "F.Cu") (net 38))
  (arc (start 167.389671 84.68673) (mid 167.331093 84.828151) (end 167.389671 84.969572) (width 0.1) (layer "F.Cu") (net 38))
  (arc (start 168.263958 84.712486) (mid 168.32121 84.850709) (end 168.263958 84.98893) (width 0.1) (layer "F.Cu") (net 38))
  (arc (start 168.2382 84.121043) (mid 168.096778 84.062465) (end 167.955357 84.121044) (width 0.1) (layer "F.Cu") (net 38))
  (arc (start 167.418627 84.998528) (mid 167.477205 85.13995) (end 167.418626 85.281371) (width 0.1) (layer "F.Cu") (net 38))
  (segment (start 156.421328 90.460008) (end 157.186328 90.460008) (width 0.2) (layer "B.Cu") (net 38))
  (segment (start 157.701328 90.460008) (end 157.186328 90.460008) (width 0.2) (layer "B.Cu") (net 38))
  (segment (start 155 91.27) (end 155 86.712022) (width 0.1) (layer "F.Cu") (net 39))
  (segment (start 155.686328 91.956328) (end 155 91.27) (width 0.1) (layer "F.Cu") (net 39))
  (segment (start 165.12 84.88) (end 167.889993 82.110007) (width 0.1) (layer "F.Cu") (net 39))
  (segment (start 167.889993 82.110007) (end 171.686327 82.110007) (width 0.1) (layer "F.Cu") (net 39))
  (segment (start 155 86.712022) (end 156.832022 84.88) (width 0.1) (layer "F.Cu") (net 39))
  (segment (start 155.686328 92.620008) (end 155.686328 91.956328) (width 0.1) (layer "F.Cu") (net 39))
  (segment (start 171.686327 82.110007) (end 172.136328 82.560008) (width 0.1) (layer "F.Cu") (net 39))
  (segment (start 156.832022 84.88) (end 165.12 84.88) (width 0.1) (layer "F.Cu") (net 39))
  (segment (start 156.186328 86.710008) (end 156.186328 86.720008) (width 0.1) (layer "F.Cu") (net 40))
  (segment (start 173.636328 83.060008) (end 168.149992 83.060008) (width 0.1) (layer "F.Cu") (net 40))
  (segment (start 168.149992 83.060008) (end 165.93 85.28) (width 0.1) (layer "F.Cu") (net 40))
  (segment (start 156.186328 92.620008) (end 156.186328 86.720008) (width 0.1) (layer "F.Cu") (net 40))
  (segment (start 165.93 85.28) (end 157.616336 85.28) (width 0.1) (layer "F.Cu") (net 40))
  (segment (start 157.616336 85.28) (end 156.186328 86.710008) (width 0.1) (layer "F.Cu") (net 40))
  (segment (start 174.136328 83.560008) (end 173.636328 83.060008) (width 0.1) (layer "F.Cu") (net 40))
  (via (at 156.186328 86.720008) (size 0.5) (drill 0.2) (layers "F.Cu" "B.Cu") (net 40))
  (segment (start 156.186328 86.710008) (end 156.186328 87.325008) (width 0.2) (layer "B.Cu") (net 40))
  (segment (start 156.186328 86.095008) (end 156.186328 86.710008) (width 0.2) (layer "B.Cu") (net 40))
  (segment (start 160.411328 87.660008) (end 160.295668 87.775668) (width 0.1) (layer "F.Cu") (net 41))
  (segment (start 164.719992 87.500008) (end 164.719984 87.5) (width 0.1) (layer "F.Cu") (net 41))
  (segment (start 164.010008 87.360008) (end 163.960008 87.360008) (width 0.1) (layer "F.Cu") (net 41))
  (segment (start 163.810008 87.510008) (end 163.810008 87.810008) (width 0.1) (layer "F.Cu") (net 41))
  (segment (start 164.719984 87.5) (end 164.66 87.5) (width 0.1) (layer "F.Cu") (net 41))
  (segment (start 160.860008 87.660008) (end 160.411328 87.660008) (width 0.1) (layer "F.Cu") (net 41))
  (segment (start 163.310008 87.360008) (end 163.260008 87.360008) (width 0.1) (layer "F.Cu") (net 41))
  (segment (start 164.51 87.65) (end 164.51 87.81) (width 0.1) (layer "F.Cu") (net 41))
  (segment (start 171.136328 85.560008) (end 169.886328 85.560008) (width 0.1) (layer "F.Cu") (net 41))
  (segment (start 169.886328 85.560008) (end 168.247435 87.198904) (width 0.1) (layer "F.Cu") (net 41))
  (segment (start 162.410008 87.510008) (end 162.410008 87.810008) (width 0.1) (layer "F.Cu") (net 41))
  (segment (start 161.210008 87.360008) (end 161.160008 87.360008) (width 0.1) (layer "F.Cu") (net 41))
  (segment (start 163.660008 87.960008) (end 163.610008 87.960008) (width 0.1) (layer "F.Cu") (net 41))
  (segment (start 166.525 87.5) (end 166.524992 87.500008) (width 0.1) (layer "F.Cu") (net 41))
  (segment (start 166.683955 87.658955) (end 166.525 87.5) (width 0.1) (layer "F.Cu") (net 41))
  (segment (start 161.560008 87.960008) (end 161.510008 87.960008) (width 0.1) (layer "F.Cu") (net 41))
  (segment (start 167.823168 87.623168) (end 167.787381 87.658955) (width 0.1) (layer "F.Cu") (net 41))
  (segment (start 159.800691 88.270641) (end 159.800692 88.270641) (width 0.1) (layer "F.Cu") (net 41))
  (segment (start 164.51 87.81) (end 164.510008 87.810008) (width 0.1) (layer "F.Cu") (net 41))
  (segment (start 163.110008 87.510008) (end 163.110008 87.810008) (width 0.1) (layer "F.Cu") (net 41))
  (segment (start 162.760008 87.810008) (end 162.760008 87.510008) (width 0.1) (layer "F.Cu") (net 41))
  (segment (start 162.960008 87.960008) (end 162.910008 87.960008) (width 0.1) (layer "F.Cu") (net 41))
  (segment (start 167.787381 87.658955) (end 166.683955 87.658955) (width 0.1) (layer "F.Cu") (net 41))
  (segment (start 168.035302 87.198903) (end 168.035302 87.198904) (width 0.1) (layer "F.Cu") (net 41))
  (segment (start 159.800692 88.270641) (end 159.686328 88.385008) (width 0.1) (layer "F.Cu") (net 41))
  (segment (start 161.360008 87.810008) (end 161.360008 87.510008) (width 0.1) (layer "F.Cu") (net 41))
  (segment (start 162.060008 87.810008) (end 162.060008 87.510008) (width 0.1) (layer "F.Cu") (net 41))
  (segment (start 163.460008 87.810008) (end 163.460008 87.510008) (width 0.1) (layer "F.Cu") (net 41))
  (segment (start 159.572697 87.547673) (end 159.572697 87.547672) (width 0.1) (layer "F.Cu") (net 41))
  (segment (start 162.610008 87.360008) (end 162.560008 87.360008) (width 0.1) (layer "F.Cu") (net 41))
  (segment (start 167.823168 87.198904) (end 167.823169 87.198903) (width 0.1) (layer "F.Cu") (net 41))
  (segment (start 159.572697 87.795159) (end 159.800692 88.023154) (width 0.1) (layer "F.Cu") (net 41))
  (segment (start 159.686328 88.385008) (end 159.686328 92.620008) (width 0.1) (layer "F.Cu") (net 41))
  (segment (start 159.572697 87.795158) (end 159.572697 87.795159) (width 0.1) (layer "F.Cu") (net 41))
  (segment (start 160.04818 87.775668) (end 159.820184 87.547672) (width 0.1) (layer "F.Cu") (net 41))
  (segment (start 164.360008 87.960008) (end 164.310008 87.960008) (width 0.1) (layer "F.Cu") (net 41))
  (segment (start 164.160008 87.810008) (end 164.160008 87.510008) (width 0.1) (layer "F.Cu") (net 41))
  (segment (start 161.910008 87.360008) (end 161.860008 87.360008) (width 0.1) (layer "F.Cu") (net 41))
  (segment (start 162.260008 87.960008) (end 162.210008 87.960008) (width 0.1) (layer "F.Cu") (net 41))
  (segment (start 161.710008 87.510008) (end 161.710008 87.810008) (width 0.1) (layer "F.Cu") (net 41))
  (segment (start 166.524992 87.500008) (end 164.719992 87.500008) (width 0.1) (layer "F.Cu") (net 41))
  (via (at 159.676328 88.390008) (size 0.5) (drill 0.2) (layers "F.Cu" "B.Cu") (net 41))
  (arc (start 164.66 87.5) (mid 164.553934 87.543934) (end 164.51 87.65) (width 0.1) (layer "F.Cu") (net 41))
  (arc (start 161.360008 87.510008) (mid 161.316074 87.403942) (end 161.210008 87.360008) (width 0.1) (layer "F.Cu") (net 41))
  (arc (start 162.060008 87.510008) (mid 162.016074 87.403942) (end 161.910008 87.360008) (width 0.1) (layer "F.Cu") (net 41))
  (arc (start 161.510008 87.960008) (mid 161.403942 87.916074) (end 161.360008 87.810008) (width 0.1) (layer "F.Cu") (net 41))
  (arc (start 159.800692 88.023154) (mid 159.851948 88.146898) (end 159.800691 88.270641) (width 0.1) (layer "F.Cu") (net 41))
  (arc (start 162.210008 87.960008) (mid 162.103942 87.916074) (end 162.060008 87.810008) (width 0.1) (layer "F.Cu") (net 41))
  (arc (start 162.910008 87.960008) (mid 162.803942 87.916074) (end 162.760008 87.810008) (width 0.1) (layer "F.Cu") (net 41))
  (arc (start 163.110008 87.810008) (mid 163.066074 87.916074) (end 162.960008 87.960008) (width 0.1) (layer "F.Cu") (net 41))
  (arc (start 159.572697 87.547672) (mid 159.521441 87.671415) (end 159.572697 87.795158) (width 0.1) (layer "F.Cu") (net 41))
  (arc (start 161.010008 87.510008) (mid 160.966074 87.616074) (end 160.860008 87.660008) (width 0.1) (layer "F.Cu") (net 41))
  (arc (start 162.410008 87.810008) (mid 162.366074 87.916074) (end 162.260008 87.960008) (width 0.1) (layer "F.Cu") (net 41))
  (arc (start 163.810008 87.810008) (mid 163.766074 87.916074) (end 163.660008 87.960008) (width 0.1) (layer "F.Cu") (net 41))
  (arc (start 163.960008 87.360008) (mid 163.853942 87.403942) (end 163.810008 87.510008) (width 0.1) (layer "F.Cu") (net 41))
  (arc (start 160.295668 87.775668) (mid 160.171924 87.826924) (end 160.04818 87.775668) (width 0.1) (layer "F.Cu") (net 41))
  (arc (start 161.160008 87.360008) (mid 161.053942 87.403942) (end 161.010008 87.510008) (width 0.1) (layer "F.Cu") (net 41))
  (arc (start 167.823169 87.198903) (mid 167.779235 87.304968) (end 167.823168 87.411036) (width 0.1) (layer "F.Cu") (net 41))
  (arc (start 164.510008 87.810008) (mid 164.466074 87.916074) (end 164.360008 87.960008) (width 0.1) (layer "F.Cu") (net 41))
  (arc (start 163.260008 87.360008) (mid 163.153942 87.403942) (end 163.110008 87.510008) (width 0.1) (layer "F.Cu") (net 41))
  (arc (start 162.560008 87.360008) (mid 162.453942 87.403942) (end 162.410008 87.510008) (width 0.1) (layer "F.Cu") (net 41))
  (arc (start 163.460008 87.510008) (mid 163.416074 87.403942) (end 163.310008 87.360008) (width 0.1) (layer "F.Cu") (net 41))
  (arc (start 161.710008 87.810008) (mid 161.666074 87.916074) (end 161.560008 87.960008) (width 0.1) (layer "F.Cu") (net 41))
  (arc (start 162.760008 87.510008) (mid 162.716074 87.403942) (end 162.610008 87.360008) (width 0.1) (layer "F.Cu") (net 41))
  (arc (start 161.860008 87.360008) (mid 161.753942 87.403942) (end 161.710008 87.510008) (width 0.1) (layer "F.Cu") (net 41))
  (arc (start 168.247435 87.198904) (mid 168.141367 87.242839) (end 168.035302 87.198903) (width 0.1) (layer "F.Cu") (net 41))
  (arc (start 163.610008 87.960008) (mid 163.503942 87.916074) (end 163.460008 87.810008) (width 0.1) (layer "F.Cu") (net 41))
  (arc (start 167.823168 87.411036) (mid 167.867102 87.517102) (end 167.823168 87.623168) (width 0.1) (layer "F.Cu") (net 41))
  (arc (start 164.310008 87.960008) (mid 164.203942 87.916074) (end 164.160008 87.810008) (width 0.1) (layer "F.Cu") (net 41))
  (arc (start 159.820184 87.547672) (mid 159.69644 87.496416) (end 159.572697 87.547673) (width 0.1) (layer "F.Cu") (net 41))
  (arc (start 168.035302 87.198904) (mid 167.929236 87.154969) (end 167.823168 87.198904) (width 0.1) (layer "F.Cu") (net 41))
  (arc (start 164.160008 87.510008) (mid 164.116074 87.403942) (end 164.010008 87.360008) (width 0.1) (layer "F.Cu") (net 41))
  (segment (start 159.636328 89.095008) (end 159.636328 88.420008) (width 0.2) (layer "B.Cu") (net 41))
  (segment (start 159.636328 87.805008) (end 159.636328 88.410008) (width 0.2) (layer "B.Cu") (net 41))
  (segment (start 159.636328 88.410008) (end 159.636328 88.420008) (width 0.2) (layer "B.Cu") (net 41))
  (segment (start 209.31 124.36) (end 209.6785 124.7285) (width 0.1) (layer "F.Cu") (net 42))
  (segment (start 209.6485 119.664) (end 209.31 120.0025) (width 0.1) (layer "F.Cu") (net 42))
  (segment (start 209.292501 117.014748) (end 209.292501 113.982499) (width 0.1) (layer "F.Cu") (net 42))
  (segment (start 209.31 120.0025) (end 209.31 124.36) (width 0.1) (layer "F.Cu") (net 42))
  (segment (start 209.6785 124.7285) (end 209.6785 126.95) (width 0.1) (layer "F.Cu") (net 42))
  (segment (start 209.6485 117.370747) (end 209.292501 117.014748) (width 0.1) (layer "F.Cu") (net 42))
  (segment (start 209.6485 118.68) (end 209.6485 119.664) (width 0.1) (layer "F.Cu") (net 42))
  (segment (start 209.6485 118.68) (end 209.6485 117.370747) (width 0.1) (layer "F.Cu") (net 42))
  (segment (start 209.655 113.62) (end 209.292501 113.982499) (width 0.1) (layer "F.Cu") (net 42))
  (segment (start 209.01 124.34) (end 208.6785 124.6715) (width 0.1) (layer "F.Cu") (net 43))
  (segment (start 208.992499 117.026748) (end 208.992499 113.982499) (width 0.1) (layer "F.Cu") (net 43))
  (segment (start 208.6785 124.6715) (end 208.6785 126.95) (width 0.1) (layer "F.Cu") (net 43))
  (segment (start 208.63 113.62) (end 208.992499 113.982499) (width 0.1) (layer "F.Cu") (net 43))
  (segment (start 208.6485 117.370747) (end 208.992499 117.026748) (width 0.1) (layer "F.Cu") (net 43))
  (segment (start 208.6485 118.68) (end 208.6485 119.695501) (width 0.1) (layer "F.Cu") (net 43))
  (segment (start 208.6485 119.695501) (end 209.01 120.057001) (width 0.1) (layer "F.Cu") (net 43))
  (segment (start 209.01 120.057001) (end 209.01 124.34) (width 0.1) (layer "F.Cu") (net 43))
  (segment (start 208.6485 118.68) (end 208.6485 117.370747) (width 0.1) (layer "F.Cu") (net 43))
  (segment (start 210.502499 116.197499) (end 210.502499 117.127501) (width 0.1) (layer "F.Cu") (net 44))
  (segment (start 210.53 120.055) (end 210.53 124.37) (width 0.1) (layer "F.Cu") (net 44))
  (segment (start 210.1785 124.7215) (end 210.1785 126.95) (width 0.1) (layer "F.Cu") (net 44))
  (segment (start 210.53 124.37) (end 210.1785 124.7215) (width 0.1) (layer "F.Cu") (net 44))
  (segment (start 210.502499 117.127501) (end 210.1485 117.4815) (width 0.1) (layer "F.Cu") (net 44))
  (segment (start 210.1485 117.4815) (end 210.1485 118.68) (width 0.1) (layer "F.Cu") (net 44))
  (segment (start 210.1485 118.68) (end 210.1485 119.6735) (width 0.1) (layer "F.Cu") (net 44))
  (segment (start 210.14 115.835) (end 210.502499 116.197499) (width 0.1) (layer "F.Cu") (net 44))
  (segment (start 210.1485 119.6735) (end 210.53 120.055) (width 0.1) (layer "F.Cu") (net 44))
  (segment (start 211.1485 117.4885) (end 211.1485 118.68) (width 0.1) (layer "F.Cu") (net 45))
  (segment (start 210.802501 116.197499) (end 210.802501 117.142501) (width 0.1) (layer "F.Cu") (net 45))
  (segment (start 211.145 119.655) (end 210.81 119.99) (width 0.1) (layer "F.Cu") (net 45))
  (segment (start 211.1785 124.7485) (end 211.1785 126.95) (width 0.1) (layer "F.Cu") (net 45))
  (segment (start 210.81 124.38) (end 211.1785 124.7485) (width 0.1) (layer "F.Cu") (net 45))
  (segment (start 210.81 119.99) (end 210.81 124.38) (width 0.1) (layer "F.Cu") (net 45))
  (segment (start 211.165 115.835) (end 210.802501 116.197499) (width 0.1) (layer "F.Cu") (net 45))
  (segment (start 211.1485 119.655) (end 211.145 119.655) (width 0.1) (layer "F.Cu") (net 45))
  (segment (start 210.802501 117.142501) (end 211.1485 117.4885) (width 0.1) (layer "F.Cu") (net 45))
  (segment (start 211.1485 118.68) (end 211.1485 119.655) (width 0.1) (layer "F.Cu") (net 45))
  (segment (start 212.6485 119.655) (end 212.645 119.655) (width 0.1) (layer "F.Cu") (net 46))
  (segment (start 212.295001 113.974999) (end 212.65 113.62) (width 0.1) (layer "F.Cu") (net 46))
  (segment (start 212.31 119.99) (end 212.31 124.41) (width 0.1) (layer "F.Cu") (net 46))
  (segment (start 212.295001 117.154711) (end 212.295001 113.974999) (width 0.1) (layer "F.Cu") (net 46))
  (segment (start 212.6485 118.68) (end 212.6485 119.655) (width 0.1) (layer "F.Cu") (net 46))
  (segment (start 212.31 124.41) (end 212.6785 124.7785) (width 0.1) (layer "F.Cu") (net 46))
  (segment (start 212.6785 124.7785) (end 212.6785 126.95) (width 0.1) (layer "F.Cu") (net 46))
  (segment (start 212.645 119.655) (end 212.31 119.99) (width 0.1) (layer "F.Cu") (net 46))
  (segment (start 212.6485 118.68) (end 212.6485 117.50821) (width 0.1) (layer "F.Cu") (net 46))
  (segment (start 212.6485 117.50821) (end 212.295001 117.154711) (width 0.1) (layer "F.Cu") (net 46))
  (segment (start 213.14 115.835) (end 213.497999 116.192999) (width 0.1) (layer "F.Cu") (net 47))
  (segment (start 213.1485 117.4765) (end 213.1485 118.68) (width 0.1) (layer "F.Cu") (net 47))
  (segment (start 213.497999 116.192999) (end 213.497999 117.127001) (width 0.1) (layer "F.Cu") (net 47))
  (segment (start 213.51 124.330472) (end 213.1785 124.661972) (width 0.1) (layer "F.Cu") (net 47))
  (segment (start 213.1485 118.68) (end 213.1485 119.6735) (width 0.1) (layer "F.Cu") (net 47))
  (segment (start 213.1485 119.6735) (end 213.51 120.035) (width 0.1) (layer "F.Cu") (net 47))
  (segment (start 213.1785 124.661972) (end 213.1785 126.95) (width 0.1) (layer "F.Cu") (net 47))
  (segment (start 213.497999 117.127001) (end 213.1485 117.4765) (width 0.1) (layer "F.Cu") (net 47))
  (segment (start 213.51 120.035) (end 213.51 124.330472) (width 0.1) (layer "F.Cu") (net 47))
  (segment (start 214.1485 118.68) (end 214.1485 119.6765) (width 0.1) (layer "F.Cu") (net 48))
  (segment (start 213.798001 116.192999) (end 213.798001 117.138001) (width 0.1) (layer "F.Cu") (net 48))
  (segment (start 214.156 115.835) (end 213.798001 116.192999) (width 0.1) (layer "F.Cu") (net 48))
  (segment (start 213.82 120.005) (end 213.82 124.363472) (width 0.1) (layer "F.Cu") (net 48))
  (segment (start 214.1485 117.4885) (end 214.1485 118.68) (width 0.1) (layer "F.Cu") (net 48))
  (segment (start 214.1785 124.721972) (end 214.1785 126.95) (width 0.1) (layer "F.Cu") (net 48))
  (segment (start 213.798001 117.138001) (end 214.1485 117.4885) (width 0.1) (layer "F.Cu") (net 48))
  (segment (start 213.82 124.363472) (end 214.1785 124.721972) (width 0.1) (layer "F.Cu") (net 48))
  (segment (start 214.1485 119.6765) (end 213.82 120.005) (width 0.1) (layer "F.Cu") (net 48))
  (segment (start 112.286328 115.222157) (end 111.121328 115.222157) (width 0.3) (layer "F.Cu") (net 53))
  (segment (start 111.121328 115.222157) (end 110.771328 114.872157) (width 0.3) (layer "F.Cu") (net 53))
  (segment (start 212.01 124.34) (end 211.6785 124.6715) (width 0.1) (layer "F.Cu") (net 54))
  (segment (start 212.01 120.0165) (end 212.01 124.34) (width 0.1) (layer "F.Cu") (net 54))
  (segment (start 211.994999 113.974999) (end 211.64 113.62) (width 0.1) (layer "F.Cu") (net 54))
  (segment (start 211.6785 124.6715) (end 211.6785 126.95) (width 0.1) (layer "F.Cu") (net 54))
  (segment (start 211.6485 117.479711) (end 211.994999 117.133212) (width 0.1) (layer "F.Cu") (net 54))
  (segment (start 211.994999 117.133212) (end 211.994999 113.974999) (width 0.1) (layer "F.Cu") (net 54))
  (segment (start 211.6485 118.68) (end 211.6485 117.479711) (width 0.1) (layer "F.Cu") (net 54))
  (segment (start 211.6485 119.655) (end 212.01 120.0165) (width 0.1) (layer "F.Cu") (net 54))
  (segment (start 211.6485 118.68) (end 211.6485 119.655) (width 0.1) (layer "F.Cu") (net 54))
  (segment (start 184.787134 109.025) (end 207.362134 109.025) (width 0.1) (layer "F.Cu") (net 55))
  (segment (start 182.537 102.725686) (end 182.436328 102.826358) (width 0.1) (layer "F.Cu") (net 55))
  (segment (start 182.537 102.394314) (end 182.537 102.725686) (width 0.1) (layer "F.Cu") (net 55))
  (segment (start 209.296819 110.959685) (end 209.296819 112.291819) (width 0.1) (layer "F.Cu") (net 55))
  (segment (start 182.436328 102.826358) (end 182.436328 106.674194) (width 0.1) (layer "F.Cu") (net 55))
  (segment (start 209.296819 112.291819) (end 209.655 112.65) (width 0.1) (layer "F.Cu") (net 55))
  (segment (start 182.436328 102.293642) (end 182.537 102.394314) (width 0.1) (layer "F.Cu") (net 55))
  (segment (start 182.436328 106.674194) (end 184.787134 109.025) (width 0.1) (layer "F.Cu") (net 55))
  (segment (start 207.362134 109.025) (end 209.296819 110.959685) (width 0.1) (layer "F.Cu") (net 55))
  (segment (start 182.136328 101.560008) (end 182.436328 101.860008) (width 0.1) (layer "F.Cu") (net 55))
  (segment (start 182.436328 101.860008) (end 182.436328 102.293642) (width 0.1) (layer "F.Cu") (net 55))
  (segment (start 208.996819 112.283181) (end 208.63 112.65) (width 0.1) (layer "F.Cu") (net 56))
  (segment (start 184.662866 109.325) (end 207.237866 109.325) (width 0.1) (layer "F.Cu") (net 56))
  (segment (start 182.136328 104.986328) (end 182.136328 106.798462) (width 0.1) (layer "F.Cu") (net 56))
  (segment (start 208.996819 111.083953) (end 208.996819 112.283181) (width 0.1) (layer "F.Cu") (net 56))
  (segment (start 182.136328 102.560008) (end 182.136328 103.986328) (width 0.1) (layer "F.Cu") (net 56))
  (segment (start 207.237866 109.325) (end 208.996819 111.083953) (width 0.1) (layer "F.Cu") (net 56))
  (segment (start 182.136328 104.985736) (end 182.136328 104.986328) (width 0.1) (layer "F.Cu") (net 56))
  (segment (start 182.136328 106.798462) (end 184.662866 109.325) (width 0.1) (layer "F.Cu") (net 56))
  (segment (start 181.636919 104.485736) (end 181.636919 104.486328) (width 0.1) (layer "F.Cu") (net 56))
  (segment (start 181.886624 104.236032) (end 181.886623 104.236032) (width 0.1) (layer "F.Cu") (net 56))
  (segment (start 181.886623 104.736032) (end 181.886624 104.736032) (width 0.1) (layer "F.Cu") (net 56))
  (arc (start 182.136328 103.986328) (mid 182.063191 104.162895) (end 181.886624 104.236032) (width 0.1) (layer "F.Cu") (net 56))
  (arc (start 181.886623 104.236032) (mid 181.710056 104.309169) (end 181.636919 104.485736) (width 0.1) (layer "F.Cu") (net 56))
  (arc (start 181.636919 104.486328) (mid 181.710056 104.662895) (end 181.886623 104.736032) (width 0.1) (layer "F.Cu") (net 56))
  (arc (start 181.886624 104.736032) (mid 182.063191 104.809169) (end 182.136328 104.985736) (width 0.1) (layer "F.Cu") (net 56))
  (segment (start 210.8175 114.5175) (end 211.165 114.865) (width 0.1) (layer "F.Cu") (net 57))
  (segment (start 183.136328 101.560008) (end 183.436328 101.860008) (width 0.1) (layer "F.Cu") (net 57))
  (segment (start 183.875 103.462866) (end 183.875 105.737866) (width 0.1) (layer "F.Cu") (net 57))
  (segment (start 208.437134 107.95) (end 210.8175 110.330366) (width 0.1) (layer "F.Cu") (net 57))
  (segment (start 183.436328 101.860008) (end 183.436328 102.294322) (width 0.1) (layer "F.Cu") (net 57))
  (segment (start 210.8175 110.330366) (end 210.8175 114.5175) (width 0.1) (layer "F.Cu") (net 57))
  (segment (start 183.875 105.737866) (end 186.087134 107.95) (width 0.1) (layer "F.Cu") (net 57))
  (segment (start 183.536328 102.725694) (end 183.436328 102.825694) (width 0.1) (layer "F.Cu") (net 57))
  (segment (start 183.436328 102.294322) (end 183.536328 102.394322) (width 0.1) (layer "F.Cu") (net 57))
  (segment (start 186.087134 107.95) (end 208.437134 107.95) (width 0.1) (layer "F.Cu") (net 57))
  (segment (start 183.436328 103.024194) (end 183.875 103.462866) (width 0.1) (layer "F.Cu") (net 57))
  (segment (start 183.536328 102.394322) (end 183.536328 102.725694) (width 0.1) (layer "F.Cu") (net 57))
  (segment (start 183.436328 102.825694) (end 183.436328 103.024194) (width 0.1) (layer "F.Cu") (net 57))
  (segment (start 183.136328 102.560008) (end 183.136328 103.148462) (width 0.1) (layer "F.Cu") (net 58))
  (segment (start 208.312866 108.25) (end 210.5175 110.454634) (width 0.1) (layer "F.Cu") (net 58))
  (segment (start 183.575 103.587134) (end 183.575 103.755) (width 0.1) (layer "F.Cu") (net 58))
  (segment (start 183.575 104.555) (end 183.575 105.862134) (width 0.1) (layer "F.Cu") (net 58))
  (segment (start 210.5175 114.4875) (end 210.14 114.865) (width 0.1) (layer "F.Cu") (net 58))
  (segment (start 183.575 105.862134) (end 185.962866 108.25) (width 0.1) (layer "F.Cu") (net 58))
  (segment (start 210.5175 110.454634) (end 210.5175 114.4875) (width 0.1) (layer "F.Cu") (net 58))
  (segment (start 183.136328 103.148462) (end 183.575 103.587134) (width 0.1) (layer "F.Cu") (net 58))
  (segment (start 185.962866 108.25) (end 208.312866 108.25) (width 0.1) (layer "F.Cu") (net 58))
  (segment (start 183.214479 104.355) (end 183.375 104.355) (width 0.1) (layer "F.Cu") (net 58))
  (segment (start 183.375 103.955) (end 183.214479 103.955) (width 0.1) (layer "F.Cu") (net 58))
  (arc (start 183.014479 104.155) (mid 183.073058 104.296421) (end 183.214479 104.355) (width 0.1) (layer "F.Cu") (net 58))
  (arc (start 183.575 103.755) (mid 183.516421 103.896421) (end 183.375 103.955) (width 0.1) (layer "F.Cu") (net 58))
  (arc (start 183.375 104.355) (mid 183.516421 104.413579) (end 183.575 104.555) (width 0.1) (layer "F.Cu") (net 58))
  (arc (start 183.214479 103.955) (mid 183.073058 104.013579) (end 183.014479 104.155) (width 0.1) (layer "F.Cu") (net 58))
  (segment (start 185.302014 102.160008) (end 185.575 102.432994) (width 0.1) (layer "F.Cu") (net 59))
  (segment (start 185.2875 103.2375) (end 185.2875 104.750366) (width 0.1) (layer "F.Cu") (net 59))
  (segment (start 212.295001 109.357867) (end 212.295001 112.295001) (width 0.1) (layer "F.Cu") (net 59))
  (segment (start 184.136328 102.560008) (end 184.536328 102.160008) (width 0.1) (layer "F.Cu") (net 59))
  (segment (start 185.575 102.95) (end 185.2875 103.2375) (width 0.1) (layer "F.Cu") (net 59))
  (segment (start 185.2875 104.750366) (end 187.287134 106.75) (width 0.1) (layer "F.Cu") (net 59))
  (segment (start 212.295001 112.295001) (end 212.65 112.65) (width 0.1) (layer "F.Cu") (net 59))
  (segment (start 187.287134 106.75) (end 209.687134 106.75) (width 0.1) (layer "F.Cu") (net 59))
  (segment (start 209.687134 106.75) (end 212.295001 109.357867) (width 0.1) (layer "F.Cu") (net 59))
  (segment (start 184.536328 102.160008) (end 185.302014 102.160008) (width 0.1) (layer "F.Cu") (net 59))
  (segment (start 185.575 102.432994) (end 185.575 102.95) (width 0.1) (layer "F.Cu") (net 59))
  (segment (start 184.8125 103.9875) (end 184.6125 103.9875) (width 0.1) (layer "F.Cu") (net 60))
  (segment (start 185.30973 105.604864) (end 185.309729 105.604865) (width 0.1) (layer "F.Cu") (net 60))
  (segment (start 184.6125 103.5875) (end 184.8125 103.5875) (width 0.1) (layer "F.Cu") (net 60))
  (segment (start 184.9875 103) (end 184.9875 103.0625) (width 0.1) (layer "F.Cu") (net 60))
  (segment (start 184.9875 104.5625) (end 184.9875 104.874634) (width 0.1) (layer "F.Cu") (net 60))
  (segment (start 209.562866 107.05) (end 211.994999 109.482133) (width 0.1) (layer "F.Cu") (net 60))
  (segment (start 185.672829 105.559962) (end 185.672829 105.559963) (width 0.1) (layer "F.Cu") (net 60))
  (segment (start 185.036432 105.241766) (end 185.036433 105.241765) (width 0.1) (layer "F.Cu") (net 60))
  (segment (start 185.136328 102.560008) (end 185.136328 102.851172) (width 0.1) (layer "F.Cu") (net 60))
  (segment (start 185.136328 102.851172) (end 184.9875 103) (width 0.1) (layer "F.Cu") (net 60))
  (segment (start 184.9875 104.5125) (end 184.9875 104.5625) (width 0.1) (layer "F.Cu") (net 60))
  (segment (start 184.9875 103.7625) (end 184.9875 103.8125) (width 0.1) (layer "F.Cu") (net 60))
  (segment (start 184.6125 104.3375) (end 184.8125 104.3375) (width 0.1) (layer "F.Cu") (net 60))
  (segment (start 184.9875 104.874634) (end 185.036433 104.923567) (width 0.1) (layer "F.Cu") (net 60))
  (segment (start 211.994999 112.295001) (end 211.64 112.65) (width 0.1) (layer "F.Cu") (net 60))
  (segment (start 185.309729 105.604865) (end 185.35463 105.559963) (width 0.1) (layer "F.Cu") (net 60))
  (segment (start 187.162866 107.05) (end 209.562866 107.05) (width 0.1) (layer "F.Cu") (net 60))
  (segment (start 184.8125 103.2375) (end 184.6125 103.2375) (width 0.1) (layer "F.Cu") (net 60))
  (segment (start 184.99153 105.604865) (end 184.991531 105.604865) (width 0.1) (layer "F.Cu") (net 60))
  (segment (start 211.994999 109.482133) (end 211.994999 112.295001) (width 0.1) (layer "F.Cu") (net 60))
  (segment (start 185.036433 105.241765) (end 184.991531 105.286666) (width 0.1) (layer "F.Cu") (net 60))
  (segment (start 185.672829 105.559963) (end 187.162866 107.05) (width 0.1) (layer "F.Cu") (net 60))
  (arc (start 184.8125 104.3375) (mid 184.936244 104.388756) (end 184.9875 104.5125) (width 0.1) (layer "F.Cu") (net 60))
  (arc (start 185.036433 104.923567) (mid 185.102334 105.082667) (end 185.036432 105.241766) (width 0.1) (layer "F.Cu") (net 60))
  (arc (start 184.4375 104.1625) (mid 184.488756 104.286244) (end 184.6125 104.3375) (width 0.1) (layer "F.Cu") (net 60))
  (arc (start 184.9875 103.0625) (mid 184.936244 103.186244) (end 184.8125 103.2375) (width 0.1) (layer "F.Cu") (net 60))
  (arc (start 184.991531 105.286666) (mid 184.925629 105.445765) (end 184.99153 105.604865) (width 0.1) (layer "F.Cu") (net 60))
  (arc (start 184.6125 103.9875) (mid 184.488756 104.038756) (end 184.4375 104.1625) (width 0.1) (layer "F.Cu") (net 60))
  (arc (start 184.4375 103.4125) (mid 184.488756 103.536244) (end 184.6125 103.5875) (width 0.1) (layer "F.Cu") (net 60))
  (arc (start 185.35463 105.559963) (mid 185.513729 105.494061) (end 185.672829 105.559962) (width 0.1) (layer "F.Cu") (net 60))
  (arc (start 184.991531 105.604865) (mid 185.150631 105.670766) (end 185.30973 105.604864) (width 0.1) (layer "F.Cu") (net 60))
  (arc (start 184.8125 103.5875) (mid 184.936244 103.638756) (end 184.9875 103.7625) (width 0.1) (layer "F.Cu") (net 60))
  (arc (start 184.9875 103.8125) (mid 184.936244 103.936244) (end 184.8125 103.9875) (width 0.1) (layer "F.Cu") (net 60))
  (arc (start 184.6125 103.2375) (mid 184.488756 103.288756) (end 184.4375 103.4125) (width 0.1) (layer "F.Cu") (net 60))
  (segment (start 187.436328 102.294322) (end 187.536328 102.394322) (width 0.1) (layer "F.Cu") (net 61))
  (segment (start 213.798001 108.610867) (end 213.798001 114.507001) (width 0.1) (layer "F.Cu") (net 61))
  (segment (start 188.662134 105.65) (end 210.837134 105.65) (width 0.1) (layer "F.Cu") (net 61))
  (segment (start 187.136328 101.560008) (end 187.436328 101.860008) (width 0.1) (layer "F.Cu") (net 61))
  (segment (start 187.436328 104.424194) (end 188.662134 105.65) (width 0.1) (layer "F.Cu") (net 61))
  (segment (start 187.436328 101.860008) (end 187.436328 102.294322) (width 0.1) (layer "F.Cu") (net 61))
  (segment (start 210.837134 105.65) (end 213.798001 108.610867) (width 0.1) (layer "F.Cu") (net 61))
  (segment (start 187.611328 103.371328) (end 187.615041 103.371328) (width 0.1) (layer "F.Cu") (net 61))
  (segment (start 187.615041 103.721328) (end 187.611328 103.721328) (width 0.1) (layer "F.Cu") (net 61))
  (segment (start 213.798001 114.507001) (end 214.156 114.865) (width 0.1) (layer "F.Cu") (net 61))
  (segment (start 187.436328 102.825694) (end 187.436328 103.196328) (width 0.1) (layer "F.Cu") (net 61))
  (segment (start 187.436328 103.946328) (end 187.436328 104.424194) (width 0.1) (layer "F.Cu") (net 61))
  (segment (start 187.536328 102.725694) (end 187.436328 102.825694) (width 0.1) (layer "F.Cu") (net 61))
  (segment (start 187.536328 102.394322) (end 187.536328 102.725694) (width 0.1) (layer "F.Cu") (net 61))
  (segment (start 187.436328 103.896328) (end 187.436328 103.946328) (width 0.1) (layer "F.Cu") (net 61))
  (arc (start 187.436328 103.196328) (mid 187.487584 103.320072) (end 187.611328 103.371328) (width 0.1) (layer "F.Cu") (net 61))
  (arc (start 187.790041 103.546328) (mid 187.738785 103.670072) (end 187.615041 103.721328) (width 0.1) (layer "F.Cu") (net 61))
  (arc (start 187.615041 103.371328) (mid 187.738785 103.422584) (end 187.790041 103.546328) (width 0.1) (layer "F.Cu") (net 61))
  (arc (start 187.611328 103.721328) (mid 187.487584 103.772584) (end 187.436328 103.896328) (width 0.1) (layer "F.Cu") (net 61))
  (segment (start 187.136328 104.548462) (end 188.537866 105.95) (width 0.1) (layer "F.Cu") (net 62))
  (segment (start 210.712866 105.95) (end 213.497999 108.735133) (width 0.1) (layer "F.Cu") (net 62))
  (segment (start 187.136328 102.560008) (end 187.136328 104.548462) (width 0.1) (layer "F.Cu") (net 62))
  (segment (start 188.537866 105.95) (end 210.712866 105.95) (width 0.1) (layer "F.Cu") (net 62))
  (segment (start 213.497999 108.735133) (end 213.497999 114.507001) (width 0.1) (layer "F.Cu") (net 62))
  (segment (start 213.497999 114.507001) (end 213.14 114.865) (width 0.1) (layer "F.Cu") (net 62))
  (segment (start 251.01 108.85) (end 251.01 107.06) (width 0.2) (layer "F.Cu") (net 63))
  (segment (start 251.01 107.06) (end 250.95 107) (width 0.2) (layer "F.Cu") (net 63))
  (via (at 243.85 102) (size 0.5) (drill 0.2) (layers "F.Cu" "B.Cu") (net 63))
  (via (at 251.01 108.85) (size 0.5) (drill 0.2) (layers "F.Cu" "B.Cu") (net 63))
  (segment (start 247.85 102.5) (end 247.85 105.69) (width 0.15) (layer "In7.Cu") (net 63))
  (segment (start 247.85 105.69) (end 251.01 108.85) (width 0.15) (layer "In7.Cu") (net 63))
  (segment (start 245.489 101.761) (end 246.671674 101.761) (width 0.15) (layer "In7.Cu") (net 63))
  (segment (start 247.435 102.085) (end 247.85 102.5) (width 0.15) (layer "In7.Cu") (net 63))
  (segment (start 245.205 102.045) (end 245.489 101.761) (width 0.15) (layer "In7.Cu") (net 63))
  (segment (start 246.995674 102.085) (end 247.435 102.085) (width 0.15) (layer "In7.Cu") (net 63))
  (segment (start 243.85 102) (end 243.895 102.045) (width 0.15) (layer "In7.Cu") (net 63))
  (segment (start 246.671674 101.761) (end 246.995674 102.085) (width 0.15) (layer "In7.Cu") (net 63))
  (segment (start 243.895 102.045) (end 245.205 102.045) (width 0.15) (layer "In7.Cu") (net 63))
  (segment (start 241.985 97.8) (end 242.6 98.415) (width 0.2) (layer "B.Cu") (net 63))
  (segment (start 243.25 102) (end 243.85 102) (width 0.2) (layer "B.Cu") (net 63))
  (segment (start 242.6 101.35) (end 243.25 102) (width 0.2) (layer "B.Cu") (net 63))
  (segment (start 242.6 98.415) (end 242.6 101.35) (width 0.2) (layer "B.Cu") (net 63))
  (segment (start 250.95 96.14) (end 250.995 96.185) (width 0.2) (layer "F.Cu") (net 64))
  (segment (start 250.95 95) (end 250.95 96.14) (width 0.2) (layer "F.Cu") (net 64))
  (via (at 250.995 96.185) (size 0.5) (drill 0.2) (layers "F.Cu" "B.Cu") (net 64))
  (via (at 243.75 94.5) (size 0.5) (drill 0.2) (layers "F.Cu" "B.Cu") (net 64))
  (segment (start 249.544326 94.105) (end 250.995 95.555674) (width 0.15) (layer "In7.Cu") (net 64))
  (segment (start 243.825 94.425) (end 245.451674 94.425) (width 0.15) (layer "In7.Cu") (net 64))
  (segment (start 243.75 94.5) (end 243.825 94.425) (width 0.15) (layer "In7.Cu") (net 64))
  (segment (start 245.451674 94.425) (end 245.735674 94.141) (width 0.15) (layer "In7.Cu") (net 64))
  (segment (start 247.895 94.105) (end 249.544326 94.105) (width 0.15) (layer "In7.Cu") (net 64))
  (segment (start 246.888 94.425) (end 247.575 94.425) (width 0.15) (layer "In7.Cu") (net 64))
  (segment (start 246.604 94.141) (end 246.888 94.425) (width 0.15) (layer "In7.Cu") (net 64))
  (segment (start 245.735674 94.141) (end 246.604 94.141) (width 0.15) (layer "In7.Cu") (net 64))
  (segment (start 247.575 94.425) (end 247.895 94.105) (width 0.15) (layer "In7.Cu") (net 64))
  (segment (start 250.995 95.555674) (end 250.995 96.185) (width 0.15) (layer "In7.Cu") (net 64))
  (segment (start 243 94.5) (end 242.6625 94.1625) (width 0.2) (layer "B.Cu") (net 64))
  (segment (start 243.75 94.5) (end 243 94.5) (width 0.2) (layer "B.Cu") (net 64))
  (segment (start 242.6625 94.1625) (end 242.6625 93.2775) (width 0.2) (layer "B.Cu") (net 64))
  (segment (start 242.6625 93.2775) (end 241.985 92.6) (width 0.2) (layer "B.Cu") (net 64))
  (segment (start 250.95 102.505) (end 250.945 102.51) (width 0.2) (layer "F.Cu") (net 65))
  (segment (start 250.95 101) (end 250.95 102.505) (width 0.2) (layer "F.Cu") (net 65))
  (via (at 243.75 98.15) (size 0.5) (drill 0.2) (layers "F.Cu" "B.Cu") (net 65))
  (via (at 250.945 102.51) (size 0.5) (drill 0.2) (layers "F.Cu" "B.Cu") (net 65))
  (segment (start 243.835 98.235) (end 245.215 98.235) (width 0.15) (layer "In7.Cu") (net 65))
  (segment (start 246.721674 97.951) (end 247.035674 98.265) (width 0.15) (layer "In7.Cu") (net 65))
  (segment (start 247.565 98.265) (end 247.8 98.5) (width 0.15) (layer "In7.Cu") (net 65))
  (segment (start 247.8 98.5) (end 247.8 99.365) (width 0.15) (layer "In7.Cu") (net 65))
  (segment (start 247.8 99.365) (end 250.945 102.51) (width 0.15) (layer "In7.Cu") (net 65))
  (segment (start 243.75 98.15) (end 243.835 98.235) (width 0.15) (layer "In7.Cu") (net 65))
  (segment (start 245.499 97.951) (end 246.721674 97.951) (width 0.15) (layer "In7.Cu") (net 65))
  (segment (start 247.035674 98.265) (end 247.565 98.265) (width 0.15) (layer "In7.Cu") (net 65))
  (segment (start 245.215 98.235) (end 245.499 97.951) (width 0.15) (layer "In7.Cu") (net 65))
  (segment (start 242.65 97.41468) (end 242.65 96.015) (width 0.2) (layer "B.Cu") (net 65))
  (segment (start 243.385319 98.15) (end 242.65 97.41468) (width 0.2) (layer "B.Cu") (net 65))
  (segment (start 243.75 98.15) (end 243.385319 98.15) (width 0.2) (layer "B.Cu") (net 65))
  (segment (start 242.65 96.015) (end 241.985 95.35) (width 0.2) (layer "B.Cu") (net 65))
  (segment (start 250.95 89.75) (end 250.95 89) (width 0.2) (layer "F.Cu") (net 66))
  (segment (start 251.02 89.82) (end 250.95 89.75) (width 0.2) (layer "F.Cu") (net 66))
  (via (at 242.7 89.906) (size 0.5) (drill 0.2) (layers "F.Cu" "B.Cu") (net 66))
  (via (at 251.02 89.82) (size 0.5) (drill 0.2) (layers "F.Cu" "B.Cu") (net 66))
  (segment (start 243.3 88.95) (end 242.7 89.55) (width 0.2) (layer "In7.Cu") (net 66))
  (segment (start 242.7 89.55) (end 242.7 89.906) (width 0.2) (layer "In7.Cu") (net 66))
  (segment (start 251.02 89.82) (end 250.15 88.95) (width 0.2) (layer "In7.Cu") (net 66))
  (segment (start 250.15 88.95) (end 243.3 88.95) (width 0.2) (layer "In7.Cu") (net 66))
  (segment (start 242.694 89.9) (end 242.7 89.906) (width 0.2) (layer "B.Cu") (net 66))
  (segment (start 241.985 89.9) (end 242.694 89.9) (width 0.2) (layer "B.Cu") (net 66))
  (segment (start 176.136328 99.560008) (end 175.636328 100.060008) (width 0.1) (layer "F.Cu") (net 67))
  (via (at 175.636328 100.060008) (size 0.5) (drill 0.2) (layers "F.Cu" "B.Cu") (net 67))
  (via (at 235.729 88.4) (size 0.5) (drill 0.2) (layers "F.Cu" "B.Cu") (net 67))
  (segment (start 199.85 93.55) (end 200.35 93.05) (width 0.1) (layer "In9.Cu") (net 67))
  (segment (start 188.524776 91.5) (end 196.292123 91.5) (width 0.1) (layer "In9.Cu") (net 67))
  (segment (start 175.636328 100.060008) (end 175.15 99.57368) (width 0.1) (layer "In9.Cu") (net 67))
  (segment (start 200.35 93.05) (end 233.05 93.05) (width 0.1) (layer "In9.Cu") (net 67))
  (segment (start 175.690153 92.6) (end 175.35 92.6) (width 0.1) (layer "In9.Cu") (net 67))
  (segment (start 188.246328 90.946328) (end 188.246328 91.221552) (width 0.1) (layer "In9.Cu") (net 67))
  (segment (start 179.797872 90.450008) (end 179.99788 90.25) (width 0.1) (layer "In9.Cu") (net 67))
  (segment (start 188.246328 91.221552) (end 188.524776 91.5) (width 0.1) (layer "In9.Cu") (net 67))
  (segment (start 177.8 90.2) (end 179 90.2) (width 0.1) (layer "In9.Cu") (net 67))
  (segment (start 233.05 93.05) (end 235.729 90.371) (width 0.1) (layer "In9.Cu") (net 67))
  (segment (start 177.070077 91.220077) (end 177.070077 90.929923) (width 0.1) (layer "In9.Cu") (net 67))
  (segment (start 175.690153 92.6) (end 177.070077 91.220077) (width 0.1) (layer "In9.Cu") (net 67))
  (segment (start 235.729 90.371) (end 235.729 88.4) (width 0.1) (layer "In9.Cu") (net 67))
  (segment (start 175.35 92.6) (end 175.15 92.8) (width 0.1) (layer "In9.Cu") (net 67))
  (segment (start 175.15 99.57368) (end 175.15 92.8) (width 0.1) (layer "In9.Cu") (net 67))
  (segment (start 177.070077 90.929923) (end 177.8 90.2) (width 0.1) (layer "In9.Cu") (net 67))
  (segment (start 179 90.2) (end 179.250008 90.450008) (width 0.1) (layer "In9.Cu") (net 67))
  (segment (start 179.99788 90.25) (end 187.55 90.25) (width 0.1) (layer "In9.Cu") (net 67))
  (segment (start 187.55 90.25) (end 188.246328 90.946328) (width 0.1) (layer "In9.Cu") (net 67))
  (segment (start 179.250008 90.450008) (end 179.797872 90.450008) (width 0.1) (layer "In9.Cu") (net 67))
  (segment (start 198.342123 93.55) (end 199.85 93.55) (width 0.1) (layer "In9.Cu") (net 67))
  (segment (start 196.292123 91.5) (end 198.342123 93.55) (width 0.1) (layer "In9.Cu") (net 67))
  (segment (start 237.075 95.375) (end 235.7 94) (width 0.1) (layer "B.Cu") (net 67))
  (segment (start 235.7 94) (end 235.7 88.429) (width 0.1) (layer "B.Cu") (net 67))
  (segment (start 235.7 88.429) (end 235.729 88.4) (width 0.1) (layer "B.Cu") (net 67))
  (segment (start 237.95 97.2) (end 237.075 96.325) (width 0.1) (layer "B.Cu") (net 67))
  (segment (start 237.075 96.325) (end 237.075 95.375) (width 0.1) (layer "B.Cu") (net 67))
  (segment (start 176.136328 101.560008) (end 175.636328 102.060008) (width 0.1) (layer "F.Cu") (net 68))
  (via (at 235.026205 87.577786) (size 0.5) (drill 0.2) (layers "F.Cu" "B.Cu") (net 68))
  (via (at 175.636328 102.060008) (size 0.5) (drill 0.2) (layers "F.Cu" "B.Cu") (net 68))
  (segment (start 178.1 89.3) (end 179.1 89.3) (width 0.1) (layer "In9.Cu") (net 68))
  (segment (start 174.65 100.480008) (end 174.462358 100.480008) (width 0.1) (layer "In9.Cu") (net 68))
  (segment (start 175.056328 101.480008) (end 175.056328 100.886336) (width 0.1) (layer "In9.Cu") (net 68))
  (segment (start 174.462358 100.480008) (end 174.15 100.16765) (width 0.1) (layer "In9.Cu") (net 68))
  (segment (start 198.240008 91.640008) (end 232.583492 91.640008) (width 0.1) (layer "In9.Cu") (net 68))
  (segment (start 175.636328 102.060008) (end 175.056328 101.480008) (width 0.1) (layer "In9.Cu") (net 68))
  (segment (start 177.939992 89.460008) (end 178.1 89.3) (width 0.1) (layer "In9.Cu") (net 68))
  (segment (start 176.642358 89.460008) (end 177.939992 89.460008) (width 0.1) (layer "In9.Cu") (net 68))
  (segment (start 232.583492 91.640008) (end 234.687 89.5365) (width 0.1) (layer "In9.Cu") (net 68))
  (segment (start 173.5 95.35) (end 173.5 92.790306) (width 0.1) (layer "In9.Cu") (net 68))
  (segment (start 192.380996 90.157994) (end 196.757994 90.157994) (width 0.1) (layer "In9.Cu") (net 68))
  (segment (start 174.15 100.16765) (end 174.15 96) (width 0.1) (layer "In9.Cu") (net 68))
  (segment (start 175.216328 90.886038) (end 176.642358 89.460008) (width 0.1) (layer "In9.Cu") (net 68))
  (segment (start 191.68301 89.460008) (end 192.380996 90.157994) (width 0.1) (layer "In9.Cu") (net 68))
  (segment (start 173.5 92.790306) (end 175.216328 91.073978) (width 0.1) (layer "In9.Cu") (net 68))
  (segment (start 179.1 89.3) (end 179.260008 89.460008) (width 0.1) (layer "In9.Cu") (net 68))
  (segment (start 175.056328 100.886336) (end 174.65 100.480008) (width 0.1) (layer "In9.Cu") (net 68))
  (segment (start 174.15 96) (end 173.5 95.35) (width 0.1) (layer "In9.Cu") (net 68))
  (segment (start 175.216328 91.073978) (end 175.216328 90.886038) (width 0.1) (layer "In9.Cu") (net 68))
  (segment (start 196.757994 90.157994) (end 198.240008 91.640008) (width 0.1) (layer "In9.Cu") (net 68))
  (segment (start 234.687 89.5365) (end 234.687 87.916991) (width 0.1) (layer "In9.Cu") (net 68))
  (segment (start 179.260008 89.460008) (end 191.68301 89.460008) (width 0.1) (layer "In9.Cu") (net 68))
  (segment (start 234.687 87.916991) (end 235.026205 87.577786) (width 0.1) (layer "In9.Cu") (net 68))
  (segment (start 235.298419 87.85) (end 236.8 87.85) (width 0.1) (layer "B.Cu") (net 68))
  (segment (start 237.15 91.5) (end 237.5 91.85) (width 0.1) (layer "B.Cu") (net 68))
  (segment (start 235.026205 87.577786) (end 235.298419 87.85) (width 0.1) (layer "B.Cu") (net 68))
  (segment (start 236.8 87.85) (end 237.15 88.2) (width 0.1) (layer "B.Cu") (net 68))
  (segment (start 237.15 88.2) (end 237.15 91.5) (width 0.1) (layer "B.Cu") (net 68))
  (segment (start 237.5 91.85) (end 237.95 91.85) (width 0.1) (layer "B.Cu") (net 68))
  (segment (start 117.136328 115.497157) (end 118.926328 115.497157) (width 0.15) (layer "F.Cu") (net 69))
  (segment (start 116.286328 115.222157) (end 116.861328 115.222157) (width 0.15) (layer "F.Cu") (net 69))
  (segment (start 116.861328 115.222157) (end 117.136328 115.497157) (width 0.15) (layer "F.Cu") (net 69))
  (segment (start 177.136328 101.560008) (end 176.636328 102.060008) (width 0.1) (layer "F.Cu") (net 70))
  (via (at 176.636328 102.060008) (size 0.5) (drill 0.2) (layers "F.Cu" "B.Cu") (net 70))
  (via (at 236.65 88.35) (size 0.5) (drill 0.2) (layers "F.Cu" "B.Cu") (net 70))
  (segment (start 188.15 92.25) (end 188.47 92.57) (width 0.1) (layer "In9.Cu") (net 70))
  (segment (start 188.15 91.802136) (end 188.15 92.25) (width 0.1) (layer "In9.Cu") (net 70))
  (segment (start 188.47 92.57) (end 196.47 92.57) (width 0.1) (layer "In9.Cu") (net 70))
  (segment (start 176.626183 92.476183) (end 176.626183 92.323817) (width 0.1) (layer "In9.Cu") (net 70))
  (segment (start 187.15 90.85) (end 187.15 91.287612) (width 0.1) (layer "In9.Cu") (net 70))
  (segment (start 197.8 93.9) (end 233.3 93.9) (width 0.1) (layer "In9.Cu") (net 70))
  (segment (start 187.412388 91.55) (end 187.897864 91.55) (width 0.1) (layer "In9.Cu") (net 70))
  (segment (start 176.636328 102.060008) (end 176.216328 101.640008) (width 0.1) (layer "In9.Cu") (net 70))
  (segment (start 236.65 90.55) (end 236.65 88.35) (width 0.1) (layer "In9.Cu") (net 70))
  (segment (start 187.897864 91.55) (end 188.15 91.802136) (width 0.1) (layer "In9.Cu") (net 70))
  (segment (start 176.216328 101.640008) (end 176.216328 92.886038) (width 0.1) (layer "In9.Cu") (net 70))
  (segment (start 176.626183 92.323817) (end 178.279992 90.670008) (width 0.1) (layer "In9.Cu") (net 70))
  (segment (start 187.15 91.287612) (end 187.412388 91.55) (width 0.1) (layer "In9.Cu") (net 70))
  (segment (start 233.3 93.9) (end 236.65 90.55) (width 0.1) (layer "In9.Cu") (net 70))
  (segment (start 186.970008 90.670008) (end 187.15 90.85) (width 0.1) (layer "In9.Cu") (net 70))
  (segment (start 196.47 92.57) (end 197.8 93.9) (width 0.1) (layer "In9.Cu") (net 70))
  (segment (start 178.279992 90.670008) (end 186.970008 90.670008) (width 0.1) (layer "In9.Cu") (net 70))
  (segment (start 176.216328 92.886038) (end 176.626183 92.476183) (width 0.1) (layer "In9.Cu") (net 70))
  (segment (start 236.65 93.25) (end 237.95 94.55) (width 0.1) (layer "B.Cu") (net 70))
  (segment (start 236.65 88.35) (end 236.65 93.25) (width 0.1) (layer "B.Cu") (net 70))
  (segment (start 113.474179 111.872157) (end 113.926328 111.872157) (width 0.15) (layer "F.Cu") (net 71))
  (segment (start 112.59918 112.747156) (end 113.474179 111.872157) (width 0.15) (layer "F.Cu") (net 71))
  (segment (start 175.136328 100.560008) (end 174.636328 101.060008) (width 0.1) (layer "F.Cu") (net 72))
  (via (at 174.636328 101.060008) (size 0.5) (drill 0.2) (layers "F.Cu" "B.Cu") (net 72))
  (via (at 235.7 86.8) (size 0.5) (drill 0.2) (layers "F.Cu" "B.Cu") (net 72))
  (segment (start 173.462358 100.480008) (end 173.1 100.11765) (width 0.1) (layer "In9.Cu") (net 72))
  (segment (start 172.216328 92.866328) (end 175.216328 89.866328) (width 0.1) (layer "In9.Cu") (net 72))
  (segment (start 233.553015 89.646985) (end 233.553015 88.146985) (width 0.1) (layer "In9.Cu") (net 72))
  (segment (start 173.1 95.85) (end 172.216328 94.966328) (width 0.1) (layer "In9.Cu") (net 72))
  (segment (start 176.462358 88.640008) (end 191.640008 88.640008) (width 0.1) (layer "In9.Cu") (net 72))
  (segment (start 175.583978 89.866328) (end 176.216328 89.233978) (width 0.1) (layer "In9.Cu") (net 72))
  (segment (start 173.1 100.11765) (end 173.1 95.85) (width 0.1) (layer "In9.Cu") (net 72))
  (segment (start 176.216328 88.886038) (end 176.462358 88.640008) (width 0.1) (layer "In9.Cu") (net 72))
  (segment (start 198.32 90.9) (end 232.3 90.9) (width 0.1) (layer "In9.Cu") (net 72))
  (segment (start 175.216328 89.866328) (end 175.583978 89.866328) (width 0.1) (layer "In9.Cu") (net 72))
  (segment (start 176.216328 89.233978) (end 176.216328 88.886038) (width 0.1) (layer "In9.Cu") (net 72))
  (segment (start 174.636328 101.060008) (end 174.056328 100.480008) (width 0.1) (layer "In9.Cu") (net 72))
  (segment (start 232.3 90.9) (end 233.553015 89.646985) (width 0.1) (layer "In9.Cu") (net 72))
  (segment (start 192.5 89.5) (end 196.92 89.5) (width 0.1) (layer "In9.Cu") (net 72))
  (segment (start 191.640008 88.640008) (end 192.5 89.5) (width 0.1) (layer "In9.Cu") (net 72))
  (segment (start 196.92 89.5) (end 198.32 90.9) (width 0.1) (layer "In9.Cu") (net 72))
  (segment (start 174.056328 100.480008) (end 173.462358 100.480008) (width 0.1) (layer "In9.Cu") (net 72))
  (segment (start 172.216328 94.966328) (end 172.216328 92.866328) (width 0.1) (layer "In9.Cu") (net 72))
  (segment (start 234.9 86.8) (end 235.7 86.8) (width 0.1) (layer "In9.Cu") (net 72))
  (segment (start 233.553015 88.146985) (end 234.9 86.8) (width 0.1) (layer "In9.Cu") (net 72))
  (segment (start 236.12 87.22) (end 236.77 87.22) (width 0.1) (layer "B.Cu") (net 72))
  (segment (start 235.7 86.8) (end 236.12 87.22) (width 0.1) (layer "B.Cu") (net 72))
  (segment (start 237.45 87.9) (end 237.45 88.65) (width 0.1) (layer "B.Cu") (net 72))
  (segment (start 237.45 88.65) (end 237.95 89.15) (width 0.1) (layer "B.Cu") (net 72))
  (segment (start 236.77 87.22) (end 237.45 87.9) (width 0.1) (layer "B.Cu") (net 72))
  (segment (start 126.911328 114.485008) (end 126.911328 117.972157) (width 0.2) (layer "F.Cu") (net 73))
  (segment (start 118.375 113) (end 125.42632 113) (width 0.2) (layer "F.Cu") (net 73))
  (segment (start 117.247157 111.872157) (end 118.375 113) (width 0.2) (layer "F.Cu") (net 73))
  (segment (start 125.42632 113) (end 126.911328 114.485008) (width 0.2) (layer "F.Cu") (net 73))
  (segment (start 114.896328 111.872157) (end 117.247157 111.872157) (width 0.2) (layer "F.Cu") (net 73))
  (segment (start 175.136328 98.560008) (end 174.636328 99.060008) (width 0.1) (layer "F.Cu") (net 74))
  (via (at 174.636328 99.060008) (size 0.5) (drill 0.2) (layers "F.Cu" "B.Cu") (net 74))
  (via (at 236.6 86.8) (size 0.5) (drill 0.2) (layers "F.Cu" "B.Cu") (net 74))
  (segment (start 179.1 89.8) (end 177 89.8) (width 0.1) (layer "In9.Cu") (net 74))
  (segment (start 191.825008 90.450008) (end 188.474784 90.450008) (width 0.1) (layer "In9.Cu") (net 74))
  (segment (start 235.2 89.992) (end 232.842 92.35) (width 0.1) (layer "In9.Cu") (net 74))
  (segment (start 177 89.8) (end 176.15 90.65) (width 0.1) (layer "In9.Cu") (net 74))
  (segment (start 174.056328 95.056328) (end 174.636328 95.636328) (width 0.1) (layer "In9.Cu") (net 74))
  (segment (start 176.15 90.65) (end 176.15 91.140306) (width 0.1) (layer "In9.Cu") (net 74))
  (segment (start 174.636328 95.636328) (end 174.636328 99.060008) (width 0.1) (layer "In9.Cu") (net 74))
  (segment (start 236.6 86.8) (end 235.2 88.2) (width 0.1) (layer "In9.Cu") (net 74))
  (segment (start 196.5 90.8) (end 192.175 90.8) (width 0.1) (layer "In9.Cu") (net 74))
  (segment (start 235.2 88.2) (end 235.2 89.992) (width 0.1) (layer "In9.Cu") (net 74))
  (segment (start 192.175 90.8) (end 191.825008 90.450008) (width 0.1) (layer "In9.Cu") (net 74))
  (segment (start 198.05 92.35) (end 196.5 90.8) (width 0.1) (layer "In9.Cu") (net 74))
  (segment (start 174.056328 93.233978) (end 174.056328 95.056328) (width 0.1) (layer "In9.Cu") (net 74))
  (segment (start 176.15 91.140306) (end 174.056328 93.233978) (width 0.1) (layer "In9.Cu") (net 74))
  (segment (start 188.474784 90.450008) (end 187.924776 89.9) (width 0.1) (layer "In9.Cu") (net 74))
  (segment (start 179.229992 89.670008) (end 179.1 89.8) (width 0.1) (layer "In9.Cu") (net 74))
  (segment (start 232.842 92.35) (end 198.05 92.35) (width 0.1) (layer "In9.Cu") (net 74))
  (segment (start 180.370008 89.670008) (end 179.229992 89.670008) (width 0.1) (layer "In9.Cu") (net 74))
  (segment (start 180.6 89.9) (end 180.370008 89.670008) (width 0.1) (layer "In9.Cu") (net 74))
  (segment (start 187.924776 89.9) (end 180.6 89.9) (width 0.1) (layer "In9.Cu") (net 74))
  (segment (start 236.925 86.475) (end 237.95 86.475) (width 0.1) (layer "B.Cu") (net 74))
  (segment (start 236.6 86.8) (end 236.925 86.475) (width 0.1) (layer "B.Cu") (net 74))
  (segment (start 141.581328 114.157157) (end 141.581328 111.108828) (width 0.15) (layer "F.Cu") (net 75))
  (segment (start 141.581328 115.237157) (end 141.581328 116.527157) (width 0.15) (layer "F.Cu") (net 75))
  (segment (start 141.581328 114.157157) (end 141.581328 115.237157) (width 0.15) (layer "F.Cu") (net 75))
  (segment (start 141.581328 111.108828) (end 141.53 111.0575) (width 0.15) (layer "F.Cu") (net 75))
  (segment (start 138.771328 113.969157) (end 138.771328 115.108157) (width 0.2) (layer "F.Cu") (net 76))
  (segment (start 138.75 113.375) (end 139.53 112.595) (width 0.2) (layer "F.Cu") (net 76))
  (segment (start 139.53 112.595) (end 139.53 111.0575) (width 0.2) (layer "F.Cu") (net 76))
  (segment (start 138.761328 116.497157) (end 138.761328 115.118157) (width 0.2) (layer "F.Cu") (net 76))
  (segment (start 138.75 113.947829) (end 138.75 113.375) (width 0.2) (layer "F.Cu") (net 76))
  (segment (start 172.386328 58.360008) (end 171.836328 58.360008) (width 0.2) (layer "F.Cu") (net 77))
  (segment (start 172.686328 58.660008) (end 172.386328 58.360008) (width 0.2) (layer "F.Cu") (net 77))
  (segment (start 172.686328 59.660008) (end 172.686328 58.660008) (width 0.2) (layer "F.Cu") (net 77))
  (segment (start 195.136328 58.210008) (end 195.636328 58.210008) (width 0.2) (layer "F.Cu") (net 77))
  (segment (start 194.786328 58.560008) (end 195.136328 58.210008) (width 0.2) (layer "F.Cu") (net 77))
  (segment (start 194.786328 59.660008) (end 194.786328 58.560008) (width 0.2) (layer "F.Cu") (net 77))
  (segment (start 170.136328 55.060008) (end 170.136328 56.370006) (width 0.2) (layer "F.Cu") (net 77))
  (segment (start 170.136328 59.660008) (end 170.136328 58.510008) (width 0.2) (layer "F.Cu") (net 77))
  (segment (start 196.836328 58.210008) (end 197.336328 58.210008) (width 0.2) (layer "F.Cu") (net 77))
  (segment (start 196.486328 58.560008) (end 196.836328 58.210008) (width 0.2) (layer "F.Cu") (net 77))
  (segment (start 196.486328 59.660008) (end 196.486328 58.560008) (width 0.2) (layer "F.Cu") (net 77))
  (segment (start 164.186328 59.660008) (end 164.186328 58.510008) (width 0.2) (layer "F.Cu") (net 77))
  (segment (start 189.636328 81.060008) (end 189.655836 81.060008) (width 0.127) (layer "F.Cu") (net 77))
  (segment (start 177.04 63.54) (end 176.14 63.54) (width 0.2) (layer "F.Cu") (net 77))
  (segment (start 190.536328 55.060008) (end 190.536328 56.210008) (width 0.2) (layer "F.Cu") (net 77))
  (segment (start 172.136328 90.560008) (end 172.636328 91.060008) (width 0.2) (layer "F.Cu") (net 77))
  (segment (start 187.986328 55.060008) (end 187.986328 56.210008) (width 0.2) (layer "F.Cu") (net 77))
  (segment (start 192.586328 58.210008) (end 193.086328 58.210008) (width 0.2) (layer "F.Cu") (net 77))
  (segment (start 166.736328 58.660008) (end 166.436328 58.360008) (width 0.2) (layer "F.Cu") (net 77))
  (segment (start 187.636328 85.060008) (end 187.655836 85.060008) (width 0.127) (layer "F.Cu") (net 77))
  (segment (start 175.236328 59.660008) (end 175.236328 58.660008) (width 0.2) (layer "F.Cu") (net 77))
  (segment (start 181.636328 80.060008) (end 181.636328 80.0405) (width 0.127) (layer "F.Cu") (net 77))
  (segment (start 191.136328 77.560008) (end 191.636328 77.060008) (width 0.2) (layer "F.Cu") (net 77))
  (segment (start 175.136328 89.560008) (end 175.636328 90.060008) (width 0.2) (layer "F.Cu") (net 77))
  (segment (start 192.236328 59.660008) (end 192.236328 58.560008) (width 0.2) (layer "F.Cu") (net 77))
  (segment (start 194.636328 86.060008) (end 194.655836 86.060008) (width 0.127) (layer "F.Cu") (net 77))
  (segment (start 170.136328 55.060008) (end 170.136328 56.210008) (width 0.2) (layer "F.Cu") (net 77))
  (segment (start 187.136328 58.560008) (end 187.486328 58.210008) (width 0.2) (layer "F.Cu") (net 77))
  (segment (start 168.436328 58.660008) (end 168.136328 58.360008) (width 0.2) (layer "F.Cu") (net 77))
  (segment (start 185.436328 59.660008) (end 185.436328 58.260008) (width 0.2) (layer "F.Cu") (net 77))
  (segment (start 178.656828 81.042847) (end 178.656828 81.080508) (width 0.127) (layer "F.Cu") (net 77))
  (segment (start 175.236328 62.636328) (end 175.236328 59.660008) (width 0.2) (layer "F.Cu") (net 77))
  (segment (start 164.186328 55.060008) (end 164.186328 56.210008) (width 0.2) (layer "F.Cu") (net 77))
  (segment (start 167.586328 55.060008) (end 167.586328 56.210008) (width 0.2) (layer "F.Cu") (net 77))
  (segment (start 197.336328 55.060008) (end 197.336328 56.210008) (width 0.2) (layer "F.Cu") (net 77))
  (segment (start 182.886328 59.660008) (end 182.886328 58.260008) (width 0.2) (layer "F.Cu") (net 77))
  (segment (start 186.136328 82.560008) (end 186.636328 82.060008) (width 0.2) (layer "F.Cu") (net 77))
  (segment (start 182.136328 80.560008) (end 181.636328 80.060008) (width 0.2) (layer "F.Cu") (net 77))
  (segment (start 177.636328 78.060008) (end 177.636328 78.0405) (width 0.127) (layer "F.Cu") (net 77))
  (segment (start 196.67 82.17) (end 196.526336 82.17) (width 0.127) (layer "F.Cu") (net 77))
  (segment (start 188.636328 78.060008) (end 188.655836 78.060008) (width 0.127) (layer "F.Cu") (net 77))
  (segment (start 178.136328 78.560008) (end 177.636328 78.060008) (width 0.2) (layer "F.Cu") (net 77))
  (segment (start 187.136328 85.560008) (end 187.636328 85.060008) (width 0.2) (layer "F.Cu") (net 77))
  (segment (start 178.136328 88.560008) (end 177.636328 88.060008) (width 0.2) (layer "F.Cu") (net 77))
  (segment (start 171.836328 55.060008) (end 171.836328 56.210008) (width 0.2) (layer "F.Cu") (net 77))
  (segment (start 184.636328 79.060008) (end 184.636328 79.0405) (width 0.127) (layer "F.Cu") (net 77))
  (segment (start 180.84 77.26368) (end 181.136328 77.560008) (width 0.2) (layer "F.Cu") (net 77))
  (segment (start 168.436328 59.660008) (end 168.436328 58.660008) (width 0.2) (layer "F.Cu") (net 77))
  (segment (start 189.136328 81.560008) (end 189.636328 81.060008) (width 0.2) (layer "F.Cu") (net 77))
  (segment (start 171.136328 87.560008) (end 171.669171 88.092851) (width 0.2) (layer "F.Cu") (net 77))
  (segment (start 179.75 84.125) (end 179.789828 84.164828) (width 0.127) (layer "F.Cu") (net 77))
  (segment (start 187.136328 59.660008) (end 187.136328 58.560008) (width 0.2) (layer "F.Cu") (net 77))
  (segment (start 175.236328 58.660008) (end 174.936328 58.360008) (width 0.2) (layer "F.Cu") (net 77))
  (segment (start 187.486328 58.210008) (end 187.986328 58.210008) (width 0.2) (layer "F.Cu") (net 77))
  (segment (start 166.736328 59.660008) (end 166.736328 58.660008) (width 0.2) (layer "F.Cu") (net 77))
  (segment (start 182.886328 55.060008) (end 182.886328 56.210008) (width 0.2) (layer "F.Cu") (net 77))
  (segment (start 176.14 63.54) (end 175.236328 62.636328) (width 0.2) (layer "F.Cu") (net 77))
  (segment (start 175.636328 90.060008) (end 175.636328 91.060008) (width 0.2) (layer "F.Cu") (net 77))
  (segment (start 189.686328 59.660008) (end 189.686328 58.560008) (width 0.2) (layer "F.Cu") (net 77))
  (segment (start 193.086328 55.060008) (end 193.086328 56.210008) (width 0.2) (layer "F.Cu") (net 77))
  (segment (start 195.136328 79.560008) (end 195.636328 79.060008) (width 0.2) (layer "F.Cu") (net 77))
  (segment (start 168.136328 58.360008) (end 167.586328 58.360008) (width 0.2) (layer "F.Cu") (net 77))
  (segment (start 190.62 84.060008) (end 190.639508 84.060008) (width 0.127) (layer "F.Cu") (net 77))
  (segment (start 119.65 82.423) (end 119.65 81.7) (width 0.127) (layer "F.Cu") (net 77))
  (segment (start 189.686328 58.560008) (end 190.036328 58.210008) (width 0.2) (layer "F.Cu") (net 77))
  (segment (start 196.526336 82.17) (end 196.136328 82.560008) (width 0.2) (layer "F.Cu") (net 77))
  (segment (start 181.136328 87.560008) (end 180.636328 88.060008) (width 0.2) (layer "F.Cu") (net 77))
  (segment (start 178.656828 81.080508) (end 179.136328 81.560008) (width 0.2) (layer "F.Cu") (net 77))
  (segment (start 188.136328 78.560008) (end 188.636328 78.060008) (width 0.2) (layer "F.Cu") (net 77))
  (segment (start 173.136328 93.560008) (end 172.636328 94.060008) (width 0.2) (layer "F.Cu") (net 77))
  (segment (start 180.84 76.898) (end 180.84 77.26368) (width 0.2) (layer "F.Cu") (net 77))
  (segment (start 193.636328 83.060008) (end 193.655836 83.060008) (width 0.127) (layer "F.Cu") (net 77))
  (segment (start 192.136328 80.560008) (end 192.636328 80.060008) (width 0.2) (layer "F.Cu") (net 77))
  (segment (start 194.136328 86.560008) (end 194.636328 86.060008) (width 0.2) (layer "F.Cu") (net 77))
  (segment (start 190.036328 58.210008) (end 190.536328 58.210008) (width 0.2) (layer "F.Cu") (net 77))
  (segment (start 166.436328 58.360008) (end 165.886328 58.360008) (width 0.2) (layer "F.Cu") (net 77))
  (segment (start 185.136328 79.560008) (end 184.636328 79.060008) (width 0.2) (layer "F.Cu") (net 77))
  (segment (start 195.636328 79.060008) (end 195.655836 79.060008) (width 0.127) (layer "F.Cu") (net 77))
  (segment (start 174.936328 58.360008) (end 174.386328 58.360008) (width 0.2) (layer "F.Cu") (net 77))
  (segment (start 190.12 84.560008) (end 190.62 84.060008) (width 0.2) (layer "F.Cu") (net 77))
  (segment (start 182.636328 83.060008) (end 182.636328 83.0405) (width 0.127) (layer "F.Cu") (net 77))
  (segment (start 186.636328 82.060008) (end 186.655836 82.060008) (width 0.127) (layer "F.Cu") (net 77))
  (segment (start 185.436328 55.060008) (end 185.436328 56.210008) (width 0.1) (layer "F.Cu") (net 77))
  (segment (start 192.636328 80.060008) (end 192.655836 80.060008) (width 0.127) (layer "F.Cu") (net 77))
  (segment (start 191.636328 77.060008) (end 191.655836 77.060008) (width 0.127) (layer "F.Cu") (net 77))
  (segment (start 193.136328 83.560008) (end 193.636328 83.060008) (width 0.2) (layer "F.Cu") (net 77))
  (segment (start 179.789828 84.213508) (end 180.136328 84.560008) (width 0.2) (layer "F.Cu") (net 77))
  (segment (start 174.386328 55.060008) (end 174.386328 56.210008) (width 0.2) (layer "F.Cu") (net 77))
  (segment (start 192.236328 58.560008) (end 192.586328 58.210008) (width 0.2) (layer "F.Cu") (net 77))
  (segment (start 183.136328 83.560008) (end 182.636328 83.060008) (width 0.2) (layer "F.Cu") (net 77))
  (segment (start 195.636328 55.060008) (end 195.636328 56.210008) (width 0.2) (layer "F.Cu") (net 77))
  (segment (start 179.789828 84.164828) (end 179.789828 84.213508) (width 0.127) (layer "F.Cu") (net 77))
  (segment (start 165.886328 55.060008) (end 165.886328 56.210008) (width 0.2) (layer "F.Cu") (net 77))
  (via (at 118.136328 77.810008) (size 0.5) (drill 0.2) (layers "F.Cu" "B.Cu") (net 77))
  (via (at 119.636328 77.810008) (size 0.5) (drill 0.2) (layers "F.Cu" "B.Cu") (net 77))
  (via (at 121.136328 77.810008) (size 0.5) (drill 0.2) (layers "F.Cu" "B.Cu") (net 77))
  (via (at 118.136328 79.310008) (size 0.5) (drill 0.2) (layers "F.Cu" "B.Cu") (net 77))
  (via (at 119.636328 79.310008) (size 0.5) (drill 0.2) (layers "F.Cu" "B.Cu") (net 77))
  (via (at 121.136328 79.310008) (size 0.5) (drill 0.2) (layers "F.Cu" "B.Cu") (net 77))
  (via (at 118.136328 80.810008) (size 0.5) (drill 0.2) (layers "F.Cu" "B.Cu") (net 77))
  (via (at 121.136328 80.810008) (size 0.5) (drill 0.2) (layers "F.Cu" "B.Cu") (net 77))
  (via (at 118.886328 78.560008) (size 0.5) (drill 0.2) (layers "F.Cu" "B.Cu") (net 77))
  (via (at 120.386328 78.560008) (size 0.5) (drill 0.2) (layers "F.Cu" "B.Cu") (net 77))
  (via (at 117.386328 80.060008) (size 0.5) (drill 0.2) (layers "F.Cu" "B.Cu") (net 77))
  (via (at 118.886328 80.060008) (size 0.5) (drill 0.2) (layers "F.Cu" "B.Cu") (net 77))
  (via (at 120.386328 80.060008) (size 0.5) (drill 0.2) (layers "F.Cu" "B.Cu") (net 77))
  (via (at 171.836328 58.360008) (size 0.5) (drill 0.2) (layers "F.Cu" "B.Cu") (net 77))
  (via (at 195.636328 58.210008) (size 0.5) (drill 0.2) (layers "F.Cu" "B.Cu") (net 77))
  (via (at 170.136328 58.510008) (size 0.5) (drill 0.2) (layers "F.Cu" "B.Cu") (net 77))
  (via (at 197.336328 58.210008) (size 0.5) (drill 0.2) (layers "F.Cu" "B.Cu") (net 77))
  (via (at 117.386328 78.560008) (size 0.5) (drill 0.2) (layers "F.Cu" "B.Cu") (net 77))
  (via (at 194.655836 86.060008) (size 0.5) (drill 0.2) (layers "F.Cu" "B.Cu") (net 77))
  (via (at 185.436328 58.260008) (size 0.5) (drill 0.2) (layers "F.Cu" "B.Cu") (net 77))
  (via (at 180.84 76.898) (size 0.5) (drill 0.2) (layers "F.Cu" "B.Cu") (net 77))
  (via (at 170.136328 56.210008) (size 0.5) (drill 0.2) (layers "F.Cu" "B.Cu") (net 77))
  (via (at 182.886328 58.260008) (size 0.5) (drill 0.2) (layers "F.Cu" "B.Cu") (net 77))
  (via (at 174.386328 56.210008) (size 0.5) (drill 0.2) (layers "F.Cu" "B.Cu") (net 77))
  (via (at 187.655836 85.060008) (size 0.5) (drill 0.2) (layers "F.Cu" "B.Cu") (net 77))
  (via (at 178.656828 81.042847) (size 0.5) (drill 0.2) (layers "F.Cu" "B.Cu") (net 77))
  (via (at 179.75 84.125) (size 0.5) (drill 0.2) (layers "F.Cu" "B.Cu") (net 77))
  (via (at 193.086328 58.210008) (size 0.5) (drill 0.2) (layers "F.Cu" "B.Cu") (net 77))
  (via (at 164.186328 56.210008) (size 0.5) (drill 0.2) (layers "F.Cu" "B.Cu") (net 77))
  (via (at 172.636328 91.060008) (size 0.5) (drill 0.2) (layers "F.Cu" "B.Cu") (net 77))
  (via (at 180.636328 88.060008) (size 0.5) (drill 0.2) (layers "F.Cu" "B.Cu") (net 77))
  (via (at 167.586328 58.360008) (size 0.5) (drill 0.2) (layers "F.Cu" "B.Cu") (net 77))
  (via (at 197.336328 56.210008) (size 0.5) (drill 0.2) (layers "F.Cu" "B.Cu") (net 77))
  (via (at 177.636328 78.0405) (size 0.5) (drill 0.2) (layers "F.Cu" "B.Cu") (net 77))
  (via (at 190.536328 58.210008) (size 0.5) (drill 0.2) (layers "F.Cu" "B.Cu") (net 77))
  (via (at 184.636328 79.0405) (size 0.5) (drill 0.2) (layers "F.Cu" "B.Cu") (net 77))
  (via (at 172.636328 94.060008) (size 0.5) (drill 0.2) (layers "F.Cu" "B.Cu") (net 77))
  (via (at 174.386328 58.360008) (size 0.5) (drill 0.2) (layers "F.Cu" "B.Cu") (net 77))
  (via (at 196.67 82.17) (size 0.5) (drill 0.2) (layers "F.Cu" "B.Cu") (net 77))
  (via (at 190.536328 56.210008) (size 0.5) (drill 0.2) (layers "F.Cu" "B.Cu") (net 77))
  (via (at 186.655836 82.060008) (size 0.5) (drill 0.2) (layers "F.Cu" "B.Cu") (net 77))
  (via (at 190.639508 84.060008) (size 0.5) (drill 0.2) (layers "F.Cu" "B.Cu") (net 77))
  (via (at 165.886328 56.210008) (size 0.5) (drill 0.2) (layers "F.Cu" "B.Cu") (net 77))
  (via (at 188.655836 78.060008) (size 0.5) (drill 0.2) (layers "F.Cu" "B.Cu") (net 77))
  (via (at 175.636328 91.060008) (size 0.5) (drill 0.2) (layers "F.Cu" "B.Cu") (net 77))
  (via (at 187.986328 58.210008) (size 0.5) (drill 0.2) (layers "F.Cu" "B.Cu") (net 77))
  (via (at 171.836328 56.210008) (size 0.5) (drill 0.2) (layers "F.Cu" "B.Cu") (net 77))
  (via (at 191.655836 77.060008) (size 0.5) (drill 0.2) (layers "F.Cu" "B.Cu") (net 77))
  (via (at 164.186328 58.510008) (size 0.5) (drill 0.2) (layers "F.Cu" "B.Cu") (net 77))
  (via (at 195.655836 79.060008) (size 0.5) (drill 0.2) (layers "F.Cu" "B.Cu") (net 77))
  (via (at 181.636328 80.0405) (size 0.5) (drill 0.2) (layers "F.Cu" "B.Cu") (net 77))
  (via (at 167.586328 56.210008) (size 0.5) (drill 0.2) (layers "F.Cu" "B.Cu") (net 77))
  (via (at 182.636328 83.0405) (size 0.5) (drill 0.2) (layers "F.Cu" "B.Cu") (net 77))
  (via (at 187.986328 56.210008) (size 0.5) (drill 0.2) (layers "F.Cu" "B.Cu") (net 77))
  (via (at 195.636328 56.210008) (size 0.5) (drill 0.2) (layers "F.Cu" "B.Cu") (net 77))
  (via (at 192.655836 80.060008) (size 0.5) (drill 0.2) (layers "F.Cu" "B.Cu") (net 77))
  (via (at 171.669171 88.092851) (size 0.5) (drill 0.2) (layers "F.Cu" "B.Cu") (net 77))
  (via (at 193.086328 56.210008) (size 0.5) (drill 0.2) (layers "F.Cu" "B.Cu") (net 77))
  (via (at 193.655836 83.060008) (size 0.5) (drill 0.2) (layers "F.Cu" "B.Cu") (net 77))
  (via (at 189.655836 81.060008) (size 0.5) (drill 0.2) (layers "F.Cu" "B.Cu") (net 77))
  (via (at 177.636328 88.060008) (size 0.5) (drill 0.2) (layers "F.Cu" "B.Cu") (net 77))
  (via (at 182.886328 56.210008) (size 0.5) (drill 0.2) (layers "F.Cu" "B.Cu") (net 77))
  (via (at 165.886328 58.360008) (size 0.5) (drill 0.2) (layers "F.Cu" "B.Cu") (net 77))
  (via (at 185.436328 56.210008) (size 0.5) (drill 0.2) (layers "F.Cu" "B.Cu") (net 77))
  (segment (start 171.88 88.65) (end 171.8 88.57) (width 0.2) (layer "B.Cu") (net 77))
  (segment (start 179.75 84.125) (end 179.925 83.95) (width 0.2) (layer "B.Cu") (net 77))
  (segment (start 187.986328 56.210008) (end 187.986328 55.245008) (width 0.2) (layer "B.Cu") (net 77))
  (segment (start 179.936328 88.260008) (end 179.936328 88.193672) (width 0.2) (layer "B.Cu") (net 77))
  (segment (start 198.247 55.918) (end 198.247 51.32) (width 0.2) (layer "B.Cu") (net 77))
  (segment (start 195.636328 78.330008) (end 195.636328 79.0405) (width 0.2) (layer "B.Cu") (net 77))
  (segment (start 242.3 51.003) (end 245.627 47.676) (width 0.2) (layer "B.Cu") (net 77))
  (segment (start 181.405 77.463) (end 181.405 77.475) (width 0.2) (layer "B.Cu") (net 77))
  (segment (start 189.779928 58.436208) (end 190.310128 58.436208) (width 0.2) (layer "B.Cu") (net 77))
  (segment (start 191.655836 77.060008) (end 191.655836 77.075836) (width 0.127) (layer "B.Cu") (net 77))
  (segment (start 182.886328 56.210008) (end 182.886328 55.245008) (width 0.2) (layer "B.Cu") (net 77))
  (segment (start 167.586328 58.025008) (end 167.951328 57.660008) (width 0.2) (layer "B.Cu") (net 77))
  (segment (start 190.310008 84.060008) (end 190.639508 84.060008) (width 0.2) (layer "B.Cu") (net 77))
  (segment (start 179.275 80.424675) (end 178.656828 81.042847) (width 0.2) (layer "B.Cu") (net 77))
  (segment (start 194.2 82.515844) (end 193.655836 83.060008) (width 0.2) (layer "B.Cu") (net 77))
  (segment (start 165.886328 56.210008) (end 165.886328 55.545008) (width 0.2) (layer "B.Cu") (net 77))
  (segment (start 195.636328 56.210008) (end 195.636328 55.255008) (width 0.2) (layer "B.Cu") (net 77))
  (segment (start 181.3 78.975) (end 181.3 79.704172) (width 0.2) (layer "B.Cu") (net 77))
  (segment (start 165.886328 57.975008) (end 165.521328 57.610008) (width 0.2) (layer "B.Cu") (net 77))
  (segment (start 175.636328 90.563672) (end 175.636328 91.060008) (width 0.2) (layer "B.Cu") (net 77))
  (segment (start 177.575 87.99868) (end 177.636328 88.060008) (width 0.2) (layer "B.Cu") (net 77))
  (segment (start 193.311328 79.605008) (end 193.110836 79.605008) (width 0.2) (layer "B.Cu") (net 77))
  (segment (start 167.586328 56.210008) (end 167.586328 55.545008) (width 0.2) (layer "B.Cu") (net 77))
  (segment (start 194.5 79.35) (end 194.4 79.35) (width 0.2) (layer "B.Cu") (net 77))
  (segment (start 197.336328 58.621328) (end 197.715 59) (width 0.2) (layer "B.Cu") (net 77))
  (segment (start 174.386328 58.360008) (end 174.386328 58.075008) (width 0.2) (layer "B.Cu") (net 77))
  (segment (start 196.11 82.73) (end 196.67 82.17) (width 0.2) (layer "B.Cu") (net 77))
  (segment (start 192.860128 58.436208) (end 193.086328 58.210008) (width 0.2) (layer "B.Cu") (net 77))
  (segment (start 197.336328 56.210008) (end 197.954992 56.210008) (width 0.2) (layer "B.Cu") (net 77))
  (segment (start 198.564 51.003) (end 242.3 51.003) (width 0.2) (layer "B.Cu") (net 77))
  (segment (start 182.886328 58.812408) (end 182.886328 58.260008) (width 0.2) (layer "B.Cu") (net 77))
  (segment (start 182.056328 82.410008) (end 182.056328 82.4605) (width 0.2) (layer "B.Cu") (net 77))
  (segment (start 195.365844 79.35) (end 195.655836 79.060008) (width 0.2) (layer "B.Cu") (net 77))
  (segment (start 171.8 88.57) (end 171.8 88.22368) (width 0.2) (layer "B.Cu") (net 77))
  (segment (start 187.75 77.975) (end 188.570828 77.975) (width 0.2) (layer "B.Cu") (net 77))
  (segment (start 170.136328 59.175008) (end 170.136328 58.510008) (width 0.2) (layer "B.Cu") (net 77))
  (segment (start 173.33 94.65) (end 173.22632 94.65) (width 0.2) (layer "B.Cu") (net 77))
  (segment (start 194.5 79.35) (end 194.375 79.35) (width 0.2) (layer "B.Cu") (net 77))
  (segment (start 172.636328 91.060008) (end 172.6 91.02368) (width 0.2) (layer "B.Cu") (net 77))
  (segment (start 164.186328 59.175008) (end 164.186328 58.510008) (width 0.2) (layer "B.Cu") (net 77))
  (segment (start 188.56 84.89) (end 187.825844 84.89) (width 0.4) (layer "B.Cu") (net 77))
  (segment (start 177.7655 78.0405) (end 177.636328 78.0405) (width 0.2) (layer "B.Cu") (net 77))
  (segment (start 180.106328 89.461328) (end 180.106328 88.430008) (width 0.2) (layer "B.Cu") (net 77))
  (segment (start 171.836328 56.210008) (end 171.836328 55.545008) (width 0.2) (layer "B.Cu") (net 77))
  (segment (start 178.33 78.55) (end 178.275 78.55) (width 0.2) (layer "B.Cu") (net 77))
  (segment (start 191.655836 77.075836) (end 192.18 77.6) (width 0.2) (layer "B.Cu") (net 77))
  (segment (start 195.636328 79.0405) (end 195.655836 79.060008) (width 0.2) (layer "B.Cu") (net 77))
  (segment (start 197.336328 56.210008) (end 197.336328 55.245008) (width 0.2) (layer "B.Cu") (net 77))
  (segment (start 192.091328 58.436208) (end 192.860128 58.436208) (width 0.2) (layer "B.Cu") (net 77))
  (segment (start 186.955 82.07) (end 187.5 81.525) (width 0.2) (layer "B.Cu") (net 77))
  (segment (start 174.386328 56.210008) (end 174.386328 55.545008) (width 0.2) (layer "B.Cu") (net 77))
  (segment (start 194.5 79.35) (end 195.365844 79.35) (width 0.2) (layer "B.Cu") (net 77))
  (segment (start 189.8 80.32) (end 189.8 80.915844) (width 0.2) (layer "B.Cu") (net 77))
  (segment (start 164.186328 56.210008) (end 164.186328 55.545008) (width 0.2) (layer "B.Cu") (net 77))
  (segment (start 190.310128 58.436208) (end 190.536328 58.210008) (width 0.2) (layer "B.Cu") (net 77))
  (segment (start 194.732928 58.436208) (end 195.410128 58.436208) (width 0.2) (layer "B.Cu") (net 77))
  (segment (start 189.295828 78.7) (end 188.655836 78.060008) (width 0.2) (layer "B.Cu") (net 77))
  (segment (start 175.75 90.45) (end 175.636328 90.563672) (width 0.2) (layer "B.Cu") (net 77))
  (segment (start 182.28 80.65) (end 182.245828 80.65) (width 0.2) (layer "B.Cu") (net 77))
  (segment (start 165.886328 58.360008) (end 165.886328 57.975008) (width 0.2) (layer "B.Cu") (net 77))
  (segment (start 170.136328 56.210008) (end 170.136328 55.545008) (width 0.2) (layer "B.Cu") (net 77))
  (segment (start 185.436328 56.210008) (end 185.436328 55.245008) (width 0.2) (layer "B.Cu") (net 77))
  (segment (start 186.655836 82.060008) (end 186.665828 82.07) (width 0.2) (layer "B.Cu") (net 77))
  (segment (start 194.075 85.575) (end 194.560008 86.060008) (width 0.2) (layer "B.Cu") (net 77))
  (segment (start 180.069992 88.060008) (end 180.636328 88.060008) (width 0.2) (layer "B.Cu") (net 77))
  (segment (start 180.84 76.898) (end 181.405 77.463) (width 0.2) (layer "B.Cu") (net 77))
  (segment (start 193.97 85.575) (end 194.075 85.575) (width 0.2) (layer "B.Cu") (net 77))
  (segment (start 179.936328 88.193672) (end 180.069992 88.060008) (width 0.2) (layer "B.Cu") (net 77))
  (segment (start 189.725 83.475) (end 190.310008 84.060008) (width 0.2) (layer "B.Cu") (net 77))
  (segment (start 171.8 88.22368) (end 171.669171 88.092851) (width 0.2) (layer "B.Cu") (net 77))
  (segment (start 194.119992 79.605008) (end 193.311328 79.605008) (width 0.2) (layer "B.Cu") (net 77))
  (segment (start 182.056328 82.4605) (end 182.636328 83.0405) (width 0.2) (layer "B.Cu") (net 77))
  (segment (start 178.275 78.55) (end 177.7655 78.0405) (width 0.2) (layer "B.Cu") (net 77))
  (segment (start 181.3 79.704172) (end 181.636328 80.0405) (width 0.2) (layer "B.Cu") (net 77))
  (segment (start 197.336328 58.210008) (end 197.336328 58.621328) (width 0.2) (layer "B.Cu") (net 77))
  (segment (start 198.247 51.32) (end 198.564 51.003) (width 0.2) (layer "B.Cu") (net 77))
  (segment (start 189.8 80.915844) (end 189.655836 81.060008) (width 0.2) (layer "B.Cu") (net 77))
  (segment (start 193.086328 56.210008) (end 193.086328 55.245008) (width 0.2) (layer "B.Cu") (net 77))
  (segment (start 172.6 91.02368) (end 172.71868 90.905) (width 0.2) (layer "B.Cu") (net 77))
  (segment (start 197.954992 56.210008) (end 198.247 55.918) (width 0.2) (layer "B.Cu") (net 77))
  (segment (start 195.410128 58.436208) (end 195.636328 58.210008) (width 0.2) (layer "B.Cu") (net 77))
  (segment (start 174.386328 58.075008) (end 174.021328 57.710008) (width 0.2) (layer "B.Cu") (net 77))
  (segment (start 188.570828 77.975) (end 188.655836 78.060008) (width 0.2) (layer "B.Cu") (net 77))
  (segment (start 196 82.73) (end 196.11 82.73) (width 0.2) (layer "B.Cu") (net 77))
  (segment (start 190.886328 83.380008) (end 190.886328 83.813188) (width 0.2) (layer "B.Cu") (net 77))
  (segment (start 177.575 87.42) (end 177.575 87.99868) (width 0.2) (layer "B.Cu") (net 77))
  (segment (start 182.245828 80.65) (end 181.636328 80.0405) (width 0.2) (layer "B.Cu") (net 77))
  (segment (start 186.665828 82.07) (end 186.955 82.07) (width 0.2) (layer "B.Cu") (net 77))
  (segment (start 171.836328 59.175008) (end 171.836328 58.360008) (width 0.2) (layer "B.Cu") (net 77))
  (segment (start 190.536328 56.210008) (end 190.536328 55.245008) (width 0.2) (layer "B.Cu") (net 77))
  (segment (start 179.275 80.395) (end 179.275 80.424675) (width 0.2) (layer "B.Cu") (net 77))
  (segment (start 190.886328 83.813188) (end 190.639508 84.060008) (width 0.2) (layer "B.Cu") (net 77))
  (segment (start 194.560008 86.060008) (end 194.655836 86.060008) (width 0.2) (layer "B.Cu") (net 77))
  (segment (start 187.825844 84.89) (end 187.655836 85.060008) (width 0.4) (layer "B.Cu") (net 77))
  (segment (start 180.106328 88.430008) (end 179.936328 88.260008) (width 0.2) (layer "B.Cu") (net 77))
  (segment (start 184.4 79.83) (end 184.4 79.276828) (width 0.2) (layer "B.Cu") (net 77))
  (segment (start 175.755 90.45) (end 175.75 90.45) (width 0.2) (layer "B.Cu") (net 77))
  (segment (start 180.25 89.605) (end 180.106328 89.461328) (width 0.2) (layer "B.Cu") (net 77))
  (segment (start 187.189128 58.436208) (end 187.760128 58.436208) (width 0.2) (layer "B.Cu") (net 77))
  (segment (start 187.5 81.525) (end 187.5 81.52) (width 0.2) (layer "B.Cu") (net 77))
  (segment (start 194.375 79.35) (end 194.119992 79.605008) (width 0.2) (layer "B.Cu") (net 77))
  (segment (start 187.760128 58.436208) (end 187.986328 58.210008) (width 0.2) (layer "B.Cu") (net 77))
  (segment (start 173.22632 94.65) (end 172.636328 94.060008) (width 0.2) (layer "B.Cu") (net 77))
  (segment (start 245.627 47.676) (end 246.688 47.676) (width 0.2) (layer "B.Cu") (net 77))
  (segment (start 189.38 78.7) (end 189.295828 78.7) (width 0.2) (layer "B.Cu") (net 77))
  (segment (start 184.4 79.276828) (end 184.636328 79.0405) (width 0.2) (layer "B.Cu") (net 77))
  (segment (start 179.925 83.95) (end 179.925 83.37) (width 0.2) (layer "B.Cu") (net 77))
  (segment (start 194.2 82.37) (end 194.2 82.515844) (width 0.2) (layer "B.Cu") (net 77))
  (segment (start 172.71868 90.905) (end 173.225 90.905) (width 0.2) (layer "B.Cu") (net 77))
  (segment (start 193.110836 79.605008) (end 192.655836 80.060008) (width 0.2) (layer "B.Cu") (net 77))
  (segment (start 167.586328 58.360008) (end 167.586328 58.025008) (width 0.2) (layer "B.Cu") (net 77))
  (segment (start 185.436328 58.260008) (end 184.850728 58.260008) (width 0.2) (layer "B.Cu") (net 77))
  (segment (start 250.95 83.1) (end 250.95 84.74) (width 0.2) (layer "F.Cu") (net 78))
  (segment (start 250.95 84.74) (end 250.97 84.76) (width 0.2) (layer "F.Cu") (net 78))
  (via (at 242.6 84.5) (size 0.5) (drill 0.2) (layers "F.Cu" "B.Cu") (net 78))
  (via (at 250.97 84.76) (size 0.5) (drill 0.2) (layers "F.Cu" "B.Cu") (net 78))
  (segment (start 242.6 84.5) (end 243 84.1) (width 0.2) (layer "In7.Cu") (net 78))
  (segment (start 250.31 84.1) (end 250.97 84.76) (width 0.2) (layer "In7.Cu") (net 78))
  (segment (start 243 84.1) (end 250.31 84.1) (width 0.2) (layer "In7.Cu") (net 78))
  (segment (start 241.985 84.5) (end 242.6 84.5) (width 0.2) (layer "B.Cu") (net 78))
  (segment (start 172.136328 101.560008) (end 171.636328 102.060008) (width 0.1) (layer "F.Cu") (net 79))
  (segment (start 220.787 112.382) (end 221.803 112.382) (width 0.1) (layer "F.Cu") (net 79))
  (segment (start 220.787 112.382) (end 219.64234 112.382) (width 0.1) (layer "F.Cu") (net 79))
  (segment (start 221.9342 112.2508) (end 223.5 112.2508) (width 0.1) (layer "F.Cu") (net 79))
  (segment (start 219.64234 112.382) (end 219.614328 112.410012) (width 0.1) (layer "F.Cu") (net 79))
  (via (at 171.636328 102.060008) (size 0.5) (drill 0.2) (layers "F.Cu" "B.Cu") (net 79))
  (via (at 219.614328 112.410012) (size 0.5) (drill 0.2) (layers "F.Cu" "B.Cu") (net 79))
  (segment (start 218.157452 109.560008) (end 219.641949 111.044504) (width 0.1) (layer "In9.Cu") (net 79))
  (segment (start 219.641949 111.044504) (end 219.641949 112.394508) (width 0.1) (layer "In9.Cu") (net 79))
  (segment (start 190.960008 109.560008) (end 218.157452 109.560008) (width 0.1) (layer "In9.Cu") (net 79))
  (segment (start 187 105.6) (end 190.960008 109.560008) (width 0.1) (layer "In9.Cu") (net 79))
  (segment (start 171.136328 103.986328) (end 172.75 105.6) (width 0.1) (layer "In9.Cu") (net 79))
  (segment (start 172.75 105.6) (end 187 105.6) (width 0.1) (layer "In9.Cu") (net 79))
  (segment (start 171.636328 102.060008) (end 171.136328 102.560008) (width 0.1) (layer "In9.Cu") (net 79))
  (segment (start 171.136328 102.560008) (end 171.136328 103.986328) (width 0.1) (layer "In9.Cu") (net 79))
  (segment (start 134.211328 115.522157) (end 134.211328 114.197157) (width 0.1) (layer "F.Cu") (net 80))
  (segment (start 133 115.516) (end 133.003843 115.512157) (width 0.2) (layer "F.Cu") (net 80))
  (segment (start 135.286338 113.122147) (end 137.661338 113.122147) (width 0.1) (layer "F.Cu") (net 80))
  (segment (start 134.211328 114.197157) (end 135.286338 113.122147) (width 0.1) (layer "F.Cu") (net 80))
  (segment (start 133.003843 115.512157) (end 134.201328 115.512157) (width 0.2) (layer "F.Cu") (net 80))
  (segment (start 138.53 112.253485) (end 138.53 111.0575) (width 0.1) (layer "F.Cu") (net 80))
  (segment (start 137.661338 113.122147) (end 138.53 112.253485) (width 0.1) (layer "F.Cu") (net 80))
  (segment (start 135.161328 116.872157) (end 135.161328 113.997157) (width 0.1) (layer "F.Cu") (net 81))
  (segment (start 139.03 112.378485) (end 139.03 111.0575) (width 0.1) (layer "F.Cu") (net 81))
  (segment (start 137.536328 117.857157) (end 136.046328 117.857157) (width 0.2) (layer "F.Cu") (net 81))
  (segment (start 136.011328 117.722157) (end 135.161328 116.872157) (width 0.1) (layer "F.Cu") (net 81))
  (segment (start 138.036328 113.372157) (end 139.03 112.378485) (width 0.1) (layer "F.Cu") (net 81))
  (segment (start 135.786328 113.372157) (end 138.036328 113.372157) (width 0.1) (layer "F.Cu") (net 81))
  (segment (start 135.161328 113.997157) (end 135.786328 113.372157) (width 0.1) (layer "F.Cu") (net 81))
  (segment (start 189.136328 97.560008) (end 189.636328 98.060008) (width 0.1) (layer "F.Cu") (net 82))
  (segment (start 138.35 120.125) (end 138.35 120.84) (width 0.2) (layer "F.Cu") (net 82))
  (via blind (at 189.636328 98.060008) (size 0.5) (drill 0.2) (layers "F.Cu" "In5.Cu") (net 82))
  (via (at 138.35 120.125) (size 0.5) (drill 0.2) (layers "F.Cu" "B.Cu") (net 82))
  (segment (start 190.175 102.115306) (end 189.7 102.590306) (width 0.1) (layer "In2.Cu") (net 82))
  (segment (start 189.062702 105.437298) (end 189.53989 105.914486) (width 0.1) (layer "In2.Cu") (net 82))
  (segment (start 187.630975 106.232847) (end 187.630864 106.232957) (width 0.1) (layer "In2.Cu") (net 82))
  (segment (start 179.05 107.95) (end 171.4 115.6) (width 0.1) (layer "In2.Cu") (net 82))
  (segment (start 187.630864 106.551045) (end 188.267098 107.187278) (width 0.1) (layer "In2.Cu") (net 82))
  (segment (start 189.221912 104.96) (end 189.221911 104.959999) (width 0.1) (layer "In2.Cu") (net 82))
  (segment (start 188.903823 104.959999) (end 188.903712 104.960109) (width 0.1) (layer "In2.Cu") (net 82))
  (segment (start 189.7 102.590306) (end 189.7 104.8) (width 0.1) (layer "In2.Cu") (net 82))
  (segment (start 189.636328 98.060008) (end 190.056328 98.480008) (width 0.1) (layer "In2.Cu") (net 82))
  (segment (start 138.475 120) (end 138.35 120.125) (width 0.1) (layer "In2.Cu") (net 82))
  (segment (start 171.4 115.6) (end 151.2 115.6) (width 0.1) (layer "In2.Cu") (net 82))
  (segment (start 190.056328 99.256328) (end 190.25 99.45) (width 0.1) (layer "In2.Cu") (net 82))
  (segment (start 186.994468 107.505529) (end 186.55 107.95) (width 0.1) (layer "In2.Cu") (net 82))
  (segment (start 151.2 115.6) (end 146.8 120) (width 0.1) (layer "In2.Cu") (net 82))
  (segment (start 190.175 100.835) (end 190.175 102.115306) (width 0.1) (layer "In2.Cu") (net 82))
  (segment (start 188.585296 106.86908) (end 187.949063 106.232847) (width 0.1) (layer "In2.Cu") (net 82))
  (segment (start 188.903712 105.278197) (end 189.062756 105.437241) (width 0.1) (layer "In2.Cu") (net 82))
  (segment (start 186.55 107.95) (end 179.05 107.95) (width 0.1) (layer "In2.Cu") (net 82))
  (segment (start 146.8 120) (end 138.475 120) (width 0.1) (layer "In2.Cu") (net 82))
  (segment (start 189.7 104.8) (end 189.54 104.96) (width 0.1) (layer "In2.Cu") (net 82))
  (segment (start 189.221692 106.232684) (end 188.585459 105.596451) (width 0.1) (layer "In2.Cu") (net 82))
  (segment (start 188.267371 105.596451) (end 188.26726 105.596561) (width 0.1) (layer "In2.Cu") (net 82))
  (segment (start 190.25 99.45) (end 190.25 100.76) (width 0.1) (layer "In2.Cu") (net 82))
  (segment (start 190.25 100.76) (end 190.175 100.835) (width 0.1) (layer "In2.Cu") (net 82))
  (segment (start 186.994579 106.869243) (end 186.994468 106.869353) (width 0.1) (layer "In2.Cu") (net 82))
  (segment (start 189.062756 105.437241) (end 189.062702 105.437298) (width 0.1) (layer "In2.Cu") (net 82))
  (segment (start 188.26726 105.914649) (end 188.903494 106.550882) (width 0.1) (layer "In2.Cu") (net 82))
  (segment (start 190.056328 98.480008) (end 190.056328 99.256328) (width 0.1) (layer "In2.Cu") (net 82))
  (segment (start 187.9489 107.505476) (end 187.312667 106.869243) (width 0.1) (layer "In2.Cu") (net 82))
  (arc (start 189.221911 104.959999) (mid 189.062867 104.894121) (end 188.903823 104.959999) (width 0.1) (layer "In2.Cu") (net 82))
  (arc (start 189.54 104.96) (mid 189.380956 105.025878) (end 189.221912 104.96) (width 0.1) (layer "In2.Cu") (net 82))
  (arc (start 187.949063 106.232847) (mid 187.790019 106.166969) (end 187.630975 106.232847) (width 0.1) (layer "In2.Cu") (net 82))
  (arc (start 188.267098 107.505476) (mid 188.107999 107.571377) (end 187.9489 107.505476) (width 0.1) (layer "In2.Cu") (net 82))
  (arc (start 189.53989 106.232684) (mid 189.380791 106.298585) (end 189.221692 106.232684) (width 0.1) (layer "In2.Cu") (net 82))
  (arc (start 188.903494 106.86908) (mid 188.744395 106.934981) (end 188.585296 106.86908) (width 0.1) (layer "In2.Cu") (net 82))
  (arc (start 186.994468 106.869353) (mid 186.92859 107.028397) (end 186.994468 107.187441) (width 0.1) (layer "In2.Cu") (net 82))
  (arc (start 188.585459 105.596451) (mid 188.426415 105.530573) (end 188.267371 105.596451) (width 0.1) (layer "In2.Cu") (net 82))
  (arc (start 187.312667 106.869243) (mid 187.153623 106.803365) (end 186.994579 106.869243) (width 0.1) (layer "In2.Cu") (net 82))
  (arc (start 189.53989 105.914486) (mid 189.605791 106.073585) (end 189.53989 106.232684) (width 0.1) (layer "In2.Cu") (net 82))
  (arc (start 188.267098 107.187278) (mid 188.332999 107.346377) (end 188.267098 107.505476) (width 0.1) (layer "In2.Cu") (net 82))
  (arc (start 188.903494 106.550882) (mid 188.969395 106.709981) (end 188.903494 106.86908) (width 0.1) (layer "In2.Cu") (net 82))
  (arc (start 188.26726 105.596561) (mid 188.201382 105.755605) (end 188.26726 105.914649) (width 0.1) (layer "In2.Cu") (net 82))
  (arc (start 188.903712 104.960109) (mid 188.837834 105.119153) (end 188.903712 105.278197) (width 0.1) (layer "In2.Cu") (net 82))
  (arc (start 187.630864 106.232957) (mid 187.564986 106.392001) (end 187.630864 106.551045) (width 0.1) (layer "In2.Cu") (net 82))
  (arc (start 186.994468 107.187441) (mid 187.060346 107.346485) (end 186.994468 107.505529) (width 0.1) (layer "In2.Cu") (net 82))
  (segment (start 138.4 120.175) (end 138.4 121.45) (width 0.1) (layer "B.Cu") (net 82))
  (segment (start 138.35 120.125) (end 138.4 120.175) (width 0.1) (layer "B.Cu") (net 82))
  (segment (start 187.136328 98.560008) (end 187.636328 99.060008) (width 0.1) (layer "F.Cu") (net 83))
  (segment (start 137.325 120.1) (end 137.325 120.83) (width 0.2) (layer "F.Cu") (net 83))
  (via blind (at 187.636328 99.060008) (size 0.5) (drill 0.2) (layers "F.Cu" "In5.Cu") (net 83))
  (via (at 137.325 120.1) (size 0.5) (drill 0.2) (layers "F.Cu" "B.Cu") (net 83))
  (segment (start 189.02 103.33) (end 189.02 103.58) (width 0.1) (layer "In2.Cu") (net 83))
  (segment (start 188.47 104.18) (end 188.82 104.18) (width 0.1) (layer "In2.Cu") (net 83))
  (segment (start 189.72029 99.55) (end 190.036328 99.866038) (width 0.1) (layer "In2.Cu") (net 83))
  (segment (start 137.83 119.595) (end 137.325 120.1) (width 0.1) (layer "In2.Cu") (net 83))
  (segment (start 188.275 98.875) (end 188.675 98.875) (width 0.1) (layer "In2.Cu") (net 83))
  (segment (start 186.984312 106.126775) (end 187.055022 106.197485) (width 0.1) (layer "In2.Cu") (net 83))
  (segment (start 146.355 119.595) (end 137.83 119.595) (width 0.1) (layer "In2.Cu") (net 83))
  (segment (start 188.098958 105.047486) (end 188.134313 105.082841) (width 0.1) (layer "In2.Cu") (net 83))
  (segment (start 186.509574 106.641986) (end 186.509574 106.641987) (width 0.1) (layer "In2.Cu") (net 83))
  (segment (start 186.560048 106.939948) (end 186.560049 106.939949) (width 0.1) (layer "In2.Cu") (net 83))
  (segment (start 188.417156 104.8) (end 188.417157 104.8) (width 0.1) (layer "In2.Cu") (net 83))
  (segment (start 186.560049 106.939949) (end 186.185 107.315) (width 0.1) (layer "In2.Cu") (net 83))
  (segment (start 188.098958 104.764645) (end 188.098958 104.764644) (width 0.1) (layer "In2.Cu") (net 83))
  (segment (start 189.02 104.48) (end 188.7 104.8) (width 0.1) (layer "In2.Cu") (net 83))
  (segment (start 187.302511 105.949999) (end 187.2318 105.879288) (width 0.1) (layer "In2.Cu") (net 83))
  (segment (start 188.82 102.33) (end 188.72 102.33) (width 0.1) (layer "In2.Cu") (net 83))
  (segment (start 188.134313 105.365684) (end 187.549999 105.949999) (width 0.1) (layer "In2.Cu") (net 83))
  (segment (start 188.825 99.375) (end 188.825 99.325) (width 0.1) (layer "In2.Cu") (net 83))
  (segment (start 186.509575 106.3945) (end 186.509574 106.3945) (width 0.1) (layer "In2.Cu") (net 83))
  (segment (start 188.12632 99.55) (end 188.65 99.55) (width 0.1) (layer "In2.Cu") (net 83))
  (segment (start 187.055022 106.444972) (end 187.055024 106.444974) (width 0.1) (layer "In2.Cu") (net 83))
  (segment (start 186.185 107.315) (end 178.685 107.315) (width 0.1) (layer "In2.Cu") (net 83))
  (segment (start 188.72 102.73) (end 189.27 102.73) (width 0.1) (layer "In2.Cu") (net 83))
  (segment (start 188.675 99.175) (end 188.275 99.175) (width 0.1) (layer "In2.Cu") (net 83))
  (segment (start 189.27 103.13) (end 189.22 103.13) (width 0.1) (layer "In2.Cu") (net 83))
  (segment (start 190.036328 99.866038) (end 190.036328 100.513672) (width 0.1) (layer "In2.Cu") (net 83))
  (segment (start 189.02 102.106183) (end 189.02 102.13) (width 0.1) (layer "In2.Cu") (net 83))
  (segment (start 150.9 115.05) (end 146.355 119.595) (width 0.1) (layer "In2.Cu") (net 83))
  (segment (start 189.887098 100.662902) (end 189.887098 101.239085) (width 0.1) (layer "In2.Cu") (net 83))
  (segment (start 188.134312 105.365684) (end 188.134313 105.365684) (width 0.1) (layer "In2.Cu") (net 83))
  (segment (start 189.175 98.725) (end 189.175 99.375) (width 0.1) (layer "In2.Cu") (net 83))
  (segment (start 189.35 99.55) (end 189.72029 99.55) (width 0.1) (layer "In2.Cu") (net 83))
  (segment (start 187.636328 99.060008) (end 188.12632 99.55) (width 0.1) (layer "In2.Cu") (net 83))
  (segment (start 186.807536 106.444974) (end 186.757061 106.3945) (width 0.1) (layer "In2.Cu") (net 83))
  (segment (start 186.509574 106.641987) (end 186.560048 106.69246) (width 0.1) (layer "In2.Cu") (net 83))
  (segment (start 189.887098 101.239085) (end 189.02 102.106183) (width 0.1) (layer "In2.Cu") (net 83))
  (segment (start 188.82 103.78) (end 188.47 103.78) (width 0.1) (layer "In2.Cu") (net 83))
  (segment (start 186.984312 106.126774) (end 186.984312 106.126775) (width 0.1) (layer "In2.Cu") (net 83))
  (segment (start 188.417157 104.8) (end 188.381801 104.764644) (width 0.1) (layer "In2.Cu") (net 83))
  (segment (start 178.685 107.315) (end 170.95 115.05) (width 0.1) (layer "In2.Cu") (net 83))
  (segment (start 189.02 104.38) (end 189.02 104.48) (width 0.1) (layer "In2.Cu") (net 83))
  (segment (start 170.95 115.05) (end 150.9 115.05) (width 0.1) (layer "In2.Cu") (net 83))
  (segment (start 190.036328 100.513672) (end 189.887098 100.662902) (width 0.1) (layer "In2.Cu") (net 83))
  (arc (start 189.47 102.93) (mid 189.411421 103.071421) (end 189.27 103.13) (width 0.1) (layer "In2.Cu") (net 83))
  (arc (start 188.825 98.725) (mid 188.876256 98.601256) (end 189 98.55) (width 0.1) (layer "In2.Cu") (net 83))
  (arc (start 189.02 102.13) (mid 188.961421 102.271421) (end 188.82 102.33) (width 0.1) (layer "In2.Cu") (net 83))
  (arc (start 188.7 104.8) (mid 188.558578 104.858579) (end 188.417156 104.8) (width 0.1) (layer "In2.Cu") (net 83))
  (arc (start 188.134313 105.082841) (mid 188.192891 105.224263) (end 188.134312 105.365684) (width 0.1) (layer "In2.Cu") (net 83))
  (arc (start 188.675 98.875) (mid 188.781066 98.831066) (end 188.825 98.725) (width 0.1) (layer "In2.Cu") (net 83))
  (arc (start 189.27 102.73) (mid 189.411421 102.788579) (end 189.47 102.93) (width 0.1) (layer "In2.Cu") (net 83))
  (arc (start 189.175 99.375) (mid 189.226256 99.498744) (end 189.35 99.55) (width 0.1) (layer "In2.Cu") (net 83))
  (arc (start 188.27 103.98) (mid 188.328579 104.121421) (end 188.47 104.18) (width 0.1) (layer "In2.Cu") (net 83))
  (arc (start 188.125 99.025) (mid 188.168934 98.918934) (end 188.275 98.875) (width 0.1) (layer "In2.Cu") (net 83))
  (arc (start 189 98.55) (mid 189.123744 98.601256) (end 189.175 98.725) (width 0.1) (layer "In2.Cu") (net 83))
  (arc (start 186.509574 106.3945) (mid 186.458318 106.518243) (end 186.509574 106.641986) (width 0.1) (layer "In2.Cu") (net 83))
  (arc (start 187.055022 106.197485) (mid 187.106264 106.32122) (end 187.055022 106.444972) (width 0.1) (layer "In2.Cu") (net 83))
  (arc (start 187.055024 106.444974) (mid 186.93128 106.49623) (end 186.807536 106.444974) (width 0.1) (layer "In2.Cu") (net 83))
  (arc (start 189.02 103.58) (mid 188.961421 103.721421) (end 188.82 103.78) (width 0.1) (layer "In2.Cu") (net 83))
  (arc (start 186.984312 105.879288) (mid 186.933056 106.003031) (end 186.984312 106.126774) (width 0.1) (layer "In2.Cu") (net 83))
  (arc (start 186.560048 106.69246) (mid 186.611304 106.816204) (end 186.560048 106.939948) (width 0.1) (layer "In2.Cu") (net 83))
  (arc (start 188.275 99.175) (mid 188.168934 99.131066) (end 188.125 99.025) (width 0.1) (layer "In2.Cu") (net 83))
  (arc (start 188.381801 104.764644) (mid 188.240379 104.706066) (end 188.098958 104.764645) (width 0.1) (layer "In2.Cu") (net 83))
  (arc (start 186.757061 106.3945) (mid 186.633318 106.343244) (end 186.509575 106.3945) (width 0.1) (layer "In2.Cu") (net 83))
  (arc (start 188.098958 104.764644) (mid 188.04038 104.906065) (end 188.098958 105.047486) (width 0.1) (layer "In2.Cu") (net 83))
  (arc (start 189.22 103.13) (mid 189.078579 103.188579) (end 189.02 103.33) (width 0.1) (layer "In2.Cu") (net 83))
  (arc (start 188.72 102.33) (mid 188.578579 102.388579) (end 188.52 102.53) (width 0.1) (layer "In2.Cu") (net 83))
  (arc (start 187.2318 105.879288) (mid 187.108056 105.828032) (end 186.984312 105.879288) (width 0.1) (layer "In2.Cu") (net 83))
  (arc (start 188.825 99.325) (mid 188.781066 99.218934) (end 188.675 99.175) (width 0.1) (layer "In2.Cu") (net 83))
  (arc (start 188.52 102.53) (mid 188.578579 102.671421) (end 188.72 102.73) (width 0.1) (layer "In2.Cu") (net 83))
  (arc (start 188.82 104.18) (mid 188.961421 104.238579) (end 189.02 104.38) (width 0.1) (layer "In2.Cu") (net 83))
  (arc (start 188.47 103.78) (mid 188.328579 103.838579) (end 188.27 103.98) (width 0.1) (layer "In2.Cu") (net 83))
  (arc (start 187.549999 105.949999) (mid 187.426255 106.001255) (end 187.302511 105.949999) (width 0.1) (layer "In2.Cu") (net 83))
  (arc (start 188.65 99.55) (mid 188.773744 99.498744) (end 188.825 99.375) (width 0.1) (layer "In2.Cu") (net 83))
  (segment (start 137.325 120.1) (end 137.3 120.125) (width 0.1) (layer "B.Cu") (net 83))
  (segment (start 137.3 120.125) (end 137.3 121.45) (width 0.1) (layer "B.Cu") (net 83))
  (segment (start 135.1 120.12849) (end 135.1 120.84) (width 0.2) (layer "F.Cu") (net 84))
  (segment (start 135.09251 120.121) (end 135.1 120.12849) (width 0.2) (layer "F.Cu") (net 84))
  (segment (start 187.136328 99.560008) (end 187.636328 100.060008) (width 0.1) (layer "F.Cu") (net 84))
  (via (at 135.09251 120.121) (size 0.5) (drill 0.2) (layers "F.Cu" "B.Cu") (net 84))
  (via blind (at 187.636328 100.060008) (size 0.5) (drill 0.2) (layers "F.Cu" "In5.Cu") (net 84))
  (segment (start 148.741328 113.508672) (end 144.75 117.5) (width 0.1) (layer "In2.Cu") (net 84))
  (segment (start 183.41 104.511477) (end 183.41 104.988523) (width 0.1) (layer "In2.Cu") (net 84))
  (segment (start 180.61 104.511477) (end 180.61 104.988523) (width 0.1) (layer "In2.Cu") (net 84))
  (segment (start 144.75 117.5) (end 137 117.5) (width 0.1) (layer "In2.Cu") (net 84))
  (segment (start 187.216328 101.233672) (end 185.65 102.8) (width 0.1) (layer "In2.Cu") (net 84))
  (segment (start 184.723579 104.775) (end 184.635 104.775) (width 0.1) (layer "In2.Cu") (net 84))
  (segment (start 137 117.5) (end 135.3 119.2) (width 0.1) (layer "In2.Cu") (net 84))
  (segment (start 184.11 104.6) (end 184.11 104.988523) (width 0.1) (layer "In2.Cu") (net 84))
  (segment (start 152.314016 112.7) (end 150.05 112.7) (width 0.1) (layer "In2.Cu") (net 84))
  (segment (start 182.71 104.511477) (end 182.71 104.988523) (width 0.1) (layer "In2.Cu") (net 84))
  (segment (start 149.882008 112.532008) (end 149.157507 112.532008) (width 0.1) (layer "In2.Cu") (net 84))
  (segment (start 185.65 102.8) (end 185.65 103.89) (width 0.1) (layer "In2.Cu") (net 84))
  (segment (start 169 112.85) (end 156.5 112.85) (width 0.1) (layer "In2.Cu") (net 84))
  (segment (start 181.31 104.511477) (end 181.31 104.988523) (width 0.1) (layer "In2.Cu") (net 84))
  (segment (start 135.09251 119.83249) (end 135.09251 120.121) (width 0.1) (layer "In2.Cu") (net 84))
  (segment (start 135.3 119.625) (end 135.09251 119.83249) (width 0.1) (layer "In2.Cu") (net 84))
  (segment (start 182.36 104.988523) (end 182.36 104.511477) (width 0.1) (layer "In2.Cu") (net 84))
  (segment (start 181.66 104.988523) (end 181.66 104.511477) (width 0.1) (layer "In2.Cu") (net 84))
  (segment (start 180.26 104.988523) (end 180.26 104.511477) (width 0.1) (layer "In2.Cu") (net 84))
  (segment (start 183.76 104.988523) (end 183.76 104.511477) (width 0.1) (layer "In2.Cu") (net 84))
  (segment (start 183.06 104.988523) (end 183.06 104.511477) (width 0.1) (layer "In2.Cu") (net 84))
  (segment (start 135.3 119.2) (end 135.3 119.625) (width 0.1) (layer "In2.Cu") (net 84))
  (segment (start 175.1 105.6) (end 174.325 106.375) (width 0.1) (layer "In2.Cu") (net 84))
  (segment (start 152.482008 112.532008) (end 152.314016 112.7) (width 0.1) (layer "In2.Cu") (net 84))
  (segment (start 187.636328 100.063672) (end 187.216328 100.483672) (width 0.1) (layer "In2.Cu") (net 84))
  (segment (start 179.91 104.511477) (end 179.91 104.988523) (width 0.1) (layer "In2.Cu") (net 84))
  (segment (start 177.425 104.775) (end 179.385 104.775) (width 0.1) (layer "In2.Cu") (net 84))
  (segment (start 149.157507 112.532008) (end 148.741328 112.948187) (width 0.1) (layer "In2.Cu") (net 84))
  (segment (start 180.96 104.988523) (end 180.96 104.511477) (width 0.1) (layer "In2.Cu") (net 84))
  (segment (start 174.325 107.525) (end 169 112.85) (width 0.1) (layer "In2.Cu") (net 84))
  (segment (start 182.01 104.511477) (end 182.01 104.988523) (width 0.1) (layer "In2.Cu") (net 84))
  (segment (start 187.636328 100.060008) (end 187.636328 100.063672) (width 0.1) (layer "In2.Cu") (net 84))
  (segment (start 179.56 104.988523) (end 179.56 104.95) (width 0.1) (layer "In2.Cu") (net 84))
  (segment (start 156.5 112.85) (end 156.182008 112.532008) (width 0.1) (layer "In2.Cu") (net 84))
  (segment (start 184.46 104.6) (end 184.46 104.511477) (width 0.1) (layer "In2.Cu") (net 84))
  (segment (start 185.65 103.89) (end 184.794289 104.745711) (width 0.1) (layer "In2.Cu") (net 84))
  (segment (start 187.216328 100.483672) (end 187.216328 101.233672) (width 0.1) (layer "In2.Cu") (net 84))
  (segment (start 174.325 106.375) (end 174.325 107.525) (width 0.1) (layer "In2.Cu") (net 84))
  (segment (start 148.741328 112.948187) (end 148.741328 113.508672) (width 0.1) (layer "In2.Cu") (net 84))
  (segment (start 184.11 104.511477) (end 184.11 104.6) (width 0.1) (layer "In2.Cu") (net 84))
  (segment (start 176.6 105.6) (end 175.1 105.6) (width 0.1) (layer "In2.Cu") (net 84))
  (segment (start 177.425 104.775) (end 176.6 105.6) (width 0.1) (layer "In2.Cu") (net 84))
  (segment (start 150.05 112.7) (end 149.882008 112.532008) (width 0.1) (layer "In2.Cu") (net 84))
  (segment (start 156.182008 112.532008) (end 152.482008 112.532008) (width 0.1) (layer "In2.Cu") (net 84))
  (arc (start 182.535 105.163523) (mid 182.411256 105.112267) (end 182.36 104.988523) (width 0.1) (layer "In2.Cu") (net 84))
  (arc (start 182.71 104.988523) (mid 182.658744 105.112267) (end 182.535 105.163523) (width 0.1) (layer "In2.Cu") (net 84))
  (arc (start 180.96 104.511477) (mid 180.908744 104.387733) (end 180.785 104.336477) (width 0.1) (layer "In2.Cu") (net 84))
  (arc (start 180.435 105.163523) (mid 180.311256 105.112267) (end 180.26 104.988523) (width 0.1) (layer "In2.Cu") (net 84))
  (arc (start 180.26 104.511477) (mid 180.208744 104.387733) (end 180.085 104.336477) (width 0.1) (layer "In2.Cu") (net 84))
  (arc (start 179.735 105.163523) (mid 179.611256 105.112267) (end 179.56 104.988523) (width 0.1) (layer "In2.Cu") (net 84))
  (arc (start 181.66 104.511477) (mid 181.608744 104.387733) (end 181.485 104.336477) (width 0.1) (layer "In2.Cu") (net 84))
  (arc (start 183.585 104.336477) (mid 183.461256 104.387733) (end 183.41 104.511477) (width 0.1) (layer "In2.Cu") (net 84))
  (arc (start 183.935 105.163523) (mid 183.811256 105.112267) (end 183.76 104.988523) (width 0.1) (layer "In2.Cu") (net 84))
  (arc (start 183.235 105.163523) (mid 183.111256 105.112267) (end 183.06 104.988523) (width 0.1) (layer "In2.Cu") (net 84))
  (arc (start 181.835 105.163523) (mid 181.711256 105.112267) (end 181.66 104.988523) (width 0.1) (layer "In2.Cu") (net 84))
  (arc (start 180.61 104.988523) (mid 180.558744 105.112267) (end 180.435 105.163523) (width 0.1) (layer "In2.Cu") (net 84))
  (arc (start 183.76 104.511477) (mid 183.708744 104.387733) (end 183.585 104.336477) (width 0.1) (layer "In2.Cu") (net 84))
  (arc (start 179.91 104.988523) (mid 179.858744 105.112267) (end 179.735 105.163523) (width 0.1) (layer "In2.Cu") (net 84))
  (arc (start 184.46 104.511477) (mid 184.408744 104.387733) (end 184.285 104.336477) (width 0.1) (layer "In2.Cu") (net 84))
  (arc (start 181.485 104.336477) (mid 181.361256 104.387733) (end 181.31 104.511477) (width 0.1) (layer "In2.Cu") (net 84))
  (arc (start 184.11 104.988523) (mid 184.058744 105.112267) (end 183.935 105.163523) (width 0.1) (layer "In2.Cu") (net 84))
  (arc (start 182.885 104.336477) (mid 182.761256 104.387733) (end 182.71 104.511477) (width 0.1) (layer "In2.Cu") (net 84))
  (arc (start 183.41 104.988523) (mid 183.358744 105.112267) (end 183.235 105.163523) (width 0.1) (layer "In2.Cu") (net 84))
  (arc (start 184.794289 104.745711) (mid 184.761847 104.767388) (end 184.723579 104.775) (width 0.1) (layer "In2.Cu") (net 84))
  (arc (start 179.56 104.95) (mid 179.508744 104.826256) (end 179.385 104.775) (width 0.1) (layer "In2.Cu") (net 84))
  (arc (start 184.635 104.775) (mid 184.511256 104.723744) (end 184.46 104.6) (width 0.1) (layer "In2.Cu") (net 84))
  (arc (start 184.285 104.336477) (mid 184.161256 104.387733) (end 184.11 104.511477) (width 0.1) (layer "In2.Cu") (net 84))
  (arc (start 182.36 104.511477) (mid 182.308744 104.387733) (end 182.185 104.336477) (width 0.1) (layer "In2.Cu") (net 84))
  (arc (start 180.085 104.336477) (mid 179.961256 104.387733) (end 179.91 104.511477) (width 0.1) (layer "In2.Cu") (net 84))
  (arc (start 181.135 105.163523) (mid 181.011256 105.112267) (end 180.96 104.988523) (width 0.1) (layer "In2.Cu") (net 84))
  (arc (start 182.01 104.988523) (mid 181.958744 105.112267) (end 181.835 105.163523) (width 0.1) (layer "In2.Cu") (net 84))
  (arc (start 182.185 104.336477) (mid 182.061256 104.387733) (end 182.01 104.511477) (width 0.1) (layer "In2.Cu") (net 84))
  (arc (start 180.785 104.336477) (mid 180.661256 104.387733) (end 180.61 104.511477) (width 0.1) (layer "In2.Cu") (net 84))
  (arc (start 183.06 104.511477) (mid 183.008744 104.387733) (end 182.885 104.336477) (width 0.1) (layer "In2.Cu") (net 84))
  (arc (start 181.31 104.988523) (mid 181.258744 105.112267) (end 181.135 105.163523) (width 0.1) (layer "In2.Cu") (net 84))
  (segment (start 135.09251 120.121) (end 135.1 120.12849) (width 0.1) (layer "B.Cu") (net 84))
  (segment (start 135.1 120.12849) (end 135.1 121.45) (width 0.1) (layer "B.Cu") (net 84))
  (segment (start 189.136328 99.560008) (end 189.636328 100.060008) (width 0.1) (layer "F.Cu") (net 85))
  (segment (start 132.9 120.125) (end 132.9 120.84) (width 0.2) (layer "F.Cu") (net 85))
  (via blind (at 189.636328 100.060008) (size 0.5) (drill 0.2) (layers "F.Cu" "In5.Cu") (net 85))
  (via (at 132.9 120.125) (size 0.5) (drill 0.2) (layers "F.Cu" "B.Cu") (net 85))
  (segment (start 188.05 104.475) (end 187.9225 104.6025) (width 0.1) (layer "In2.Cu") (net 85))
  (segment (start 189.056328 100.640008) (end 189.056328 101.618672) (width 0.1) (layer "In2.Cu") (net 85))
  (segment (start 189.636328 100.060008) (end 189.056328 100.640008) (width 0.1) (layer "In2.Cu") (net 85))
  (segment (start 137.9325 118.75) (end 136.9 119.7825) (width 0.1) (layer "In2.Cu") (net 85))
  (segment (start 187.63909 105.449328) (end 187.639091 105.449327) (width 0.1) (layer "In2.Cu") (net 85))
  (segment (start 134.0625 121.275) (end 132.9125 120.125) (width 0.1) (layer "In2.Cu") (net 85))
  (segment (start 139.725 119) (end 139.475 118.75) (width 0.1) (layer "In2.Cu") (net 85))
  (segment (start 185.845 106.68) (end 178.32 106.68) (width 0.1) (layer "In2.Cu") (net 85))
  (segment (start 186.791127 105.73387) (end 185.845 106.68) (width 0.1) (layer "In2.Cu") (net 85))
  (segment (start 136.9 119.7825) (end 136.9 120.6) (width 0.1) (layer "In2.Cu") (net 85))
  (segment (start 132.9125 120.125) (end 132.9 120.125) (width 0.1) (layer "In2.Cu") (net 85))
  (segment (start 186.756906 105.416807) (end 186.791127 105.451028) (width 0.1) (layer "In2.Cu") (net 85))
  (segment (start 139.475 118.75) (end 137.9325 118.75) (width 0.1) (layer "In2.Cu") (net 85))
  (segment (start 187.639657 104.6025) (end 187.605435 104.568278) (width 0.1) (layer "In2.Cu") (net 85))
  (segment (start 145.95 119) (end 139.725 119) (width 0.1) (layer "In2.Cu") (net 85))
  (segment (start 186.756907 105.133965) (end 186.756906 105.133965) (width 0.1) (layer "In2.Cu") (net 85))
  (segment (start 187.356247 105.450462) (end 187.356248 105.450463) (width 0.1) (layer "In2.Cu") (net 85))
  (segment (start 150.5 114.45) (end 145.95 119) (width 0.1) (layer "In2.Cu") (net 85))
  (segment (start 170.55 114.45) (end 150.5 114.45) (width 0.1) (layer "In2.Cu") (net 85))
  (segment (start 136.9 120.6) (end 136.225 121.275) (width 0.1) (layer "In2.Cu") (net 85))
  (segment (start 188.05 102.625) (end 188.05 104.475) (width 0.1) (layer "In2.Cu") (net 85))
  (segment (start 136.225 121.275) (end 134.0625 121.275) (width 0.1) (layer "In2.Cu") (net 85))
  (segment (start 187.322592 104.568279) (end 187.322593 104.568278) (width 0.1) (layer "In2.Cu") (net 85))
  (segment (start 187.639656 104.6025) (end 187.639657 104.6025) (width 0.1) (layer "In2.Cu") (net 85))
  (segment (start 187.322593 104.85112) (end 187.356814 104.885341) (width 0.1) (layer "In2.Cu") (net 85))
  (segment (start 186.791126 105.733871) (end 186.791127 105.73387) (width 0.1) (layer "In2.Cu") (net 85))
  (segment (start 187.356248 105.450463) (end 187.039749 105.133965) (width 0.1) (layer "In2.Cu") (net 85))
  (segment (start 187.639091 105.449327) (end 187.637956 105.450463) (width 0.1) (layer "In2.Cu") (net 85))
  (segment (start 187.356814 104.885341) (end 187.639091 105.167619) (width 0.1) (layer "In2.Cu") (net 85))
  (segment (start 178.32 106.68) (end 170.55 114.45) (width 0.1) (layer "In2.Cu") (net 85))
  (segment (start 189.056328 101.618672) (end 188.05 102.625) (width 0.1) (layer "In2.Cu") (net 85))
  (arc (start 186.791127 105.451028) (mid 186.849705 105.59245) (end 186.791126 105.733871) (width 0.1) (layer "In2.Cu") (net 85))
  (arc (start 187.637956 105.450463) (mid 187.497101 105.508806) (end 187.356247 105.450462) (width 0.1) (layer "In2.Cu") (net 85))
  (arc (start 186.756906 105.133965) (mid 186.698328 105.275386) (end 186.756906 105.416807) (width 0.1) (layer "In2.Cu") (net 85))
  (arc (start 187.9225 104.6025) (mid 187.781078 104.661079) (end 187.639656 104.6025) (width 0.1) (layer "In2.Cu") (net 85))
  (arc (start 187.605435 104.568278) (mid 187.464013 104.5097) (end 187.322592 104.568279) (width 0.1) (layer "In2.Cu") (net 85))
  (arc (start 187.639091 105.167619) (mid 187.697434 105.308474) (end 187.63909 105.449328) (width 0.1) (layer "In2.Cu") (net 85))
  (arc (start 187.039749 105.133965) (mid 186.898328 105.075387) (end 186.756907 105.133965) (width 0.1) (layer "In2.Cu") (net 85))
  (arc (start 187.322593 104.568278) (mid 187.264015 104.709699) (end 187.322593 104.85112) (width 0.1) (layer "In2.Cu") (net 85))
  (segment (start 132.9 120.125) (end 132.9 121.45) (width 0.1) (layer "B.Cu") (net 85))
  (segment (start 188.136328 99.560008) (end 188.636328 100.060008) (width 0.1) (layer "F.Cu") (net 86))
  (segment (start 131.8 120.125) (end 131.8 120.84) (width 0.2) (layer "F.Cu") (net 86))
  (via blind (at 188.636328 100.060008) (size 0.5) (drill 0.2) (layers "F.Cu" "In5.Cu") (net 86))
  (via (at 131.8 120.125) (size 0.5) (drill 0.2) (layers "F.Cu" "B.Cu") (net 86))
  (segment (start 178.341918 105.806165) (end 178.288082 105.806165) (width 0.1) (layer "In2.Cu") (net 86))
  (segment (start 178.54 105.41) (end 178.54 105.608083) (width 0.1) (layer "In2.Cu") (net 86))
  (segment (start 145.1 118) (end 137.27 118) (width 0.1) (layer "In2.Cu") (net 86))
  (segment (start 188.216328 100.480008) (end 188.216328 101.083672) (width 0.1) (layer "In2.Cu") (net 86))
  (segment (start 149.7 113.4) (end 145.1 118) (width 0.1) (layer "In2.Cu") (net 86))
  (segment (start 186.556328 102.743672) (end 186.556328 103.943672) (width 0.1) (layer "In2.Cu") (net 86))
  (segment (start 185.611827 104.640685) (end 185.947704 104.976562) (width 0.1) (layer "In2.Cu") (net 86))
  (segment (start 133.478015 119.228015) (end 132.271985 119.228015) (width 0.1) (layer "In2.Cu") (net 86))
  (segment (start 186.556328 103.943672) (end 186.425 104.075) (width 0.1) (layer "In2.Cu") (net 86))
  (segment (start 137.27 118) (end 135.7 119.57) (width 0.1) (layer "In2.Cu") (net 86))
  (segment (start 134.791 120.541) (end 133.478015 119.228015) (width 0.1) (layer "In2.Cu") (net 86))
  (segment (start 185.930024 104.075) (end 185.894668 104.110355) (width 0.1) (layer "In2.Cu") (net 86))
  (segment (start 185.328982 105.171014) (end 185.328983 105.171014) (width 0.1) (layer "In2.Cu") (net 86))
  (segment (start 175.345693 106.295693) (end 174.78 106.861385) (width 0.1) (layer "In2.Cu") (net 86))
  (segment (start 185.894668 104.357843) (end 185.894668 104.357842) (width 0.1) (layer "In2.Cu") (net 86))
  (segment (start 185.328983 105.171014) (end 185.09 105.41) (width 0.1) (layer "In2.Cu") (net 86))
  (segment (start 135.7 119.57) (end 135.7 120.3) (width 0.1) (layer "In2.Cu") (net 86))
  (segment (start 178.991918 105.211918) (end 178.991918 105.211917) (width 0.1) (layer "In2.Cu") (net 86))
  (segment (start 178.541918 105.41) (end 178.54 105.41) (width 0.1) (layer "In2.Cu") (net 86))
  (segment (start 178.541918 105.211918) (end 178.541918 105.41) (width 0.1) (layer "In2.Cu") (net 86))
  (segment (start 135.459 120.541) (end 134.791 120.541) (width 0.1) (layer "In2.Cu") (net 86))
  (segment (start 176.704307 106.295693) (end 175.345693 106.295693) (width 0.1) (layer "In2.Cu") (net 86))
  (segment (start 186.230545 104.976563) (end 186.230546 104.976562) (width 0.1) (layer "In2.Cu") (net 86))
  (segment (start 178.09 105.608083) (end 178.09 105.608082) (width 0.1) (layer "In2.Cu") (net 86))
  (segment (start 185.09 105.41) (end 179.19 105.41) (width 0.1) (layer "In2.Cu") (net 86))
  (segment (start 178.541918 105.211917) (end 178.541918 105.211918) (width 0.1) (layer "In2.Cu") (net 86))
  (segment (start 135.7 120.3) (end 135.459 120.541) (width 0.1) (layer "In2.Cu") (net 86))
  (segment (start 169.5 113.4) (end 149.7 113.4) (width 0.1) (layer "In2.Cu") (net 86))
  (segment (start 174.78 108.12) (end 169.5 113.4) (width 0.1) (layer "In2.Cu") (net 86))
  (segment (start 174.78 106.861385) (end 174.78 108.12) (width 0.1) (layer "In2.Cu") (net 86))
  (segment (start 178.793836 105.013835) (end 178.74 105.013835) (width 0.1) (layer "In2.Cu") (net 86))
  (segment (start 177.59 105.41) (end 176.704307 106.295693) (width 0.1) (layer "In2.Cu") (net 86))
  (segment (start 188.216328 101.083672) (end 186.556328 102.743672) (width 0.1) (layer "In2.Cu") (net 86))
  (segment (start 188.636328 100.060008) (end 188.216328 100.480008) (width 0.1) (layer "In2.Cu") (net 86))
  (segment (start 185.930025 104.074999) (end 185.930024 104.075) (width 0.1) (layer "In2.Cu") (net 86))
  (segment (start 185.328983 104.923528) (end 185.328983 104.923527) (width 0.1) (layer "In2.Cu") (net 86))
  (segment (start 131.8 119.7) (end 131.8 120.125) (width 0.1) (layer "In2.Cu") (net 86))
  (segment (start 177.891918 105.41) (end 177.59 105.41) (width 0.1) (layer "In2.Cu") (net 86))
  (segment (start 185.894668 104.357842) (end 186.230546 104.69372) (width 0.1) (layer "In2.Cu") (net 86))
  (segment (start 185.364339 104.640685) (end 185.328983 104.67604) (width 0.1) (layer "In2.Cu") (net 86))
  (segment (start 132.271985 119.228015) (end 131.8 119.7) (width 0.1) (layer "In2.Cu") (net 86))
  (arc (start 186.177512 104.075) (mid 186.053769 104.023743) (end 185.930025 104.074999) (width 0.1) (layer "In2.Cu") (net 86))
  (arc (start 179.19 105.41) (mid 179.049935 105.351983) (end 178.991918 105.211918) (width 0.1) (layer "In2.Cu") (net 86))
  (arc (start 185.611827 104.640685) (mid 185.488083 104.589429) (end 185.364339 104.640685) (width 0.1) (layer "In2.Cu") (net 86))
  (arc (start 178.288082 105.806165) (mid 178.148017 105.748148) (end 178.09 105.608083) (width 0.1) (layer "In2.Cu") (net 86))
  (arc (start 185.328983 104.67604) (mid 185.277727 104.799784) (end 185.328983 104.923528) (width 0.1) (layer "In2.Cu") (net 86))
  (arc (start 178.991918 105.211917) (mid 178.933901 105.071852) (end 178.793836 105.013835) (width 0.1) (layer "In2.Cu") (net 86))
  (arc (start 185.328983 104.923527) (mid 185.380239 105.047271) (end 185.328982 105.171014) (width 0.1) (layer "In2.Cu") (net 86))
  (arc (start 186.230546 104.976562) (mid 186.089124 105.035141) (end 185.947704 104.976562) (width 0.1) (layer "In2.Cu") (net 86))
  (arc (start 178.74 105.013835) (mid 178.599935 105.071852) (end 178.541918 105.211917) (width 0.1) (layer "In2.Cu") (net 86))
  (arc (start 178.09 105.608082) (mid 178.031983 105.468017) (end 177.891918 105.41) (width 0.1) (layer "In2.Cu") (net 86))
  (arc (start 186.425 104.075) (mid 186.301256 104.126256) (end 186.177512 104.075) (width 0.1) (layer "In2.Cu") (net 86))
  (arc (start 178.54 105.608083) (mid 178.481983 105.748148) (end 178.341918 105.806165) (width 0.1) (layer "In2.Cu") (net 86))
  (arc (start 186.230546 104.69372) (mid 186.289124 104.835142) (end 186.230545 104.976563) (width 0.1) (layer "In2.Cu") (net 86))
  (arc (start 185.894668 104.110355) (mid 185.843412 104.234099) (end 185.894668 104.357843) (width 0.1) (layer "In2.Cu") (net 86))
  (segment (start 131.8 120.125) (end 131.8 121.45) (width 0.1) (layer "B.Cu") (net 86))
  (segment (start 130.685 120.825) (end 130.7 120.84) (width 0.2) (layer "F.Cu") (net 87))
  (segment (start 188.136328 100.560008) (end 188.636328 101.060008) (width 0.1) (layer "F.Cu") (net 87))
  (segment (start 130.685 120.125) (end 130.685 120.825) (width 0.2) (layer "F.Cu") (net 87))
  (via blind (at 188.636328 101.060008) (size 0.5) (drill 0.2) (layers "F.Cu" "In5.Cu") (net 87))
  (via (at 130.685 120.125) (size 0.5) (drill 0.2) (layers "F.Cu" "B.Cu") (net 87))
  (segment (start 136.02899 120.9) (end 134.45 120.9) (width 0.1) (layer "In2.Cu") (net 87))
  (segment (start 132.6 119.625) (end 132.375 119.85) (width 0.1) (layer "In2.Cu") (net 87))
  (segment (start 136.58751 119.36249) (end 136.58751 120.34148) (width 0.1) (layer "In2.Cu") (net 87))
  (segment (start 136.58751 120.34148) (end 136.02899 120.9) (width 0.1) (layer "In2.Cu") (net 87))
  (segment (start 188.636328 101.388672) (end 187.3 102.725) (width 0.1) (layer "In2.Cu") (net 87))
  (segment (start 185.455 106.045) (end 177.955 106.045) (width 0.1) (layer "In2.Cu") (net 87))
  (segment (start 187.3 104.2) (end 185.455 106.045) (width 0.1) (layer "In2.Cu") (net 87))
  (segment (start 188.636328 101.060008) (end 188.636328 101.388672) (width 0.1) (layer "In2.Cu") (net 87))
  (segment (start 170.05 113.95) (end 150.05 113.95) (width 0.1) (layer "In2.Cu") (net 87))
  (segment (start 187.3 102.725) (end 187.3 104.2) (width 0.1) (layer "In2.Cu") (net 87))
  (segment (start 150.05 113.95) (end 145.6 118.4) (width 0.1) (layer "In2.Cu") (net 87))
  (segment (start 177.955 106.045) (end 170.05 113.95) (width 0.1) (layer "In2.Cu") (net 87))
  (segment (start 132.375 119.85) (end 132.375 120.425) (width 0.1) (layer "In2.Cu") (net 87))
  (segment (start 131.21 120.65) (end 130.685 120.125) (width 0.1) (layer "In2.Cu") (net 87))
  (segment (start 132.15 120.65) (end 131.21 120.65) (width 0.1) (layer "In2.Cu") (net 87))
  (segment (start 134.45 120.9) (end 133.175 119.625) (width 0.1) (layer "In2.Cu") (net 87))
  (segment (start 132.375 120.425) (end 132.15 120.65) (width 0.1) (layer "In2.Cu") (net 87))
  (segment (start 133.175 119.625) (end 132.6 119.625) (width 0.1) (layer "In2.Cu") (net 87))
  (segment (start 145.6 118.4) (end 137.55 118.4) (width 0.1) (layer "In2.Cu") (net 87))
  (segment (start 137.55 118.4) (end 136.58751 119.36249) (width 0.1) (layer "In2.Cu") (net 87))
  (segment (start 130.685 120.125) (end 130.7 120.14) (width 0.1) (layer "B.Cu") (net 87))
  (segment (start 130.7 120.14) (end 130.7 121.45) (width 0.1) (layer "B.Cu") (net 87))
  (segment (start 188.136328 97.560008) (end 188.636328 98.060008) (width 0.1) (layer "F.Cu") (net 88))
  (via blind (at 188.636328 98.060008) (size 0.5) (drill 0.2) (layers "F.Cu" "In5.Cu") (net 88))
  (via (at 144.55 116.4) (size 0.5) (drill 0.2) (layers "F.Cu" "B.Cu") (net 88))
  (segment (start 176.286175 104.071862) (end 176.286176 104.071861) (width 0.1) (layer "In2.Cu") (net 88))
  (segment (start 177.5 104.11) (end 177.09 104.11) (width 0.1) (layer "In2.Cu") (net 88))
  (segment (start 184.615 104.11) (end 184.38 104.11) (width 0.1) (layer "In2.Cu") (net 88))
  (segment (start 178.375 103.885) (end 178.375 104.335) (width 0.1) (layer "In2.Cu") (net 88))
  (segment (start 177.09 104.11) (end 176.99 104.21) (width 0.1) (layer "In2.Cu") (net 88))
  (segment (start 188.216328 98.480008) (end 187.6 98.480008) (width 0.1) (layer "In2.Cu") (net 88))
  (segment (start 173.75 107.05) (end 168.681239 112.118761) (width 0.1) (layer "In2.Cu") (net 88))
  (segment (start 184.18 103.91) (end 184.18 103.31) (width 0.1) (layer "In2.Cu") (net 88))
  (segment (start 186.8625 100.0875) (end 186.8625 100.9375) (width 0.1) (layer "In2.Cu") (net 88))
  (segment (start 176.707157 104.21) (end 176.569018 104.071861) (width 0.1) (layer "In2.Cu") (net 88))
  (segment (start 177.675 103.885) (end 177.675 103.935) (width 0.1) (layer "In2.Cu") (net 88))
  (segment (start 148 112.55) (end 148 113.357455) (width 0.1) (layer "In2.Cu") (net 88))
  (segment (start 181.13 104.11) (end 179.25 104.11) (width 0.1) (layer "In2.Cu") (net 88))
  (segment (start 148 113.357455) (end 144.957455 116.4) (width 0.1) (layer "In2.Cu") (net 88))
  (segment (start 182.98 103.31) (end 182.98 103.91) (width 0.1) (layer "In2.Cu") (net 88))
  (segment (start 187.175 98.905008) (end 187.175 99.775) (width 0.1) (layer "In2.Cu") (net 88))
  (segment (start 176.424314 104.775683) (end 176.3 104.9) (width 0.1) (layer "In2.Cu") (net 88))
  (segment (start 181.18 104.11) (end 181.13 104.11) (width 0.1) (layer "In2.Cu") (net 88))
  (segment (start 183.78 103.31) (end 183.78 103.91) (width 0.1) (layer "In2.Cu") (net 88))
  (segment (start 175 104.9) (end 173.75 106.15) (width 0.1) (layer "In2.Cu") (net 88))
  (segment (start 149.9 111.5) (end 149.05 111.5) (width 0.1) (layer "In2.Cu") (net 88))
  (segment (start 182.58 103.91) (end 182.58 103.31) (width 0.1) (layer "In2.Cu") (net 88))
  (segment (start 152.518761 112.118761) (end 152.35 111.95) (width 0.1) (layer "In2.Cu") (net 88))
  (segment (start 176.707156 104.21) (end 176.707157 104.21) (width 0.1) (layer "In2.Cu") (net 88))
  (segment (start 178.725 104.285) (end 178.725 103.885) (width 0.1) (layer "In2.Cu") (net 88))
  (segment (start 176.424313 104.775684) (end 176.424314 104.775683) (width 0.1) (layer "In2.Cu") (net 88))
  (segment (start 182.18 103.31) (end 182.18 103.91) (width 0.1) (layer "In2.Cu") (net 88))
  (segment (start 181.78 103.91) (end 181.78 103.31) (width 0.1) (layer "In2.Cu") (net 88))
  (segment (start 183.38 103.91) (end 183.38 103.31) (width 0.1) (layer "In2.Cu") (net 88))
  (segment (start 168.681239 112.118761) (end 152.518761 112.118761) (width 0.1) (layer "In2.Cu") (net 88))
  (segment (start 178.025 104.335) (end 178.025 103.885) (width 0.1) (layer "In2.Cu") (net 88))
  (segment (start 144.957455 116.4) (end 144.55 116.4) (width 0.1) (layer "In2.Cu") (net 88))
  (segment (start 187.6 98.480008) (end 187.175 98.905008) (width 0.1) (layer "In2.Cu") (net 88))
  (segment (start 152.35 111.95) (end 150.35 111.95) (width 0.1) (layer "In2.Cu") (net 88))
  (segment (start 150.35 111.95) (end 149.9 111.5) (width 0.1) (layer "In2.Cu") (net 88))
  (segment (start 185 102.8) (end 185 103.725) (width 0.1) (layer "In2.Cu") (net 88))
  (segment (start 176.286176 104.354703) (end 176.424314 104.492841) (width 0.1) (layer "In2.Cu") (net 88))
  (segment (start 186.8625 100.9375) (end 185 102.8) (width 0.1) (layer "In2.Cu") (net 88))
  (segment (start 185 103.725) (end 184.615 104.11) (width 0.1) (layer "In2.Cu") (net 88))
  (segment (start 173.75 106.15) (end 173.75 107.05) (width 0.1) (layer "In2.Cu") (net 88))
  (segment (start 187.175 99.775) (end 186.8625 100.0875) (width 0.1) (layer "In2.Cu") (net 88))
  (segment (start 181.38 103.31) (end 181.38 103.91) (width 0.1) (layer "In2.Cu") (net 88))
  (segment (start 188.636328 98.060008) (end 188.216328 98.480008) (width 0.1) (layer "In2.Cu") (net 88))
  (segment (start 179.075 104.285) (end 179.075 104.335) (width 0.1) (layer "In2.Cu") (net 88))
  (segment (start 178.725 104.335) (end 178.725 104.285) (width 0.1) (layer "In2.Cu") (net 88))
  (segment (start 149.05 111.5) (end 148 112.55) (width 0.1) (layer "In2.Cu") (net 88))
  (segment (start 176.3 104.9) (end 175 104.9) (width 0.1) (layer "In2.Cu") (net 88))
  (arc (start 182.78 104.11) (mid 182.638579 104.051421) (end 182.58 103.91) (width 0.1) (layer "In2.Cu") (net 88))
  (arc (start 184.18 103.31) (mid 184.121421 103.168579) (end 183.98 103.11) (width 0.1) (layer "In2.Cu") (net 88))
  (arc (start 176.569018 104.071861) (mid 176.427596 104.013283) (end 176.286175 104.071862) (width 0.1) (layer "In2.Cu") (net 88))
  (arc (start 178.55 103.71) (mid 178.426256 103.761256) (end 178.375 103.885) (width 0.1) (layer "In2.Cu") (net 88))
  (arc (start 181.38 103.91) (mid 181.321421 104.051421) (end 181.18 104.11) (width 0.1) (layer "In2.Cu") (net 88))
  (arc (start 179.075 104.335) (mid 179.023744 104.458744) (end 178.9 104.51) (width 0.1) (layer "In2.Cu") (net 88))
  (arc (start 179.25 104.11) (mid 179.126256 104.161256) (end 179.075 104.285) (width 0.1) (layer "In2.Cu") (net 88))
  (arc (start 182.58 103.31) (mid 182.521421 103.168579) (end 182.38 103.11) (width 0.1) (layer "In2.Cu") (net 88))
  (arc (start 178.9 104.51) (mid 178.776256 104.458744) (end 178.725 104.335) (width 0.1) (layer "In2.Cu") (net 88))
  (arc (start 178.375 104.335) (mid 178.323744 104.458744) (end 178.2 104.51) (width 0.1) (layer "In2.Cu") (net 88))
  (arc (start 181.58 103.11) (mid 181.438579 103.168579) (end 181.38 103.31) (width 0.1) (layer "In2.Cu") (net 88))
  (arc (start 181.98 104.11) (mid 181.838579 104.051421) (end 181.78 103.91) (width 0.1) (layer "In2.Cu") (net 88))
  (arc (start 183.58 104.11) (mid 183.438579 104.051421) (end 183.38 103.91) (width 0.1) (layer "In2.Cu") (net 88))
  (arc (start 177.85 103.71) (mid 177.726256 103.761256) (end 177.675 103.885) (width 0.1) (layer "In2.Cu") (net 88))
  (arc (start 183.98 103.11) (mid 183.838579 103.168579) (end 183.78 103.31) (width 0.1) (layer "In2.Cu") (net 88))
  (arc (start 182.98 103.91) (mid 182.921421 104.051421) (end 182.78 104.11) (width 0.1) (layer "In2.Cu") (net 88))
  (arc (start 183.78 103.91) (mid 183.721421 104.051421) (end 183.58 104.11) (width 0.1) (layer "In2.Cu") (net 88))
  (arc (start 176.424314 104.492841) (mid 176.482892 104.634263) (end 176.424313 104.775684) (width 0.1) (layer "In2.Cu") (net 88))
  (arc (start 183.18 103.11) (mid 183.038579 103.168579) (end 182.98 103.31) (width 0.1) (layer "In2.Cu") (net 88))
  (arc (start 183.38 103.31) (mid 183.321421 103.168579) (end 183.18 103.11) (width 0.1) (layer "In2.Cu") (net 88))
  (arc (start 178.025 103.885) (mid 177.973744 103.761256) (end 177.85 103.71) (width 0.1) (layer "In2.Cu") (net 88))
  (arc (start 177.675 103.935) (mid 177.623744 104.058744) (end 177.5 104.11) (width 0.1) (layer "In2.Cu") (net 88))
  (arc (start 178.2 104.51) (mid 178.076256 104.458744) (end 178.025 104.335) (width 0.1) (layer "In2.Cu") (net 88))
  (arc (start 181.78 103.31) (mid 181.721421 103.168579) (end 181.58 103.11) (width 0.1) (layer "In2.Cu") (net 88))
  (arc (start 182.38 103.11) (mid 182.238579 103.168579) (end 182.18 103.31) (width 0.1) (layer "In2.Cu") (net 88))
  (arc (start 178.725 103.885) (mid 178.673744 103.761256) (end 178.55 103.71) (width 0.1) (layer "In2.Cu") (net 88))
  (arc (start 184.38 104.11) (mid 184.238579 104.051421) (end 184.18 103.91) (width 0.1) (layer "In2.Cu") (net 88))
  (arc (start 176.99 104.21) (mid 176.848578 104.268579) (end 176.707156 104.21) (width 0.1) (layer "In2.Cu") (net 88))
  (arc (start 182.18 103.91) (mid 182.121421 104.051421) (end 181.98 104.11) (width 0.1) (layer "In2.Cu") (net 88))
  (arc (start 176.286176 104.071861) (mid 176.227598 104.213282) (end 176.286176 104.354703) (width 0.1) (layer "In2.Cu") (net 88))
  (segment (start 140.735 119.065) (end 143.335 119.065) (width 0.2) (layer "B.Cu") (net 88))
  (segment (start 140.735 119.065) (end 140.735 119.65) (width 0.2) (layer "B.Cu") (net 88))
  (segment (start 140.735 118.507) (end 140.735 119.065) (width 0.2) (layer "B.Cu") (net 88))
  (segment (start 143.335 119.065) (end 144.55 117.85) (width 0.2) (layer "B.Cu") (net 88))
  (segment (start 144.55 117.85) (end 144.55 116.4) (width 0.2) (layer "B.Cu") (net 88))
  (segment (start 242.3 129.5) (end 243.06 129.5) (width 0.2) (layer "F.Cu") (net 89))
  (segment (start 243.06 129.5) (end 243.15 129.59) (width 0.2) (layer "F.Cu") (net 89))
  (via (at 242.3 129.5) (size 0.5) (drill 0.2) (layers "F.Cu" "B.Cu") (net 89))
  (segment (start 242.77 125.563505) (end 242.77 129.03) (width 0.2) (layer "B.Cu") (net 89))
  (segment (start 241.6 124.085) (end 241.6 124.393505) (width 0.2) (layer "B.Cu") (net 89))
  (segment (start 241.6 124.393505) (end 242.77 125.563505) (width 0.2) (layer "B.Cu") (net 89))
  (segment (start 242.77 129.03) (end 242.3 129.5) (width 0.2) (layer "B.Cu") (net 89))
  (segment (start 242.2 132.1) (end 243.12 132.1) (width 0.2) (layer "F.Cu") (net 90))
  (segment (start 243.12 132.1) (end 243.15 132.13) (width 0.2) (layer "F.Cu") (net 90))
  (via (at 242.2 132.1) (size 0.5) (drill 0.2) (layers "F.Cu" "B.Cu") (net 90))
  (segment (start 241.6 126.685) (end 241.6 131.5) (width 0.2) (layer "B.Cu") (net 90))
  (segment (start 241.6 131.5) (end 242.2 132.1) (width 0.2) (layer "B.Cu") (net 90))
  (segment (start 191.136328 89.560008) (end 190.636328 90.060008) (width 0.127) (layer "F.Cu") (net 91))
  (segment (start 224.78 87.85) (end 225.25 87.85) (width 0.12) (layer "F.Cu") (net 91))
  (segment (start 224.935 82.975) (end 223.925 82.975) (width 0.12) (layer "F.Cu") (net 91))
  (segment (start 225.8 83.84) (end 224.935 82.975) (width 0.12) (layer "F.Cu") (net 91))
  (segment (start 223.925 84.345) (end 223.925 82.975) (width 0.12) (layer "F.Cu") (net 91))
  (segment (start 225.25 87.85) (end 225.8 87.3) (width 0.12) (layer "F.Cu") (net 91))
  (segment (start 225.8 87.3) (end 225.8 83.84) (width 0.12) (layer "F.Cu") (net 91))
  (via (at 190.636328 90.060008) (size 0.5) (drill 0.2) (layers "F.Cu" "B.Cu") (net 91))
  (via (at 223.925 84.345) (size 0.5) (drill 0.2) (layers "F.Cu" "B.Cu") (net 91))
  (segment (start 223.925 84.345) (end 223.255 83.675) (width 0.12) (layer "In7.Cu") (net 91))
  (segment (start 214.55 87.075) (end 199.65 87.075) (width 0.12) (layer "In7.Cu") (net 91))
  (segment (start 189.125 89.35) (end 189.336809 89.561809) (width 0.12) (layer "In7.Cu") (net 91))
  (segment (start 199.1 86.525) (end 190.563224 86.525) (width 0.12) (layer "In7.Cu") (net 91))
  (segment (start 190.563224 86.525) (end 189.125 87.963224) (width 0.12) (layer "In7.Cu") (net 91))
  (segment (start 223.255 83.675) (end 217.95 83.675) (width 0.12) (layer "In7.Cu") (net 91))
  (segment (start 199.65 87.075) (end 199.1 86.525) (width 0.12) (layer "In7.Cu") (net 91))
  (segment (start 190.138129 89.561809) (end 190.636328 90.060008) (width 0.12) (layer "In7.Cu") (net 91))
  (segment (start 217.95 83.675) (end 214.55 87.075) (width 0.12) (layer "In7.Cu") (net 91))
  (segment (start 189.125 87.963224) (end 189.125 89.35) (width 0.12) (layer "In7.Cu") (net 91))
  (segment (start 189.336809 89.561809) (end 190.138129 89.561809) (width 0.12) (layer "In7.Cu") (net 91))
  (segment (start 163.595 120.656397) (end 163.595 122.24) (width 0.2) (layer "B.Cu") (net 92))
  (segment (start 163.595 122.24) (end 163.585 122.25) (width 0.2) (layer "B.Cu") (net 92))
  (segment (start 190.111577 96.560008) (end 190.136328 96.560008) (width 0.1) (layer "F.Cu") (net 93))
  (segment (start 189.612069 96.0605) (end 190.111577 96.560008) (width 0.1) (layer "F.Cu") (net 93))
  (via (at 189.612069 96.0605) (size 0.5) (drill 0.2) (layers "F.Cu" "B.Cu") (net 93))
  (via (at 209.37 104.28) (size 0.5) (drill 0.2) (layers "F.Cu" "B.Cu") (net 93))
  (via (at 236.85 126.55) (size 0.5) (drill 0.2) (layers "F.Cu" "B.Cu") (net 93))
  (segment (start 220.1 105.8) (end 218.220636 105.8) (width 0.1) (layer "In9.Cu") (net 93))
  (segment (start 217.767136 105.3465) (end 210.4365 105.3465) (width 0.1) (layer "In9.Cu") (net 93))
  (segment (start 210.4365 105.3465) (end 209.37 104.28) (width 0.1) (layer "In9.Cu") (net 93))
  (segment (start 218.220636 105.8) (end 217.767136 105.3465) (width 0.1) (layer "In9.Cu") (net 93))
  (segment (start 236.85 126.55) (end 236.31 126.01) (width 0.1) (layer "In9.Cu") (net 93))
  (segment (start 238 122.4) (end 238 116.123364) (width 0.1) (layer "In9.Cu") (net 93))
  (segment (start 236.1 115.2) (end 235.931 115.369) (width 0.1) (layer "In9.Cu") (net 93))
  (segment (start 236.31 124.09) (end 238 122.4) (width 0.1) (layer "In9.Cu") (net 93))
  (segment (start 237.076636 115.2) (end 236.1 115.2) (width 0.1) (layer "In9.Cu") (net 93))
  (segment (start 236.31 126.01) (end 236.31 124.09) (width 0.1) (layer "In9.Cu") (net 93))
  (segment (start 235.931 115.369) (end 229.669 115.369) (width 0.1) (layer "In9.Cu") (net 93))
  (segment (start 238 116.123364) (end 237.076636 115.2) (width 0.1) (layer "In9.Cu") (net 93))
  (segment (start 229.669 115.369) (end 220.1 105.8) (width 0.1) (layer "In9.Cu") (net 93))
  (segment (start 190.28 99.27) (end 190.28 101.08) (width 0.1) (layer "B.Cu") (net 93))
  (segment (start 191.050048 105.050048) (end 192.1 106.1) (width 0.1) (layer "B.Cu") (net 93))
  (segment (start 209.02 104.28) (end 209.37 104.28) (width 0.1) (layer "B.Cu") (net 93))
  (segment (start 190.28 101.08) (end 191.050048 101.850048) (width 0.1) (layer "B.Cu") (net 93))
  (segment (start 238.65 126.515) (end 237.685 126.515) (width 0.1) (layer "B.Cu") (net 93))
  (segment (start 237.685 126.515) (end 237.65 126.55) (width 0.1) (layer "B.Cu") (net 93))
  (segment (start 189.612069 96.0605) (end 189.612069 96.412069) (width 0.1) (layer "B.Cu") (net 93))
  (segment (start 191.050048 101.850048) (end 191.050048 105.050048) (width 0.1) (layer "B.Cu") (net 93))
  (segment (start 236.87 126.53) (end 237.64 126.53) (width 0.1) (layer "B.Cu") (net 93))
  (segment (start 191.066328 97.866328) (end 191.066328 98.483672) (width 0.1) (layer "B.Cu") (net 93))
  (segment (start 207.2 106.1) (end 209.02 104.28) (width 0.1) (layer "B.Cu") (net 93))
  (segment (start 192.1 106.1) (end 207.2 106.1) (width 0.1) (layer "B.Cu") (net 93))
  (segment (start 191.066328 98.483672) (end 190.28 99.27) (width 0.1) (layer "B.Cu") (net 93))
  (segment (start 236.85 126.55) (end 236.87 126.53) (width 0.1) (layer "B.Cu") (net 93))
  (segment (start 189.612069 96.412069) (end 191.066328 97.866328) (width 0.1) (layer "B.Cu") (net 93))
  (segment (start 164.915 118.066397) (end 164.865 118.116397) (width 0.2) (layer "B.Cu") (net 94))
  (segment (start 164.915 116.3) (end 164.915 118.066397) (width 0.2) (layer "B.Cu") (net 94))
  (segment (start 223.393336 115.731) (end 223.9155 115.731) (width 0.1) (layer "F.Cu") (net 95))
  (segment (start 222.917 115.731) (end 223.393336 115.731) (width 0.1) (layer "F.Cu") (net 95))
  (segment (start 174.136328 100.560008) (end 173.636328 101.060008) (width 0.1) (layer "F.Cu") (net 95))
  (via (at 223.393336 115.731) (size 0.5) (drill 0.2) (layers "F.Cu" "B.Cu") (net 95))
  (via (at 173.636328 101.060008) (size 0.5) (drill 0.2) (layers "F.Cu" "B.Cu") (net 95))
  (segment (start 173.2 102.377344) (end 173.636328 102.813672) (width 0.1) (layer "In9.Cu") (net 95))
  (segment (start 218.907454 108.060008) (end 223.420957 112.573512) (width 0.1) (layer "In9.Cu") (net 95))
  (segment (start 173.2 101.902366) (end 173.2 102.377344) (width 0.1) (layer "In9.Cu") (net 95))
  (segment (start 173.636328 101.466038) (end 173.2 101.902366) (width 0.1) (layer "In9.Cu") (net 95))
  (segment (start 174.125 104.4) (end 187.6 104.4) (width 0.1) (layer "In9.Cu") (net 95))
  (segment (start 173.636328 102.813672) (end 173.636328 103.911328) (width 0.1) (layer "In9.Cu") (net 95))
  (segment (start 173.636328 103.911328) (end 174.125 104.4) (width 0.1) (layer "In9.Cu") (net 95))
  (segment (start 223.422785 115.715496) (end 223.422785 112.573512) (width 0.1) (layer "In9.Cu") (net 95))
  (segment (start 187.6 104.4) (end 191.260008 108.060008) (width 0.1) (layer "In9.Cu") (net 95))
  (segment (start 191.260008 108.060008) (end 218.907454 108.060008) (width 0.1) (layer "In9.Cu") (net 95))
  (segment (start 173.636328 101.060008) (end 173.636328 101.466038) (width 0.1) (layer "In9.Cu") (net 95))
  (segment (start 237.993 119.375) (end 237.993 118.315) (width 0.1) (layer "F.Cu") (net 96))
  (segment (start 237.949 118.271) (end 237.037 118.271) (width 0.1) (layer "F.Cu") (net 96))
  (segment (start 189.467098 100.890778) (end 189.467098 101.060015) (width 0.1) (layer "F.Cu") (net 96))
  (segment (start 189.136328 100.560008) (end 189.467098 100.890778) (width 0.1) (layer "F.Cu") (net 96))
  (segment (start 236.252 118.271) (end 237.037 118.271) (width 0.1) (layer "F.Cu") (net 96))
  (via (at 189.467098 101.060015) (size 0.5) (drill 0.2) (layers "F.Cu" "B.Cu") (net 96))
  (via (at 237.037 118.271) (size 0.5) (drill 0.2) (layers "F.Cu" "B.Cu") (net 96))
  (segment (start 191.836328 106.560008) (end 220.057454 106.560008) (width 0.1) (layer "In9.Cu") (net 96))
  (segment (start 237.066449 118.255496) (end 237.5 117.821945) (width 0.1) (layer "In9.Cu") (net 96))
  (segment (start 189.467098 101.060015) (end 189.15 101.377113) (width 0.1) (layer "In9.Cu") (net 96))
  (segment (start 237.044504 116.244504) (end 229.743777 116.244504) (width 0.1) (layer "In9.Cu") (net 96))
  (segment (start 189.15 103.87368) (end 191.836328 106.560008) (width 0.1) (layer "In9.Cu") (net 96))
  (segment (start 237.5 116.7) (end 237.044504 116.244504) (width 0.1) (layer "In9.Cu") (net 96))
  (segment (start 237.5 117.821945) (end 237.5 116.7) (width 0.1) (layer "In9.Cu") (net 96))
  (segment (start 189.15 101.377113) (end 189.15 103.87368) (width 0.1) (layer "In9.Cu") (net 96))
  (segment (start 220.057454 106.560008) (end 229.741949 116.244504) (width 0.1) (layer "In9.Cu") (net 96))
  (segment (start 229.993 80.95) (end 228.745 80.95) (width 0.12) (layer "F.Cu") (net 97))
  (segment (start 228.745 80.45) (end 229.993 80.45) (width 0.12) (layer "F.Cu") (net 98))
  (segment (start 171.136328 101.560008) (end 170.636328 102.060008) (width 0.1) (layer "F.Cu") (net 99))
  (via (at 170.636328 102.060008) (size 0.5) (drill 0.2) (layers "F.Cu" "B.Cu") (net 99))
  (segment (start 170.636328 102.436328) (end 171.136328 102.936328) (width 0.1) (layer "B.Cu") (net 99))
  (segment (start 171.136328 102.936328) (end 171.136328 104.679208) (width 0.1) (layer "B.Cu") (net 99))
  (segment (start 171.136328 104.679208) (end 170.615528 105.200008) (width 0.1) (layer "B.Cu") (net 99))
  (segment (start 170.636328 102.060008) (end 170.636328 102.436328) (width 0.1) (layer "B.Cu") (net 99))
  (segment (start 190.136328 89.560008) (end 189.704527 89.991809) (width 0.127) (layer "F.Cu") (net 100))
  (via (at 189.704527 89.991809) (size 0.5) (drill 0.2) (layers "F.Cu" "B.Cu") (net 100))
  (segment (start 190.146336 89.55) (end 189.704527 89.991809) (width 0.2) (layer "B.Cu") (net 100))
  (segment (start 197.386328 92.325008) (end 194.61132 89.55) (width 0.2) (layer "B.Cu") (net 100))
  (segment (start 194.61132 89.55) (end 190.146336 89.55) (width 0.2) (layer "B.Cu") (net 100))
  (segment (start 250.63 77.5) (end 249.745 78.385) (width 0.2) (layer "F.Cu") (net 101))
  (segment (start 250.825 77.5) (end 250.63 77.5) (width 0.2) (layer "F.Cu") (net 101))
  (via (at 249.745 78.385) (size 0.5) (drill 0.2) (layers "F.Cu" "B.Cu") (net 101))
  (via (at 242.7 78.4) (size 0.5) (drill 0.2) (layers "F.Cu" "B.Cu") (net 101))
  (segment (start 243.6 78.4) (end 242.7 78.4) (width 0.2) (layer "In7.Cu") (net 101))
  (segment (start 249.31 77.95) (end 244.05 77.95) (width 0.2) (layer "In7.Cu") (net 101))
  (segment (start 249.745 78.385) (end 249.31 77.95) (width 0.2) (layer "In7.Cu") (net 101))
  (segment (start 244.05 77.95) (end 243.6 78.4) (width 0.2) (layer "In7.Cu") (net 101))
  (segment (start 241.885 78.4) (end 242.7 78.4) (width 0.2) (layer "B.Cu") (net 101))
  (segment (start 251.603 77.067) (end 251.036 76.5) (width 0.2) (layer "F.Cu") (net 102))
  (segment (start 250.995 78.385) (end 251.092 78.385) (width 0.2) (layer "F.Cu") (net 102))
  (segment (start 251.036 76.5) (end 250.825 76.5) (width 0.2) (layer "F.Cu") (net 102))
  (segment (start 251.092 78.385) (end 251.603 77.874) (width 0.2) (layer "F.Cu") (net 102))
  (segment (start 251.603 77.874) (end 251.603 77.067) (width 0.2) (layer "F.Cu") (net 102))
  (via (at 250.995 78.385) (size 0.5) (drill 0.2) (layers "F.Cu" "B.Cu") (net 102))
  (via (at 242.7 80.4) (size 0.5) (drill 0.2) (layers "F.Cu" "B.Cu") (net 102))
  (segment (start 244.6 79) (end 250.38 79) (width 0.2) (layer "In7.Cu") (net 102))
  (segment (start 242.7 80.4) (end 243.2 80.4) (width 0.2) (layer "In7.Cu") (net 102))
  (segment (start 243.2 80.4) (end 244.6 79) (width 0.2) (layer "In7.Cu") (net 102))
  (segment (start 250.38 79) (end 250.995 78.385) (width 0.2) (layer "In7.Cu") (net 102))
  (segment (start 241.885 80.4) (end 242.7 80.4) (width 0.2) (layer "B.Cu") (net 102))
  (segment (start 118.836328 101.372157) (end 118.836328 102.497157) (width 0.3) (layer "F.Cu") (net 103))
  (segment (start 119.154 101.054485) (end 118.836328 101.372157) (width 0.3) (layer "F.Cu") (net 103))
  (segment (start 220.535 121.865) (end 220.6 121.8) (width 0.2) (layer "F.Cu") (net 103))
  (segment (start 109.9492 100.134285) (end 109.936328 100.147157) (width 0.2) (layer "F.Cu") (net 103))
  (segment (start 109.9492 98.1) (end 109.9492 100.134285) (width 0.2) (layer "F.Cu") (net 103))
  (segment (start 111.36 110.5) (end 111.36 111.36) (width 0.4) (layer "F.Cu") (net 103))
  (segment (start 219.85 121.865) (end 220.535 121.865) (width 0.2) (layer "F.Cu") (net 103))
  (via (at 111.036328 111.310008) (size 0.5) (drill 0.2) (layers "F.Cu" "B.Cu") (net 103))
  (via (at 111.786328 111.310008) (size 0.5) (drill 0.2) (layers "F.Cu" "B.Cu") (net 103))
  (via (at 111.036328 112.310008) (size 0.5) (drill 0.2) (layers "F.Cu" "B.Cu") (net 103))
  (via (at 111.386328 111.810008) (size 0.5) (drill 0.2) (layers "F.Cu" "B.Cu") (net 103))
  (via (at 112.136328 111.810008) (size 0.5) (drill 0.2) (layers "F.Cu" "B.Cu") (net 103))
  (via (at 110.636328 112.810008) (size 0.5) (drill 0.2) (layers "F.Cu" "B.Cu") (net 103))
  (via (at 111.386328 112.810008) (size 0.5) (drill 0.2) (layers "F.Cu" "B.Cu") (net 103))
  (via (at 113.836328 107.510008) (size 0.5) (drill 0.2) (layers "F.Cu" "B.Cu") (net 103))
  (via (at 113.086328 107.510008) (size 0.5) (drill 0.2) (layers "F.Cu" "B.Cu") (net 103))
  (via (at 114.186328 107.010008) (size 0.5) (drill 0.2) (layers "F.Cu" "B.Cu") (net 103))
  (via (at 112.686328 107.010008) (size 0.5) (drill 0.2) (layers "F.Cu" "B.Cu") (net 103))
  (via (at 112.336328 107.510008) (size 0.5) (drill 0.2) (layers "F.Cu" "B.Cu") (net 103))
  (via (at 113.436328 107.010008) (size 0.5) (drill 0.2) (layers "F.Cu" "B.Cu") (net 103))
  (via (at 111.936328 107.010008) (size 0.5) (drill 0.2) (layers "F.Cu" "B.Cu") (net 103))
  (via (at 111.586328 107.510008) (size 0.5) (drill 0.2) (layers "F.Cu" "B.Cu") (net 103))
  (via (at 113.836328 106.510008) (size 0.5) (drill 0.2) (layers "F.Cu" "B.Cu") (net 103))
  (via (at 111.586328 106.510008) (size 0.5) (drill 0.2) (layers "F.Cu" "B.Cu") (net 103))
  (via (at 112.336328 106.510008) (size 0.5) (drill 0.2) (layers "F.Cu" "B.Cu") (net 103))
  (via (at 113.086328 106.510008) (size 0.5) (drill 0.2) (layers "F.Cu" "B.Cu") (net 103))
  (via (at 183.4 115.8) (size 0.5) (drill 0.2) (layers "F.Cu" "B.Cu") (net 103))
  (via (at 112.536328 117.147157) (size 0.5) (drill 0.2) (layers "F.Cu" "B.Cu") (net 103))
  (via (at 183.1 115.2) (size 0.5) (drill 0.2) (layers "F.Cu" "B.Cu") (net 103))
  (via (at 204.5 131.4) (size 0.5) (drill 0.2) (layers "F.Cu" "B.Cu") (net 103))
  (via (at 113.036328 117.947157) (size 0.5) (drill 0.2) (layers "F.Cu" "B.Cu") (net 103))
  (via (at 181.7 115.2) (size 0.5) (drill 0.2) (layers "F.Cu" "B.Cu") (net 103))
  (via (at 109.436328 117.147157) (size 0.5) (drill 0.2) (layers "F.Cu" "B.Cu") (net 103))
  (via (at 110.286328 111.310008) (size 0.5) (drill 0.2) (layers "F.Cu" "B.Cu") (net 103))
  (via (at 111.536328 117.147157) (size 0.5) (drill 0.2) (layers "F.Cu" "B.Cu") (net 103))
  (via (at 112.036328 117.947157) (size 0.5) (drill 0.2) (layers "F.Cu" "B.Cu") (free) (net 103))
  (via (at 118.911328 103.247157) (size 0.5) (drill 0.2) (layers "F.Cu" "B.Cu") (net 103))
  (via (at 180.6 115.8) (size 0.5) (drill 0.2) (layers "F.Cu" "B.Cu") (net 103))
  (via (at 111.536328 118.747157) (size 0.5) (drill 0.2) (layers "F.Cu" "B.Cu") (net 103))
  (via (at 179.9 115.8) (size 0.5) (drill 0.2) (layers "F.Cu" "B.Cu") (net 103))
  (via (at 117.911328 105.497157) (size 0.5) (drill 0.2) (layers "F.Cu" "B.Cu") (net 103))
  (via (at 179.2 115.8) (size 0.5) (drill 0.2) (layers "F.Cu" "B.Cu") (net 103))
  (via (at 114.036328 117.947157) (size 0.5) (drill 0.2) (layers "F.Cu" "B.Cu") (net 103))
  (via (at 117.911328 104.997157) (size 0.5) (drill 0.2) (layers "F.Cu" "B.Cu") (net 103))
  (via (at 205.5 133.2) (size 0.5) (drill 0.2) (layers "F.Cu" "B.Cu") (free) (net 103))
  (via (at 181 115.2) (size 0.5) (drill 0.2) (layers "F.Cu" "B.Cu") (net 103))
  (via (at 117.911328 103.997157) (size 0.5) (drill 0.2) (layers "F.Cu" "B.Cu") (net 103))
  (via (at 182.7 115.8) (size 0.5) (drill 0.2) (layers "F.Cu" "B.Cu") (net 103))
  (via (at 180.3 115.2) (size 0.5) (drill 0.2) (layers "F.Cu" "B.Cu") (net 103))
  (via (at 182 115.8) (size 0.5) (drill 0.2) (layers "F.Cu" "B.Cu") (net 103))
  (via (at 114.436328 118.747157) (size 0.5) (drill 0.2) (layers "F.Cu" "B.Cu") (net 103))
  (via (at 110.436328 117.147157) (size 0.5) (drill 0.2) (layers "F.Cu" "B.Cu") (net 103))
  (via (at 204.1 133.2) (size 0.5) (drill 0.2) (layers "F.Cu" "B.Cu") (net 103))
  (via (at 117.911328 104.497157) (size 0.5) (drill 0.2) (layers "F.Cu" "B.Cu") (net 103))
  (via (at 113.436328 117.147157) (size 0.5) (drill 0.2) (layers "F.Cu" "B.Cu") (net 103))
  (via (at 205.2 132.6) (size 0.5) (drill 0.2) (layers "F.Cu" "B.Cu") (net 103))
  (via (at 182.4 115.2) (size 0.5) (drill 0.2) (layers "F.Cu" "B.Cu") (net 103))
  (via (at 179.6 115.2) (size 0.5) (drill 0.2) (layers "F.Cu" "B.Cu") (net 103))
  (via (at 205.2 131.4) (size 0.5) (drill 0.2) (layers "F.Cu" "B.Cu") (free) (net 103))
  (via (at 109.936328 117.947157) (size 0.5) (drill 0.2) (layers "F.Cu" "B.Cu") (free) (net 103))
  (via (at 204.5 132.6) (size 0.5) (drill 0.2) (layers "F.Cu" "B.Cu") (net 103))
  (via (at 112.536328 118.747157) (size 0.5) (drill 0.2) (layers "F.Cu" "B.Cu") (net 103))
  (via (at 113.436328 118.747157) (size 0.5) (drill 0.2) (layers "F.Cu" "B.Cu") (net 103))
  (via (at 118.411328 103.247157) (size 0.5) (drill 0.2) (layers "F.Cu" "B.Cu") (net 103))
  (via (at 204.8 133.2) (size 0.5) (drill 0.2) (layers "F.Cu" "B.Cu") (net 103))
  (via (at 181.3 115.8) (size 0.5) (drill 0.2) (layers "F.Cu" "B.Cu") (net 103))
  (via (at 114.436328 117.147157) (size 0.5) (drill 0.2) (layers "F.Cu" "B.Cu") (net 103))
  (via (at 183.8 115.2) (size 0.5) (drill 0.2) (layers "F.Cu" "B.Cu") (net 103))
  (via (at 203.8 132.6) (size 0.5) (drill 0.2) (layers "F.Cu" "B.Cu") (net 103))
  (via (at 117.911328 103.247157) (size 0.5) (drill 0.2) (layers "F.Cu" "B.Cu") (net 103))
  (via (at 110.436328 118.747157) (size 0.5) (drill 0.2) (layers "F.Cu" "B.Cu") (net 103))
  (via (at 109.436328 118.747157) (size 0.5) (drill 0.2) (layers "F.Cu" "B.Cu") (net 103))
  (via (at 225.5 126.8) (size 0.5) (drill 0.2) (layers "F.Cu" "B.Cu") (net 103))
  (via (at 117.161328 104.997157) (size 0.5) (drill 0.2) (layers "F.Cu" "B.Cu") (net 103))
  (via (at 220.6 121.8) (size 0.5) (drill 0.2) (layers "F.Cu" "B.Cu") (net 103))
  (via (at 204.9 130.8) (size 0.5) (drill 0.2) (layers "F.Cu" "B.Cu") (net 103))
  (via (at 203.8 131.4) (size 0.5) (drill 0.2) (layers "F.Cu" "B.Cu") (net 103))
  (via (at 204.2 130.8) (size 0.5) (drill 0.2) (layers "F.Cu" "B.Cu") (net 103))
  (via (at 110.936328 117.947157) (size 0.5) (drill 0.2) (layers "F.Cu" "B.Cu") (net 103))
  (via (at 115.136328 117.947157) (size 0.5) (drill 0.2) (layers "F.Cu" "B.Cu") (net 103))
  (via (at 117.161328 105.497157) (size 0.5) (drill 0.2) (layers "F.Cu" "B.Cu") (net 103))
  (via (at 203.5 130.8) (size 0.5) (drill 0.2) (layers "F.Cu" "B.Cu") (net 103))
  (segment (start 228.8 125.2) (end 228.8 126.3) (width 0.2) (layer "B.Cu") (net 103))
  (segment (start 228.35 126.75) (end 227.75 126.75) (width 0.2) (layer "B.Cu") (net 103))
  (segment (start 227.75 124.85) (end 228.45 124.85) (width 0.2) (layer "B.Cu") (net 103))
  (segment (start 228.45 124.85) (end 228.8 125.2) (width 0.2) (layer "B.Cu") (net 103))
  (segment (start 225.515 126.785) (end 225.5 126.8) (width 0.2) (layer "B.Cu") (net 103))
  (segment (start 226.335 126.75) (end 226.3 126.785) (width 0.2) (layer "B.Cu") (net 103))
  (segment (start 227.75 126.75) (end 226.335 126.75) (width 0.2) (layer "B.Cu") (net 103))
  (segment (start 226.3 126.785) (end 225.515 126.785) (width 0.2) (layer "B.Cu") (net 103))
  (segment (start 228.8 126.3) (end 228.35 126.75) (width 0.2) (layer "B.Cu") (net 103))
  (segment (start 131.6 100.577) (end 131.6 101.3) (width 0.127) (layer "F.Cu") (net 104))
  (segment (start 120.896328 116.622157) (end 120.896328 115.887157) (width 0.15) (layer "F.Cu") (net 104))
  (segment (start 126.911328 109.772157) (end 132.774979 109.772157) (width 0.2) (layer "F.Cu") (net 104))
  (segment (start 120.896328 115.887157) (end 120.911328 115.872157) (width 0.15) (layer "F.Cu") (net 104))
  (via (at 123.911328 110.747157) (size 0.5) (drill 0.2) (layers "F.Cu" "B.Cu") (net 104))
  (via (at 120.911328 115.872157) (size 0.5) (drill 0.2) (layers "F.Cu" "B.Cu") (net 104))
  (segment (start 120.911328 114.997157) (end 123.911328 111.997157) (width 0.15) (layer "B.Cu") (net 104))
  (segment (start 123.911328 111.997157) (end 123.911328 110.747157) (width 0.15) (layer "B.Cu") (net 104))
  (segment (start 120.911328 115.872157) (end 120.911328 114.997157) (width 0.15) (layer "B.Cu") (net 104))
  (segment (start 118.651328 95.810008) (end 119.651328 95.810008) (width 0.45) (layer "F.Cu") (net 105))
  (segment (start 252.575 76.125) (end 252.575 76.5) (width 0.2) (layer "F.Cu") (net 106))
  (segment (start 252.25 75.8) (end 252.575 76.125) (width 0.2) (layer "F.Cu") (net 106))
  (via (at 252.25 75.8) (size 0.5) (drill 0.2) (layers "F.Cu" "B.Cu") (net 106))
  (via (at 242.6 82.5) (size 0.5) (drill 0.2) (layers "F.Cu" "B.Cu") (net 106))
  (segment (start 245.4 80.2) (end 243.1 82.5) (width 0.2) (layer "In7.Cu") (net 106))
  (segment (start 243.1 82.5) (end 242.6 82.5) (width 0.2) (layer "In7.Cu") (net 106))
  (segment (start 250.5 80.2) (end 245.4 80.2) (width 0.2) (layer "In7.Cu") (net 106))
  (segment (start 251.7 79) (end 250.5 80.2) (width 0.2) (layer "In7.Cu") (net 106))
  (segment (start 252.25 75.8) (end 251.7 76.35) (width 0.2) (layer "In7.Cu") (net 106))
  (segment (start 251.7 76.35) (end 251.7 79) (width 0.2) (layer "In7.Cu") (net 106))
  (segment (start 241.885 82.5) (end 242.6 82.5) (width 0.2) (layer "B.Cu") (net 106))
  (segment (start 119.896328 114.497157) (end 119.896328 115.497157) (width 0.15) (layer "F.Cu") (net 107))
  (segment (start 228.6 126.1) (end 226.7 124.2) (width 0.2) (layer "F.Cu") (net 108))
  (segment (start 236.75 123.3) (end 234.15 123.3) (width 0.2) (layer "F.Cu") (net 108))
  (segment (start 226.7 124.2) (end 226.7 123.55) (width 0.2) (layer "F.Cu") (net 108))
  (segment (start 236.75 123.3) (end 238.3 123.3) (width 0.2) (layer "F.Cu") (net 108))
  (segment (start 234.15 123.3) (end 231.35 126.1) (width 0.2) (layer "F.Cu") (net 108))
  (segment (start 231.35 126.1) (end 228.6 126.1) (width 0.2) (layer "F.Cu") (net 108))
  (segment (start 112.286328 116.022157) (end 110.796328 116.022157) (width 0.3) (layer "F.Cu") (net 109))
  (segment (start 116.286328 116.022157) (end 117.646328 116.022157) (width 0.15) (layer "F.Cu") (net 110))
  (segment (start 117.926328 117.747157) (end 117.926328 116.622157) (width 0.15) (layer "F.Cu") (net 110))
  (segment (start 117.926328 116.302157) (end 117.926328 116.622157) (width 0.15) (layer "F.Cu") (net 110))
  (segment (start 117.646328 116.022157) (end 117.926328 116.302157) (width 0.15) (layer "F.Cu") (net 110))
  (segment (start 156.557849 131.076396) (end 158.859998 131.076396) (width 0.2) (layer "B.Cu") (net 112))
  (segment (start 166.908925 131.05) (end 166.935321 131.076396) (width 0.2) (layer "B.Cu") (net 113))
  (segment (start 166.935321 131.076396) (end 169.600002 131.076396) (width 0.2) (layer "B.Cu") (net 113))
  (segment (start 240.4 125.6) (end 241.85 127.05) (width 0.2) (layer "F.Cu") (net 115))
  (segment (start 240.4 124.4) (end 240.4 125.6) (width 0.2) (layer "F.Cu") (net 115))
  (segment (start 241.85 127.05) (end 243.15 127.05) (width 0.2) (layer "F.Cu") (net 115))
  (via (at 240.4 124.4) (size 0.5) (drill 0.2) (layers "F.Cu" "B.Cu") (net 115))
  (segment (start 239.4 122.4) (end 239.4 123.4) (width 0.15) (layer "B.Cu") (net 115))
  (segment (start 239.4 123.4) (end 240.4 124.4) (width 0.15) (layer "B.Cu") (net 115))
  (segment (start 241.1 122.1) (end 239.7 122.1) (width 0.15) (layer "B.Cu") (net 115))
  (segment (start 241.585 121.2) (end 241.585 121.615) (width 0.15) (layer "B.Cu") (net 115))
  (segment (start 239.7 122.1) (end 239.4 122.4) (width 0.15) (layer "B.Cu") (net 115))
  (segment (start 241.585 121.615) (end 241.1 122.1) (width 0.15) (layer "B.Cu") (net 115))
  (segment (start 118.896328 116.622157) (end 119.926328 116.622157) (width 0.15) (layer "F.Cu") (net 118))
  (segment (start 228.9 122.8) (end 229.5 123.4) (width 0.2) (layer "F.Cu") (net 119))
  (segment (start 228.15 122.8) (end 228.9 122.8) (width 0.2) (layer "F.Cu") (net 119))
  (segment (start 229.5 123.4) (end 229.5 123.9) (width 0.127) (layer "F.Cu") (net 119))
  (segment (start 227.376259 123.020289) (end 227.679711 123.020289) (width 0.2) (layer "F.Cu") (net 119))
  (segment (start 227.679711 123.020289) (end 227.9 122.8) (width 0.2) (layer "F.Cu") (net 119))
  (segment (start 227.9 122.8) (end 228.15 122.8) (width 0.2) (layer "F.Cu") (net 119))
  (segment (start 229.5 123.9) (end 230.9 125.3) (width 0.127) (layer "F.Cu") (net 119))
  (via (at 227.376259 123.020289) (size 0.5) (drill 0.2) (layers "F.Cu" "B.Cu") (net 119))
  (segment (start 226.25 122.365) (end 227.052518 122.365) (width 0.2) (layer "B.Cu") (net 119))
  (segment (start 227.376259 122.688741) (end 228.065 122) (width 0.2) (layer "B.Cu") (net 119))
  (segment (start 227.376259 123.020289) (end 227.376259 122.688741) (width 0.2) (layer "B.Cu") (net 119))
  (segment (start 227.052518 122.365) (end 227.376259 122.688741) (width 0.2) (layer "B.Cu") (net 119))
  (segment (start 251.385 114.5) (end 251.525 114.5) (width 0.127) (layer "F.Cu") (net 120))
  (segment (start 207.8 99.9) (end 237.85 99.9) (width 0.127) (layer "F.Cu") (net 120))
  (segment (start 189.136328 102.560008) (end 189.136328 103.236328) (width 0.127) (layer "F.Cu") (net 120))
  (segment (start 190.35 104.45) (end 199.175 104.45) (width 0.127) (layer "F.Cu") (net 120))
  (segment (start 202.825 104.875) (end 207.8 99.9) (width 0.127) (layer "F.Cu") (net 120))
  (segment (start 199.175 104.45) (end 199.6 104.875) (width 0.127) (layer "F.Cu") (net 120))
  (segment (start 199.6 104.875) (end 202.825 104.875) (width 0.127) (layer "F.Cu") (net 120))
  (segment (start 251.525 114.5) (end 252.25 115.225) (width 0.127) (layer "F.Cu") (net 120))
  (segment (start 242.9 104.95) (end 242.9 114.5) (width 0.127) (layer "F.Cu") (net 120))
  (segment (start 237.85 99.9) (end 242.9 104.95) (width 0.127) (layer "F.Cu") (net 120))
  (segment (start 242.9 114.5) (end 242.925 114.525) (width 0.127) (layer "F.Cu") (net 120))
  (segment (start 189.136328 103.236328) (end 190.35 104.45) (width 0.127) (layer "F.Cu") (net 120))
  (via (at 242.925 114.525) (size 0.5) (drill 0.2) (layers "F.Cu" "B.Cu") (net 120))
  (via (at 252.25 115.225) (size 0.5) (drill 0.2) (layers "F.Cu" "B.Cu") (net 120))
  (segment (start 242.925 114.525) (end 244.1425 115.7425) (width 0.127) (layer "In5.Cu") (net 120))
  (segment (start 244.1425 115.7425) (end 251.7325 115.7425) (width 0.127) (layer "In5.Cu") (net 120))
  (segment (start 251.7325 115.7425) (end 252.25 115.225) (width 0.127) (layer "In5.Cu") (net 120))
  (segment (start 252.905 115.875) (end 252.9 115.875) (width 0.127) (layer "B.Cu") (net 120))
  (segment (start 252.9 115.875) (end 252.25 115.225) (width 0.127) (layer "B.Cu") (net 120))
  (segment (start 148.521328 107.747157) (end 149.161328 107.747157) (width 0.1) (layer "F.Cu") (net 126))
  (segment (start 173.136328 100.560008) (end 172.636328 101.060008) (width 0.1) (layer "F.Cu") (net 126))
  (via (at 149.161328 107.747157) (size 0.5) (drill 0.2) (layers "F.Cu" "B.Cu") (net 126))
  (via (at 172.636328 101.060008) (size 0.5) (drill 0.2) (layers "F.Cu" "B.Cu") (net 126))
  (via (at 253.5 89.8) (size 0.5) (drill 0.2) (layers "F.Cu" "B.Cu") (net 126))
  (segment (start 175.877366 92.225) (end 177.725 92.225) (width 0.1) (layer "In7.Cu") (net 126))
  (segment (start 188.451 95.625) (end 189.276 96.45) (width 0.1) (layer "In7.Cu") (net 126))
  (segment (start 190.15 96.15) (end 190.15 95.92) (width 0.1) (layer "In7.Cu") (net 126))
  (segment (start 172.619992 99.480008) (end 172.819992 99.480008) (width 0.1) (layer "In7.Cu") (net 126))
  (segment (start 183.15 92.35) (end 183.35 92.55) (width 0.1) (layer "In7.Cu") (net 126))
  (segment (start 189.276 96.45) (end 189.85 96.45) (width 0.1) (layer "In7.Cu") (net 126))
  (segment (start 185.05 92.55) (end 186.2 93.7) (width 0.1) (layer "In7.Cu") (net 126))
  (segment (start 193.385 95.065) (end 198.988 95.065) (width 0.1) (layer "In7.Cu") (net 126))
  (segment (start 183.35 92.55) (end 185.05 92.55) (width 0.1) (layer "In7.Cu") (net 126))
  (segment (start 192.951 95.499) (end 193.385 95.065) (width 0.1) (layer "In7.Cu") (net 126))
  (segment (start 182.622358 91.640008) (end 182.940008 91.640008) (width 0.1) (layer "In7.Cu") (net 126))
  (segment (start 181.359992 90.640008) (end 181.970298 90.640008) (width 0.1) (layer "In7.Cu") (net 126))
  (segment (start 180.7 91.3) (end 181.359992 90.640008) (width 0.1) (layer "In7.Cu") (net 126))
  (segment (start 172.636328 101.060008) (end 172.216328 100.640008) (width 0.1) (layer "In7.Cu") (net 126))
  (segment (start 182.216328 90.886038) (end 182.216328 91.233978) (width 0.1) (layer "In7.Cu") (net 126))
  (segment (start 187.60735 95.625) (end 188.451 95.625) (width 0.1) (layer "In7.Cu") (net 126))
  (segment (start 189.85 96.45) (end 190.15 96.15) (width 0.1) (layer "In7.Cu") (net 126))
  (segment (start 183.15 91.85) (end 183.15 92.35) (width 0.1) (layer "In7.Cu") (net 126))
  (segment (start 254 88.40603) (end 254 89.3) (width 0.1) (layer "In7.Cu") (net 126))
  (segment (start 175.216328 92.886038) (end 175.877366 92.225) (width 0.1) (layer "In7.Cu") (net 126))
  (segment (start 172.216328 100.640008) (end 172.216328 99.883672) (width 0.1) (layer "In7.Cu") (net 126))
  (segment (start 254 89.3) (end 253.5 89.8) (width 0.1) (layer "In7.Cu") (net 126))
  (segment (start 181.970298 90.640008) (end 182.216328 90.886038) (width 0.1) (layer "In7.Cu") (net 126))
  (segment (start 179.959992 91.640008) (end 180.3 91.3) (width 0.1) (layer "In7.Cu") (net 126))
  (segment (start 253.67397 88.08) (end 254 88.40603) (width 0.1) (layer "In7.Cu") (net 126))
  (segment (start 237.9 92.6) (end 242.42 88.08) (width 0.1) (layer "In7.Cu") (net 126))
  (segment (start 178.309992 91.640008) (end 179.959992 91.640008) (width 0.1) (layer "In7.Cu") (net 126))
  (segment (start 182.940008 91.640008) (end 183.15 91.85) (width 0.1) (layer "In7.Cu") (net 126))
  (segment (start 190.15 95.92) (end 190.571 95.499) (width 0.1) (layer "In7.Cu") (net 126))
  (segment (start 177.725 92.225) (end 178.309992 91.640008) (width 0.1) (layer "In7.Cu") (net 126))
  (segment (start 198.988 95.065) (end 201.453 92.6) (width 0.1) (layer "In7.Cu") (net 126))
  (segment (start 172.819992 99.480008) (end 175.216328 97.083672) (width 0.1) (layer "In7.Cu") (net 126))
  (segment (start 182.216328 91.233978) (end 182.622358 91.640008) (width 0.1) (layer "In7.Cu") (net 126))
  (segment (start 201.453 92.6) (end 237.9 92.6) (width 0.1) (layer "In7.Cu") (net 126))
  (segment (start 186.2 94.21765) (end 187.60735 95.625) (width 0.1) (layer "In7.Cu") (net 126))
  (segment (start 172.216328 99.883672) (end 172.619992 99.480008) (width 0.1) (layer "In7.Cu") (net 126))
  (segment (start 180.3 91.3) (end 180.7 91.3) (width 0.1) (layer "In7.Cu") (net 126))
  (segment (start 186.2 93.7) (end 186.2 94.21765) (width 0.1) (layer "In7.Cu") (net 126))
  (segment (start 190.571 95.499) (end 192.951 95.499) (width 0.1) (layer "In7.Cu") (net 126))
  (segment (start 242.42 88.08) (end 253.67397 88.08) (width 0.1) (layer "In7.Cu") (net 126))
  (segment (start 175.216328 97.083672) (end 175.216328 92.886038) (width 0.1) (layer "In7.Cu") (net 126))
  (segment (start 154 109) (end 154 106.25) (width 0.1) (layer "In9.Cu") (net 126))
  (segment (start 171.216328 101.833672) (end 171.569992 101.480008) (width 0.1) (layer "In9.Cu") (net 126))
  (segment (start 153.35 109.65) (end 154 109) (width 0.1) (layer "In9.Cu") (net 126))
  (segment (start 163.355 105.38) (end 163.745 105.77) (width 0.1) (layer "In9.Cu") (net 126))
  (segment (start 150.397157 107.747157) (end 152.3 109.65) (width 0.1) (layer "In9.Cu") (net 126))
  (segment (start 170.619992 102.480008) (end 170.810298 102.480008) (width 0.1) (layer "In9.Cu") (net 126))
  (segment (start 168.05 105.05) (end 170.619992 102.480008) (width 0.1) (layer "In9.Cu") (net 126))
  (segment (start 171.216328 102.073978) (end 171.216328 101.833672) (width 0.1) (layer "In9.Cu") (net 126))
  (segment (start 172.216328 101.480008) (end 172.636328 101.060008) (width 0.1) (layer "In9.Cu") (net 126))
  (segment (start 168.05 105.45) (end 168.05 105.05) (width 0.1) (layer "In9.Cu") (net 126))
  (segment (start 163.745 105.77) (end 167.73 105.77) (width 0.1) (layer "In9.Cu") (net 126))
  (segment (start 152.3 109.65) (end 153.35 109.65) (width 0.1) (layer "In9.Cu") (net 126))
  (segment (start 154.87 105.38) (end 163.355 105.38) (width 0.1) (layer "In9.Cu") (net 126))
  (segment (start 149.161328 107.747157) (end 150.397157 107.747157) (width 0.1) (layer "In9.Cu") (net 126))
  (segment (start 171.569992 101.480008) (end 172.216328 101.480008) (width 0.1) (layer "In9.Cu") (net 126))
  (segment (start 154 106.25) (end 154.87 105.38) (width 0.1) (layer "In9.Cu") (net 126))
  (segment (start 167.73 105.77) (end 168.05 105.45) (width 0.1) (layer "In9.Cu") (net 126))
  (segment (start 170.810298 102.480008) (end 171.216328 102.073978) (width 0.1) (layer "In9.Cu") (net 126))
  (segment (start 252.905 89.205) (end 253.5 89.8) (width 0.1) (layer "B.Cu") (net 126))
  (segment (start 173.136328 99.560008) (end 172.636328 100.060008) (width 0.1) (layer "F.Cu") (net 128))
  (segment (start 148.521328 106.622157) (end 149.161328 106.622157) (width 0.1) (layer "F.Cu") (net 128))
  (via (at 253.5 88.5) (size 0.5) (drill 0.2) (layers "F.Cu" "B.Cu") (net 128))
  (via (at 149.161328 106.622157) (size 0.5) (drill 0.2) (layers "F.Cu" "B.Cu") (net 128))
  (via (at 172.636328 100.060008) (size 0.5) (drill 0.2) (layers "F.Cu" "B.Cu") (net 128))
  (segment (start 182.216328 92.233978) (end 182.622358 92.640008) (width 0.1) (layer "In7.Cu") (net 128))
  (segment (start 185.7125 94.7125) (end 186.0875 94.7125) (width 0.1) (layer "In7.Cu") (net 128))
  (segment (start 182.622358 92.640008) (end 182.990008 92.640008) (width 0.1) (layer "In7.Cu") (net 128))
  (segment (start 182.990008 92.640008) (end 183.216328 92.866328) (width 0.1) (layer "In7.Cu") (net 128))
  (segment (start 172.636328 100.060008) (end 172.989992 100.060008) (width 0.1) (layer "In7.Cu") (net 128))
  (segment (start 182.216328 91.886038) (end 182.216328 92.233978) (width 0.1) (layer "In7.Cu") (net 128))
  (segment (start 201.776 92.95) (end 238.25 92.95) (width 0.1) (layer "In7.Cu") (net 128))
  (segment (start 185.2 93.8) (end 185.2 94.2) (width 0.1) (layer "In7.Cu") (net 128))
  (segment (start 238.25 92.95) (end 242.7 88.5) (width 0.1) (layer "In7.Cu") (net 128))
  (segment (start 176.216328 96.833672) (end 176.216328 92.886038) (width 0.1) (layer "In7.Cu") (net 128))
  (segment (start 180.4 91.6) (end 181.93029 91.6) (width 0.1) (layer "In7.Cu") (net 128))
  (segment (start 180.2 92.090306) (end 180.2 91.8) (width 0.1) (layer "In7.Cu") (net 128))
  (segment (start 180.2 91.8) (end 180.4 91.6) (width 0.1) (layer "In7.Cu") (net 128))
  (segment (start 185 93.6) (end 185.2 93.8) (width 0.1) (layer "In7.Cu") (net 128))
  (segment (start 186.0875 94.7125) (end 186.85 95.475) (width 0.1) (layer "In7.Cu") (net 128))
  (segment (start 190.735653 96.554653) (end 191.301306 95.989) (width 0.1) (layer "In7.Cu") (net 128))
  (segment (start 176.216328 92.886038) (end 176.551183 92.551183) (width 0.1) (layer "In7.Cu") (net 128))
  (segment (start 181.93029 91.6) (end 182.216328 91.886038) (width 0.1) (layer "In7.Cu") (net 128))
  (segment (start 242.7 88.5) (end 253.5 88.5) (width 0.1) (layer "In7.Cu") (net 128))
  (segment (start 183.58235 93.6) (end 185 93.6) (width 0.1) (layer "In7.Cu") (net 128))
  (segment (start 187.274 96.474) (end 188.819 96.474) (width 0.1) (layer "In7.Cu") (net 128))
  (segment (start 191.301306 95.989) (end 193.011 95.989) (width 0.1) (layer "In7.Cu") (net 128))
  (segment (start 189.065 96.72) (end 190.095 96.72) (width 0.1) (layer "In7.Cu") (net 128))
  (segment (start 193.54 95.46) (end 199.266 95.46) (width 0.1) (layer "In7.Cu") (net 128))
  (segment (start 186.85 95.475) (end 186.85 96.05) (width 0.1) (layer "In7.Cu") (net 128))
  (segment (start 190.735653 96.554653) (end 190.260347 96.554653) (width 0.1) (layer "In7.Cu") (net 128))
  (segment (start 183.216328 92.866328) (end 183.216328 93.233978) (width 0.1) (layer "In7.Cu") (net 128))
  (segment (start 176.551183 92.551183) (end 179.739123 92.551183) (width 0.1) (layer "In7.Cu") (net 128))
  (segment (start 190.260347 96.554653) (end 190.095 96.72) (width 0.1) (layer "In7.Cu") (net 128))
  (segment (start 193.011 95.989) (end 193.54 95.46) (width 0.1) (layer "In7.Cu") (net 128))
  (segment (start 185.2 94.2) (end 185.7125 94.7125) (width 0.1) (layer "In7.Cu") (net 128))
  (segment (start 172.989992 100.060008) (end 176.216328 96.833672) (width 0.1) (layer "In7.Cu") (net 128))
  (segment (start 186.85 96.05) (end 187.274 96.474) (width 0.1) (layer "In7.Cu") (net 128))
  (segment (start 199.266 95.46) (end 201.776 92.95) (width 0.1) (layer "In7.Cu") (net 128))
  (segment (start 183.216328 93.233978) (end 183.58235 93.6) (width 0.1) (layer "In7.Cu") (net 128))
  (segment (start 188.819 96.474) (end 189.065 96.72) (width 0.1) (layer "In7.Cu") (net 128))
  (segment (start 179.739123 92.551183) (end 180.2 92.090306) (width 0.1) (layer "In7.Cu") (net 128))
  (segment (start 149.789171 107.25) (end 149.161328 106.622157) (width 0.1) (layer "In9.Cu") (net 128))
  (segment (start 164.17 105.32) (end 163.8 104.95) (width 0.1) (layer "In9.Cu") (net 128))
  (segment (start 150.65 107.25) (end 149.789171 107.25) (width 0.1) (layer "In9.Cu") (net 128))
  (segment (start 154.7 104.95) (end 153.5 106.15) (width 0.1) (layer "In9.Cu") (net 128))
  (segment (start 153.5 106.15) (end 153.5 108.75) (width 0.1) (layer "In9.Cu") (net 128))
  (segment (start 172.636328 100.060008) (end 172.196336 100.5) (width 0.1) (layer "In9.Cu") (net 128))
  (segment (start 171.05 101.25) (end 170.8 101.5) (width 0.1) (layer "In9.Cu") (net 128))
  (segment (start 153.1 109.15) (end 152.55 109.15) (width 0.1) (layer "In9.Cu") (net 128))
  (segment (start 171.602366 100.5) (end 171.05 101.052366) (width 0.1) (layer "In9.Cu") (net 128))
  (segment (start 152.55 109.15) (end 150.65 107.25) (width 0.1) (layer "In9.Cu") (net 128))
  (segment (start 153.5 108.75) (end 153.1 109.15) (width 0.1) (layer "In9.Cu") (net 128))
  (segment (start 171.05 101.052366) (end 171.05 101.25) (width 0.1) (layer "In9.Cu") (net 128))
  (segment (start 167.45 104.652366) (end 167.45 105.05) (width 0.1) (layer "In9.Cu") (net 128))
  (segment (start 163.8 104.95) (end 154.7 104.95) (width 0.1) (layer "In9.Cu") (net 128))
  (segment (start 170.602366 101.5) (end 167.45 104.652366) (width 0.1) (layer "In9.Cu") (net 128))
  (segment (start 170.8 101.5) (end 170.602366 101.5) (width 0.1) (layer "In9.Cu") (net 128))
  (segment (start 172.196336 100.5) (end 171.602366 100.5) (width 0.1) (layer "In9.Cu") (net 128))
  (segment (start 167.45 105.05) (end 167.18 105.32) (width 0.1) (layer "In9.Cu") (net 128))
  (segment (start 167.18 105.32) (end 164.17 105.32) (width 0.1) (layer "In9.Cu") (net 128))
  (segment (start 252.935 87.935) (end 253.5 88.5) (width 0.1) (layer "B.Cu") (net 128))
  (segment (start 252.905 87.935) (end 252.935 87.935) (width 0.1) (layer "B.Cu") (net 128))
  (segment (start 149.072157 104.372157) (end 149.161302 104.461302) (width 0.1) (layer "F.Cu") (net 131))
  (segment (start 172.136328 99.560008) (end 171.636328 100.060008) (width 0.1) (layer "F.Cu") (net 131))
  (segment (start 148.521328 104.372157) (end 149.072157 104.372157) (width 0.1) (layer "F.Cu") (net 131))
  (segment (start 149.161302 104.461302) (end 149.161302 104.772178) (width 0.1) (layer "F.Cu") (net 131))
  (via (at 171.636328 100.060008) (size 0.5) (drill 0.2) (layers "F.Cu" "B.Cu") (net 131))
  (via (at 253.5 84.7) (size 0.5) (drill 0.2) (layers "F.Cu" "B.Cu") (net 131))
  (via (at 149.161302 104.772178) (size 0.5) (drill 0.2) (layers "F.Cu" "B.Cu") (net 131))
  (segment (start 198.710992 94.640008) (end 201.126 92.225) (width 0.1) (layer "In7.Cu") (net 131))
  (segment (start 190.120657 95.479343) (end 190.591 95.009) (width 0.1) (layer "In7.Cu") (net 131))
  (segment (start 172.056328 98.886038) (end 173.367366 97.575) (width 0.1) (layer "In7.Cu") (net 131))
  (segment (start 242.2 87.775) (end 244.925 87.775) (width 0.1) (layer "In7.Cu") (net 131))
  (segment (start 184.840008 91.640008) (end 186.216328 93.016328) (width 0.1) (layer "In7.Cu") (net 131))
  (segment (start 173.367366 97.575) (end 173.875 97.575) (width 0.1) (layer "In7.Cu") (net 131))
  (segment (start 186.216328 93.016328) (end 186.216328 93.233978) (width 0.1) (layer "In7.Cu") (net 131))
  (segment (start 179.625 91.35) (end 179.975 91) (width 0.1) (layer "In7.Cu") (net 131))
  (segment (start 252.39397 86.5) (end 253.5 85.39397) (width 0.1) (layer "In7.Cu") (net 131))
  (segment (start 188.919343 95.479343) (end 190.120657 95.479343) (width 0.1) (layer "In7.Cu") (net 131))
  (segment (start 246.66 87.71) (end 247.35397 87.71) (width 0.1) (layer "In7.Cu") (net 131))
  (segment (start 244.925 87.775) (end 245.325 87.375) (width 0.1) (layer "In7.Cu") (net 131))
  (segment (start 247.35397 87.71) (end 248.04 87.02397) (width 0.1) (layer "In7.Cu") (net 131))
  (segment (start 187.93 94.98) (end 188.42 94.98) (width 0.1) (layer "In7.Cu") (net 131))
  (segment (start 246.325 87.375) (end 246.66 87.71) (width 0.1) (layer "In7.Cu") (net 131))
  (segment (start 187.216328 94.266328) (end 187.93 94.98) (width 0.1) (layer "In7.Cu") (net 131))
  (segment (start 190.591 95.009) (end 191.093366 95.009) (width 0.1) (layer "In7.Cu") (net 131))
  (segment (start 186.810298 93.640008) (end 187.216328 94.046038) (width 0.1) (layer "In7.Cu") (net 131))
  (segment (start 182.70029 90.37) (end 183.216328 90.886038) (width 0.1) (layer "In7.Cu") (net 131))
  (segment (start 180.65 91) (end 181.28 90.37) (width 0.1) (layer "In7.Cu") (net 131))
  (segment (start 177.85 91.35) (end 179.625 91.35) (width 0.1) (layer "In7.Cu") (net 131))
  (segment (start 173.875 97.575) (end 174.1 97.35) (width 0.1) (layer "In7.Cu") (net 131))
  (segment (start 179.975 91) (end 180.65 91) (width 0.1) (layer "In7.Cu") (net 131))
  (segment (start 183.6 91.640008) (end 184.840008 91.640008) (width 0.1) (layer "In7.Cu") (net 131))
  (segment (start 248.2 86.5) (end 252.39397 86.5) (width 0.1) (layer "In7.Cu") (net 131))
  (segment (start 248.04 86.66) (end 248.2 86.5) (width 0.1) (layer "In7.Cu") (net 131))
  (segment (start 186.216328 93.233978) (end 186.622358 93.640008) (width 0.1) (layer "In7.Cu") (net 131))
  (segment (start 172.056328 99.640008) (end 172.056328 98.886038) (width 0.1) (layer "In7.Cu") (net 131))
  (segment (start 237.75 92.225) (end 242.2 87.775) (width 0.1) (layer "In7.Cu") (net 131))
  (segment (start 191.093366 95.009) (end 191.462358 94.640008) (width 0.1) (layer "In7.Cu") (net 131))
  (segment (start 177.35 91.85) (end 177.85 91.35) (width 0.1) (layer "In7.Cu") (net 131))
  (segment (start 174.1 93.190306) (end 175.440306 91.85) (width 0.1) (layer "In7.Cu") (net 131))
  (segment (start 191.462358 94.640008) (end 198.710992 94.640008) (width 0.1) (layer "In7.Cu") (net 131))
  (segment (start 174.1 97.35) (end 174.1 93.190306) (width 0.1) (layer "In7.Cu") (net 131))
  (segment (start 245.325 87.375) (end 246.325 87.375) (width 0.1) (layer "In7.Cu") (net 131))
  (segment (start 248.04 87.02397) (end 248.04 86.66) (width 0.1) (layer "In7.Cu") (net 131))
  (segment (start 186.622358 93.640008) (end 186.810298 93.640008) (width 0.1) (layer "In7.Cu") (net 131))
  (segment (start 181.28 90.37) (end 182.70029 90.37) (width 0.1) (layer "In7.Cu") (net 131))
  (segment (start 253.5 85.39397) (end 253.5 84.7) (width 0.1) (layer "In7.Cu") (net 131))
  (segment (start 183.216328 91.256336) (end 183.6 91.640008) (width 0.1) (layer "In7.Cu") (net 131))
  (segment (start 171.636328 100.060008) (end 172.056328 99.640008) (width 0.1) (layer "In7.Cu") (net 131))
  (segment (start 175.440306 91.85) (end 177.35 91.85) (width 0.1) (layer "In7.Cu") (net 131))
  (segment (start 183.216328 90.886038) (end 183.216328 91.256336) (width 0.1) (layer "In7.Cu") (net 131))
  (segment (start 188.42 94.98) (end 188.919343 95.479343) (width 0.1) (layer "In7.Cu") (net 131))
  (segment (start 187.216328 94.046038) (end 187.216328 94.266328) (width 0.1) (layer "In7.Cu") (net 131))
  (segment (start 201.126 92.225) (end 237.75 92.225) (width 0.1) (layer "In7.Cu") (net 131))
  (segment (start 169.969992 100.480008) (end 171.216328 100.480008) (width 0.1) (layer "In9.Cu") (net 131))
  (segment (start 152.5 103.85) (end 166.6 103.85) (width 0.1) (layer "In9.Cu") (net 131))
  (segment (start 171.216328 100.480008) (end 171.636328 100.060008) (width 0.1) (layer "In9.Cu") (net 131))
  (segment (start 149.161302 104.772178) (end 151.577822 104.772178) (width 0.1) (layer "In9.Cu") (net 131))
  (segment (start 151.577822 104.772178) (end 152.5 103.85) (width 0.1) (layer "In9.Cu") (net 131))
  (segment (start 166.6 103.85) (end 169.969992 100.480008) (width 0.1) (layer "In9.Cu") (net 131))
  (segment (start 252.925 84.125) (end 253.5 84.7) (width 0.1) (layer "B.Cu") (net 131))
  (segment (start 252.905 84.125) (end 252.925 84.125) (width 0.1) (layer "B.Cu") (net 131))
  (segment (start 149.574179 102.122157) (end 149.636328 102.060008) (width 0.1) (layer "F.Cu") (net 133))
  (segment (start 148.521328 102.122157) (end 149.574179 102.122157) (width 0.1) (layer "F.Cu") (net 133))
  (segment (start 172.136328 96.560008) (end 171.636328 97.060008) (width 0.1) (layer "F.Cu") (net 133))
  (via (at 253.5 83.2) (size 0.5) (drill 0.2) (layers "F.Cu" "B.Cu") (net 133))
  (via (at 171.636328 97.060008) (size 0.5) (drill 0.2) (layers "F.Cu" "B.Cu") (net 133))
  (via (at 149.636328 102.060008) (size 0.5) (drill 0.2) (layers "F.Cu" "B.Cu") (net 133))
  (segment (start 187.6 92.640008) (end 187.810298 92.640008) (width 0.1) (layer "In7.Cu") (net 133))
  (segment (start 179.279992 90.670008) (end 179.45 90.5) (width 0.1) (layer "In7.Cu") (net 133))
  (segment (start 188.216328 93.046038) (end 188.216328 93.241328) (width 0.1) (layer "In7.Cu") (net 133))
  (segment (start 246.7 85.4) (end 246.9 85.2) (width 0.1) (layer "In7.Cu") (net 133))
  (segment (start 187.216328 92.256336) (end 187.6 92.640008) (width 0.1) (layer "In7.Cu") (net 133))
  (segment (start 187.810298 92.640008) (end 188.216328 93.046038) (width 0.1) (layer "In7.Cu") (net 133))
  (segment (start 187.216328 91.886038) (end 187.216328 92.256336) (width 0.1) (layer "In7.Cu") (net 133))
  (segment (start 179.45 90.5) (end 180.4 90.5) (width 0.1) (layer "In7.Cu") (net 133))
  (segment (start 242.315 86.46) (end 246.29 86.46) (width 0.1) (layer "In7.Cu") (net 133))
  (segment (start 237.3 91.475) (end 242.315 86.46) (width 0.1) (layer "In7.Cu") (net 133))
  (segment (start 246.7 86.05) (end 246.7 85.4) (width 0.1) (layer "In7.Cu") (net 133))
  (segment (start 191.340008 93.640008) (end 191.525 93.825) (width 0.1) (layer "In7.Cu") (net 133))
  (segment (start 176.474784 90.670008) (end 179.279992 90.670008) (width 0.1) (layer "In7.Cu") (net 133))
  (segment (start 184.84235 89.86) (end 186.622358 91.640008) (width 0.1) (layer "In7.Cu") (net 133))
  (segment (start 172.216328 96.480008) (end 172.216328 92.886038) (width 0.1) (layer "In7.Cu") (net 133))
  (segment (start 186.970298 91.640008) (end 187.216328 91.886038) (width 0.1) (layer "In7.Cu") (net 133))
  (segment (start 172.216328 92.886038) (end 174.502366 90.6) (width 0.1) (layer "In7.Cu") (net 133))
  (segment (start 188.216328 93.241328) (end 188.615008 93.640008) (width 0.1) (layer "In7.Cu") (net 133))
  (segment (start 174.502366 90.6) (end 176.404776 90.6) (width 0.1) (layer "In7.Cu") (net 133))
  (segment (start 180.4 90.5) (end 181.04 89.86) (width 0.1) (layer "In7.Cu") (net 133))
  (segment (start 253.114926 84.509044) (end 253.114926 83.585074) (width 0.1) (layer "In7.Cu") (net 133))
  (segment (start 188.615008 93.640008) (end 191.340008 93.640008) (width 0.1) (layer "In7.Cu") (net 133))
  (segment (start 200.536 91.475) (end 237.3 91.475) (width 0.1) (layer "In7.Cu") (net 133))
  (segment (start 246.9 85.2) (end 252.42397 85.2) (width 0.1) (layer "In7.Cu") (net 133))
  (segment (start 246.29 86.46) (end 246.7 86.05) (width 0.1) (layer "In7.Cu") (net 133))
  (segment (start 198.186 93.825) (end 200.536 91.475) (width 0.1) (layer "In7.Cu") (net 133))
  (segment (start 186.622358 91.640008) (end 186.970298 91.640008) (width 0.1) (layer "In7.Cu") (net 133))
  (segment (start 176.404776 90.6) (end 176.474784 90.670008) (width 0.1) (layer "In7.Cu") (net 133))
  (segment (start 181.04 89.86) (end 184.84235 89.86) (width 0.1) (layer "In7.Cu") (net 133))
  (segment (start 171.636328 97.060008) (end 172.216328 96.480008) (width 0.1) (layer "In7.Cu") (net 133))
  (segment (start 253.114926 83.585074) (end 253.5 83.2) (width 0.1) (layer "In7.Cu") (net 133))
  (segment (start 191.525 93.825) (end 198.186 93.825) (width 0.1) (layer "In7.Cu") (net 133))
  (segment (start 252.42397 85.2) (end 253.114926 84.509044) (width 0.1) (layer "In7.Cu") (net 133))
  (segment (start 149.636328 102.060008) (end 157.389992 102.060008) (width 0.1) (layer "In9.Cu") (net 133))
  (segment (start 169.10603 99.5) (end 171.790306 99.5) (width 0.1) (layer "In9.Cu") (net 133))
  (segment (start 172.1 99.190306) (end 172.1 97.52368) (width 0.1) (layer "In9.Cu") (net 133))
  (segment (start 171.790306 99.5) (end 172.1 99.190306) (width 0.1) (layer "In9.Cu") (net 133))
  (segment (start 157.6 101.85) (end 166.75603 101.85) (width 0.1) (layer "In9.Cu") (net 133))
  (segment (start 157.389992 102.060008) (end 157.6 101.85) (width 0.1) (layer "In9.Cu") (net 133))
  (segment (start 172.1 97.52368) (end 171.636328 97.060008) (width 0.1) (layer "In9.Cu") (net 133))
  (segment (start 166.75603 101.85) (end 169.10603 99.5) (width 0.1) (layer "In9.Cu") (net 133))
  (segment (start 252.905 82.855) (end 253.25 83.2) (width 0.1) (layer "B.Cu") (net 133))
  (segment (start 253.25 83.2) (end 253.5 83.2) (width 0.1) (layer "B.Cu") (net 133))
  (segment (start 142.536328 99.762157) (end 142.536328 99.122157) (width 0.1) (layer "F.Cu") (net 135))
  (segment (start 172.136328 97.560008) (end 171.636328 98.060008) (width 0.1) (layer "F.Cu") (net 135))
  (via blind (at 142.536328 99.122157) (size 0.5) (drill 0.2) (layers "F.Cu" "In2.Cu") (net 135))
  (via (at 171.636328 98.060008) (size 0.5) (drill 0.2) (layers "F.Cu" "B.Cu") (net 135))
  (segment (start 169.75 101.45) (end 169.75 99.1) (width 0.1) (layer "In2.Cu") (net 135))
  (segment (start 142.5 99.158485) (end 142.5 101.1) (width 0.1) (layer "In2.Cu") (net 135))
  (segment (start 152.830008 102.480008) (end 154.25 103.9) (width 0.1) (layer "In2.Cu") (net 135))
  (segment (start 154.25 103.9) (end 167.3 103.9) (width 0.1) (layer "In2.Cu") (net 135))
  (segment (start 143.880008 102.480008) (end 152.830008 102.480008) (width 0.1) (layer "In2.Cu") (net 135))
  (segment (start 142.5 101.1) (end 143.880008 102.480008) (width 0.1) (layer "In2.Cu") (net 135))
  (segment (start 169.75 99.1) (end 170.209992 98.640008) (width 0.1) (layer "In2.Cu") (net 135))
  (segment (start 171.056328 98.640008) (end 171.636328 98.060008) (width 0.1) (layer "In2.Cu") (net 135))
  (segment (start 167.3 103.9) (end 169.75 101.45) (width 0.1) (layer "In2.Cu") (net 135))
  (segment (start 170.209992 98.640008) (end 171.056328 98.640008) (width 0.1) (layer "In2.Cu") (net 135))
  (segment (start 142.536328 99.122157) (end 142.5 99.158485) (width 0.1) (layer "In2.Cu") (net 135))
  (segment (start 171.136328 98.560008) (end 170.636328 99.060008) (width 0.1) (layer "F.Cu") (net 137))
  (segment (start 141.411328 99.762157) (end 141.411328 99.122157) (width 0.1) (layer "F.Cu") (net 137))
  (via blind (at 141.411328 99.122157) (size 0.5) (drill 0.2) (layers "F.Cu" "In2.Cu") (net 137))
  (via (at 170.636328 99.060008) (size 0.5) (drill 0.2) (layers "F.Cu" "B.Cu") (net 137))
  (segment (start 141.411328 99.122157) (end 141.636328 99.347157) (width 0.1) (layer "In2.Cu") (net 137))
  (segment (start 141.636328 99.347157) (end 141.636328 100.842866) (width 0.1) (layer "In2.Cu") (net 137))
  (segment (start 152.5625 102.75) (end 154.1125 104.3) (width 0.1) (layer "In2.Cu") (net 137))
  (segment (start 154.1125 104.3) (end 167.65 104.3) (width 0.1) (layer "In2.Cu") (net 137))
  (segment (start 170.636328 99.446514) (end 170.636328 99.060008) (width 0.1) (layer "In2.Cu") (net 137))
  (segment (start 170.116421 101.833579) (end 170.116421 99.966421) (width 0.1) (layer "In2.Cu") (net 137))
  (segment (start 141.636328 100.842866) (end 143.543462 102.75) (width 0.1) (layer "In2.Cu") (net 137))
  (segment (start 143.543462 102.75) (end 152.5625 102.75) (width 0.1) (layer "In2.Cu") (net 137))
  (segment (start 167.65 104.3) (end 170.116421 101.833579) (width 0.1) (layer "In2.Cu") (net 137))
  (segment (start 170.116421 99.966421) (end 170.636328 99.446514) (width 0.1) (layer "In2.Cu") (net 137))
  (segment (start 133.426328 102.622157) (end 132.786328 102.622157) (width 0.1) (layer "F.Cu") (net 139))
  (segment (start 172.15 106.8) (end 173.136328 105.813672) (width 0.1) (layer "F.Cu") (net 139))
  (segment (start 173.136328 102.560008) (end 173.136328 105.813672) (width 0.1) (layer "F.Cu") (net 139))
  (via (at 172.15 106.8) (size 0.5) (drill 0.2) (layers "F.Cu" "B.Cu") (net 139))
  (via blind (at 132.786328 102.622157) (size 0.5) (drill 0.2) (layers "F.Cu" "In2.Cu") (net 139))
  (segment (start 136.401657 102.601657) (end 132.806828 102.601657) (width 0.1) (layer "In2.Cu") (net 139))
  (segment (start 172.15 106.8) (end 169.95 109) (width 0.1) (layer "In2.Cu") (net 139))
  (segment (start 150.562328 108.217808) (end 148.617808 108.217808) (width 0.1) (layer "In2.Cu") (net 139))
  (segment (start 169.95 109) (end 151.34452 109) (width 0.1) (layer "In2.Cu") (net 139))
  (segment (start 132.806828 102.601657) (end 132.786328 102.622157) (width 0.1) (layer "In2.Cu") (net 139))
  (segment (start 151.34452 109) (end 150.562328 108.217808) (width 0.1) (layer "In2.Cu") (net 139))
  (segment (start 137.8 104) (end 136.401657 102.601657) (width 0.1) (layer "In2.Cu") (net 139))
  (segment (start 144.4 104) (end 137.8 104) (width 0.1) (layer "In2.Cu") (net 139))
  (segment (start 148.617808 108.217808) (end 144.4 104) (width 0.1) (layer "In2.Cu") (net 139))
  (segment (start 133.426328 105.872157) (end 132.786328 105.872157) (width 0.1) (layer "F.Cu") (net 141))
  (segment (start 173.05 106.7) (end 173.111336 106.7) (width 0.1) (layer "F.Cu") (net 141))
  (segment (start 173.650928 103.036208) (end 174.127128 102.560008) (width 0.1) (layer "F.Cu") (net 141))
  (segment (start 173.111336 106.7) (end 173.650928 106.160408) (width 0.1) (layer "F.Cu") (net 141))
  (segment (start 173.650928 106.160408) (end 173.650928 103.036208) (width 0.1) (layer "F.Cu") (net 141))
  (via (at 173.05 106.7) (size 0.5) (drill 0.2) (layers "F.Cu" "B.Cu") (net 141))
  (via blind (at 132.786328 105.872157) (size 0.5) (drill 0.2) (layers "F.Cu" "In2.Cu") (net 141))
  (segment (start 149.00132 109.4) (end 144.10132 104.5) (width 0.1) (layer "In2.Cu") (net 141))
  (segment (start 137.744736 104.5) (end 136.372579 105.872157) (width 0.1) (layer "In2.Cu") (net 141))
  (segment (start 170.35 109.4) (end 149.00132 109.4) (width 0.1) (layer "In2.Cu") (net 141))
  (segment (start 144.10132 104.5) (end 137.744736 104.5) (width 0.1) (layer "In2.Cu") (net 141))
  (segment (start 136.372579 105.872157) (end 132.786328 105.872157) (width 0.1) (layer "In2.Cu") (net 141))
  (segment (start 173.05 106.7) (end 170.35 109.4) (width 0.1) (layer "In2.Cu") (net 141))
  (segment (start 161.863477 97.297157) (end 163.448477 97.297157) (width 0.2) (layer "F.Cu") (net 143))
  (segment (start 163.486328 97.259306) (end 164.586328 97.259306) (width 0.2) (layer "F.Cu") (net 143))
  (segment locked (start 212.8985 121.734) (end 212.8975 121.735) (width 0.2) (layer "F.Cu") (net 143))
  (segment locked (start 212.8985 120.53) (end 212.8985 121.734) (width 0.2) (layer "F.Cu") (net 143))
  (segment locked (start 209.8985 120.505) (end 209.8985 121.709) (width 0.2) (layer "F.Cu") (net 143))
  (segment (start 156.686328 92.620008) (end 156.686328 91.720008) (width 0.15) (layer "F.Cu") (net 143))
  (segment (start 158.281047 79.577157) (end 158.724 79.134204) (width 0.2) (layer "F.Cu") (net 143))
  (segment (start 157.496328 79.577157) (end 158.281047 79.577157) (width 0.2) (layer "F.Cu") (net 143))
  (segment (start 156.520442 82.582127) (end 156.020443 83.082127) (width 0.2) (layer "F.Cu") (net 143))
  (segment (start 154.480801 79.596001) (end 154.9808 79.096001) (width 0.2) (layer "F.Cu") (net 143))
  (segment (start 171.136328 97.560008) (end 170.636328 98.060008) (width 0.2) (layer "F.Cu") (net 143))
  (segment (start 188.136328 98.560008) (end 187.636328 98.060008) (width 0.2) (layer "F.Cu") (net 143))
  (segment (start 184.136328 96.560008) (end 184.636328 97.060008) (width 0.2) (layer "F.Cu") (net 143))
  (segment (start 173.136328 83.560008) (end 173.114992 83.560008) (width 0.2) (layer "F.Cu") (net 143))
  (segment (start 184.636328 98.060008) (end 184.636328 97.060008) (width 0.2) (layer "F.Cu") (net 143))
  (segment (start 164.586328 97.259306) (end 165.425626 97.259306) (width 0.2) (layer "F.Cu") (net 143))
  (segment (start 179.136328 91.560008) (end 178.636328 92.060008) (width 0.2) (layer "F.Cu") (net 143))
  (segment (start 120.102128 75.751008) (end 120.768128 76.417008) (width 0.2) (layer "F.Cu") (net 143))
  (segment (start 252.575 78.055) (end 252.27 78.36) (width 0.2) (layer "F.Cu") (net 143))
  (segment (start 221.947 115.731) (end 221.285485 115.731) (width 0.2) (layer "F.Cu") (net 143))
  (segment (start 175.585 106.615) (end 175.2 107) (width 0.2) (layer "F.Cu") (net 143))
  (segment (start 252.55 127.86) (end 252.55 128.55) (width 0.127) (layer "F.Cu") (net 143))
  (segment (start 123.917728 73.160408) (end 122.972128 74.106008) (width 0.2) (layer "F.Cu") (net 143))
  (segment (start 177.866328 106.910008) (end 177.866328 109.210008) (width 0.2) (layer "F.Cu") (net 143))
  (segment (start 174.136328 96.560008) (end 173.636328 97.060008) (width 0.2) (layer "F.Cu") (net 143))
  (segment (start 153.66 107.645) (end 153.535 107.645) (width 0.15) (layer "F.Cu") (net 143))
  (segment (start 158.7 103.99) (end 158.7 103.441173) (width 0.15) (layer "F.Cu") (net 143))
  (segment (start 123.917728 72.140008) (end 124.806728 72.140008) (width 0.2) (layer "F.Cu") (net 143))
  (segment (start 154.149179 94.797157) (end 153.636328 95.310008) (width 0.2) (layer "F.Cu") (net 143))
  (segment (start 233.9255 115.731) (end 235.282 115.731) (width 0.1) (layer "F.Cu") (net 143))
  (segment (start 222.79 87.3) (end 223.81 87.3) (width 0.12) (layer "F.Cu") (net 143))
  (segment (start 159.41 109.295) (end 159.4 109.285) (width 0.1) (layer "F.Cu") (net 143))
  (segment (start 242.23 130.63) (end 242.2 130.6) (width 0.2) (layer "F.Cu") (net 143))
  (segment (start 172.136328 100.560008) (end 171.636328 101.060008) (width 0.2) (layer "F.Cu") (net 143))
  (segment (start 252.45 84.08) (end 252.295 84.235) (width 0.2) (layer "F.Cu") (net 143))
  (segment (start 221.803 113.352) (end 221.803 114.01) (width 0.2) (layer "F.Cu") (net 143))
  (segment (start 134.431328 107.407157) (end 136.805343 107.407157) (width 0.15) (layer "F.Cu") (net 143))
  (segment (start 155.117208 75.770208) (end 155.117208 77.660008) (width 0.3) (layer "F.Cu") (net 143))
  (segment (start 156.175 103.35) (end 156.35 103.175) (width 0.127) (layer "F.Cu") (net 143))
  (segment (start 147.55 108.8) (end 147.45 108.7) (width 0.2) (layer "F.Cu") (net 143))
  (segment (start 191.180008 87.560008) (end 191.64 88.02) (width 0.2) (layer "F.Cu") (net 143))
  (segment (start 242.31 128.09) (end 242.3 128.1) (width 0.2) (layer "F.Cu") (net 143))
  (segment (start 252.45 102.28) (end 252.245 102.485) (width 0.2) (layer "F.Cu") (net 143))
  (segment (start 244.05 125.55) (end 244.1 125.5) (width 0.2) (layer "F.Cu") (net 143))
  (segment (start 137.325 122.724502) (end 137.3 122.749502) (width 0.2) (layer "F.Cu") (net 143))
  (segment (start 172.136328 80.560008) (end 171.636328 80.060008) (width 0.127) (layer "F.Cu") (net 143))
  (segment (start 177.136328 85.560008) (end 176.636329 85.060009) (width 0.2) (layer "F.Cu") (net 143))
  (segment (start 138.35 122.699502) (end 138.3 122.749502) (width 0.2) (layer "F.Cu") (net 143))
  (segment (start 130.7 121.81) (end 130.7 122.749502) (width 0.2) (layer "F.Cu") (net 143))
  (segment (start 235.49 85.45) (end 233.55 85.45) (width 0.4) (layer "F.Cu") (net 143))
  (segment (start 252.6 89.825) (end 252.45 89.675) (width 0.2) (layer "F.Cu") (net 143))
  (segment (start 120.768128 76.417008) (end 122.520728 76.417008) (width 0.2) (layer "F.Cu") (net 143))
  (segment (start 165.425626 97.259306) (end 165.486328 97.320008) (width 0.2) (layer "F.Cu") (net 143))
  (segment (start 223.81 87.3) (end 223.81 86.75) (width 0.12) (layer "F.Cu") (net 143))
  (segment (start 252.625 108.9) (end 252.625 108.005) (width 0.2) (layer "F.Cu") (net 143))
  (segment (start 178.136328 98.560008) (end 177.636328 99.060008) (width 0.2) (layer "F.Cu") (net 143))
  (segment (start 238.919 118.271) (end 239.704 118.271) (width 0.1) (layer "F.Cu") (net 143))
  (segment (start 220.635 86.75) (end 220.635 86.01) (width 0.12) (layer "F.Cu") (net 143))
  (segment (start 152.8305 104.91) (end 153.24 104.91) (width 0.15) (layer "F.Cu") (net 143))
  (segment (start 182.136328 100.560008) (end 181.636328 100.060008) (width 0.2) (layer "F.Cu") (net 143))
  (segment (start 134.431328 108.012157) (end 134.426328 108.017157) (width 0.15) (layer "F.Cu") (net 143))
  (segment (start 131.8 121.81) (end 131.8 122.749502) (width 0.2) (layer "F.Cu") (net 143))
  (segment (start 134.421328 104.832157) (end 135.131328 104.832157) (width 0.15) (layer "F.Cu") (net 143))
  (segment (start 120.102128 74.106008) (end 120.102128 75.751008) (width 0.2) (layer "F.Cu") (net 143))
  (segment (start 177.851328 106.615) (end 177.866328 106.6) (width 0.2) (layer "F.Cu") (net 143))
  (segment (start 252.45 89.675) (end 252.45 89) (width 0.2) (layer "F.Cu") (net 143))
  (segment (start 223.81 87.85) (end 223.81 87.3) (width 0.12) (layer "F.Cu") (net 143))
  (segment (start 153.535 107.645) (end 153.28 107.9) (width 0.15) (layer "F.Cu") (net 143))
  (segment (start 153.625 104.525) (end 153.67 104.525) (width 0.15) (layer "F.Cu") (net 143))
  (segment (start 191.64 88.02) (end 192.676336 88.02) (width 0.2) (layer "F.Cu") (net 143))
  (segment (start 122.505128 72.140008) (end 123.917728 72.140008) (width 0.2) (layer "F.Cu") (net 143))
  (segment (start 220.635 86.01) (end 220.625 86) (width 0.12) (layer "F.Cu") (net 143))
  (segment (start 220.675 125.4) (end 221.365 125.4) (width 0.2) (layer "F.Cu") (net 143))
  (segment (start 252.45 107.83) (end 252.45 107) (width 0.2) (layer "F.Cu") (net 143))
  (segment (start 159.105 102.295) (end 159.09 102.28) (width 0.15) (layer "F.Cu") (net 143))
  (segment (start 162.7 103.431356) (end 162.7 104.025) (width 0.15) (layer "F.Cu") (net 143))
  (segment (start 252.45 95) (end 252.45 95.955) (width 0.2) (layer "F.Cu") (net 143))
  (segment (start 243.15 128.09) (end 242.31 128.09) (width 0.2) (layer "F.Cu") (net 143))
  (segment (start 132.9 121.81) (end 132.9 122.749502) (width 0.2) (layer "F.Cu") (net 143))
  (segment (start 176.136328 92.560008) (end 175.636328 93.060008) (width 0.2) (layer "F.Cu") (net 143))
  (segment (start 221.285485 115.731) (end 221.269328 115.747157) (width 0.2) (layer "F.Cu") (net 143))
  (segment (start 252.45 95.955) (end 252.245 96.16) (width 0.2) (layer "F.Cu") (net 143))
  (segment (start 143.031328 116.527157) (end 143.776328 116.527157) (width 0.15) (layer "F.Cu") (net 143))
  (segment (start 163.045678 103.085678) (end 162.7 103.431356) (width 0.15) (layer "F.Cu") (net 143))
  (segment (start 146.95 109.4) (end 146.8 109.4) (width 0.2) (layer "F.Cu") (net 143))
  (segment (start 221.947 118.271) (end 221.363171 118.271) (width 0.2) (layer "F.Cu") (net 143))
  (segment (start 145.046328 115.082157) (end 145.046328 115.717157) (width 0.15) (layer "F.Cu") (net 143))
  (segment (start 147.15 108.7) (end 147.05 108.8) (width 0.2) (layer "F.Cu") (net 143))
  (segment (start 221.363171 118.271) (end 221.339328 118.247157) (width 0.2) (layer "F.Cu") (net 143))
  (segment (start 175.136328 79.560008) (end 175.136328 79.476328) (width 0.127) (layer "F.Cu") (net 143))
  (segment (start 177.136328 95.560008) (end 176.636328 96.060008) (width 0.2) (layer "F.Cu") (net 143))
  (segment (start 135.1 121.81) (end 135.1 122.749502) (width 0.2) (layer "F.Cu") (net 143))
  (segment (start 138.8 119.175) (end 138.786328 119.161328) (width 0.2) (layer "F.Cu") (net 143))
  (segment (start 147.45 108.7) (end 147.15 108.7) (width 0.2) (layer "F.Cu") (net 143))
  (segment (start 250.99 113.925) (end 250.415 114.5) (width 0.127) (layer "F.Cu") (net 143))
  (segment (start 159.105 103.036173) (end 159.105 102.295) (width 0.15) (layer "F.Cu") (net 143))
  (segment (start 235.282 115.731) (end 235.282 114.992) (width 0.1) (layer "F.Cu") (net 143))
  (segment (start 147.05 108.8) (end 146.45 108.8) (width 0.2) (layer "F.Cu") (net 143))
  (segment (start 152.34 110.245) (end 152.985 110.245) (width 0.15) (layer "F.Cu") (net 143))
  (segment (start 138.35 121.81) (end 138.35 122.699502) (width 0.2) (layer "F.Cu") (net 143))
  (segment (start 255.515 90.1) (end 255.715 90.3) (width 0.127) (layer "F.Cu") (net 143))
  (segment (start 122.520728 76.417008) (end 122.972128 75.965608) (width 0.2) (layer "F.Cu") (net 143))
  (segment (start 238.919 117.001) (end 239.704 117.001) (width 0.1) (layer "F.Cu") (net 143))
  (segment (start 155.009179 94.797157) (end 154.149179 94.797157) (width 0.2) (layer "F.Cu") (net 143))
  (segment (start 146.45 108.8) (end 145.38 109.87) (width 0.2) (layer "F.Cu") (net 143))
  (segment (start 147.55 108.8) (end 146.95 109.4) (width 0.2) (layer "F.Cu") (net 143))
  (segment (start 176.136328 82.560008) (end 175.636328 82.060008) (width 0.2) (layer "F.Cu") (net 143))
  (segment (start 173.114992 83.560008) (end 172.625 84.05) (width 0.2) (layer "F.Cu") (net 143))
  (segment (start 140.161328 100.697157) (end 139.536328 100.697157) (width 0.15) (layer "F.Cu") (net 143))
  (segment (start 187.136328 95.560008) (end 187.636328 96.060008) (width 0.2) (layer "F.Cu") (net 143))
  (segment (start 186.136328 103.143672) (end 186.12 103.16) (width 0.1) (layer "F.Cu") (net 143))
  (segment (start 175.136328 79.476328) (end 174.77 79.11) (width 0.2) (layer "F.Cu") (net 143))
  (segment (start 143.776328 116.527157) (end 143.786328 116.517157) (width 0.15) (layer "F.Cu") (net 143))
  (segment (start 134.431328 107.407157) (end 134.431328 108.012157) (width 0.15) (layer "F.Cu") (net 143))
  (segment (start 140.161328 100.697157) (end 140.53 101.065829) (width 0.15) (layer "F.Cu") (net 143))
  (segment (start 252.45 83.1) (end 252.45 84.08) (width 0.2) (layer "F.Cu") (net 143))
  (segment (start 243.15 125.55) (end 244.05 125.55) (width 0.2) (layer "F.Cu") (net 143))
  (segment (start 222.71 86.09) (end 222.725 86.075) (width 0.12) (layer "F.Cu") (net 143))
  (segment (start 190.136328 92.560008) (end 190.636328 93.060008) (width 0.2) (layer "F.Cu") (net 143))
  (segment (start 111.173 108.95) (end 110.45 108.95) (width 0.127) (layer "F.Cu") (net 143))
  (segment (start 186.136328 102.560008) (end 186.136328 103.143672) (width 0.2) (layer "F.Cu") (net 143))
  (segment (start 222.71 86.75) (end 222.71 86.09) (width 0.12) (layer "F.Cu") (net 143))
  (segment (start 135.603485 104.37) (end 135.136328 104.837157) (width 0.15) (layer "F.Cu") (net 143))
  (segment (start 159.41 109.99) (end 159.41 109.295) (width 0.1) (layer "F.Cu") (net 143))
  (segment (start 138.786328 119.161328) (end 138.786328 118.222157) (width 0.2) (layer "F.Cu") (net 143))
  (segment (start 171.136328 77.560008) (end 170.65632 77.08) (width 0.2) (layer "F.Cu") (net 143))
  (segment (start 122.972128 75.965608) (end 122.972128 74.106008) (width 0.2) (layer "F.Cu") (net 143))
  (segment (start 137.325 121.8) (end 137.325 122.724502) (width 0.2) (layer "F.Cu") (net 143))
  (segment (start 222.71 86.75) (end 222.71 87.22) (width 0.12) (layer "F.Cu") (net 143))
  (segment (start 235.282 114.992) (end 235.259 114.969) (width 0.1) (layer "F.Cu") (net 143))
  (segment (start 176.136328 102.560008) (end 175.636328 103.060008) (width 0.2) (layer "F.Cu") (net 143))
  (segment (start 254.85 90.1) (end 255.515 90.1) (width 0.127) (layer "F.Cu") (net 143))
  (segment (start 191.136328 87.560008) (end 191.180008 87.560008) (width 0.2) (layer "F.Cu") (net 143))
  (segment (start 153.28 107.9) (end 152.82 107.9) (width 0.15) (layer "F.Cu") (net 143))
  (segment (start 176.05 106.615) (end 175.585 106.615) (width 0.2) (layer "F.Cu") (net 143))
  (segment (start 180.136328 94.560008) (end 179.636328 95.060008) (width 0.2) (layer "F.Cu") (net 143))
  (segment (start 155.103 75.756) (end 155.117208 75.770208) (width 0.3) (layer "F.Cu") (net 143))
  (segment (start 252.625 108.005) (end 252.45 107.83) (width 0.2) (layer "F.Cu") (net 143))
  (segment (start 254.851076 89.491703) (end 255.523297 89.491703) (width 0.127) (layer "F.Cu") (net 143))
  (segment (start 139.536328 100.697157) (end 139.516328 100.717157) (width 0.15) (layer "F.Cu") (net 143))
  (segment (start 192.676336 88.02) (end 192.695955 88.000381) (width 0.2) (layer "F.Cu") (net 143))
  (segment (start 158.7 103.441173) (end 159.105 103.036173) (width 0.15) (layer "F.Cu") (net 143))
  (segment (start 153.24 104.91) (end 153.625 104.525) (width 0.15) (layer "F.Cu") (net 143))
  (segment (start 152.985 110.245) (end 153.1 110.13) (width 0.15) (layer "F.Cu") (net 143))
  (segment (start 123.917728 72.140008) (end 123.917728 73.160408) (width 0.2) (layer "F.Cu") (net 143))
  (segment (start 145.38 109.87) (end 144.7175 109.87) (width 0.2) (layer "F.Cu") (net 143))
  (segment (start 222.71 87.22) (end 222.79 87.3) (width 0.12) (layer "F.Cu") (net 143))
  (segment (start 255.523297 89.491703) (end 255.715 89.3) (width 0.127) (layer "F.Cu") (net 143))
  (segment (start 179.136328 101.560008) (end 178.636328 102.060008) (width 0.2) (layer "F.Cu") (net 143))
  (segment (start 252.575 77.5) (end 252.575 78.055) (width 0.2) (layer "F.Cu") (net 143))
  (segment (start 136.805343 107.407157) (end 136.8425 107.37) (width 0.15) (layer "F.Cu") (net 143))
  (segment (start 252.45 101) (end 252.45 102.28) (width 0.2) (layer "F.Cu") (net 143))
  (segment (start 176.05 106.615) (end 177.851328 106.615) (width 0.2) (layer "F.Cu") (net 143))
  (segment (start 252.275 113.925) (end 250.99 113.925) (width 0.127) (layer "F.Cu") (net 143))
  (segment (start 243.15 130.63) (end 242.23 130.63) (width 0.2) (layer "F.Cu") (net 143))
  (segment (start 156.175 103.94) (end 156.175 103.35) (width 0.127) (layer "F.Cu") (net 143))
  (segment (start 171.709782 80.133462) (end 171.591865 80.133462) (width 0.2) (layer "F.Cu") (net 143))
  (segment (start 136.8425 104.37) (end 135.603485 104.37) (width 0.15) (layer "F.Cu") (net 143))
  (segment (start 174.136328 86.560008) (end 173.636328 86.060008) (width 0.2) (layer "F.Cu") (net 143))
  (segment (start 155.103 75.756) (end 154.3664 75.0194) (width 0.15) (layer "F.Cu") (net 143))
  (segment (start 185.136328 99.560008) (end 185.636328 100.060008) (width 0.2) (layer "F.Cu") (net 143))
  (segment (start 140.53 101.065829) (end 140.53 103.1825) (width 0.15) (layer "F.Cu") (net 143))
  (segment (start 252.295 84.235) (end 252.295 84.735) (width 0.2) (layer "F.Cu") (net 143))
  (segment (start 176.636329 85.060009) (end 176.467087 85.060009) (width 0.2) (layer "F.Cu") (net 143))
  (segment (start 175.136328 99.560008) (end 174.636328 100.060008) (width 0.2) (layer "F.Cu") (net 143))
  (segment (start 170.65632 77.08) (end 170.53 77.08) (width 0.2) (layer "F.Cu") (net 143))
  (segment (start 189.136328 101.560008) (end 189.636328 102.060008) (width 0.2) (layer "F.Cu") (net 143))
  (segment (start 181.136328 97.560008) (end 180.669171 98.027165) (width 0.2) (layer "F.Cu") (net 143))
  (segment (start 154.3664 75.0194) (end 152.8058 75.0194) (width 0.15) (layer "F.Cu") (net 143))
  (segment (start 172.136328 80.560008) (end 171.709782 80.133462) (width 0.2) (layer "F.Cu") (net 143))
  (via (at 154.672849 131.022098) (size 0.5) (drill 0.2) (layers "F.Cu" "B.Cu") (net 143))
  (via (at 165.323925 131.095702) (size 0.5) (drill 0.2) (layers "F.Cu" "B.Cu") (net 143))
  (via (at 168.086328 96.520008) (size 0.5) (drill 0.2) (layers "F.Cu" "B.Cu") (net 143))
  (via (at 168.086328 98.020008) (size 0.5) (drill 0.2) (layers "F.Cu" "B.Cu") (net 143))
  (via (at 165.486328 97.320008) (size 0.5) (drill 0.2) (layers "F.Cu" "B.Cu") (net 143))
  (via locked (at 212.8975 121.735) (size 0.5) (drill 0.2) (layers "F.Cu" "B.Cu") (net 143))
  (via locked (at 209.8975 121.71) (size 0.5) (drill 0.2) (layers "F.Cu" "B.Cu") (net 143))
  (via (at 156.686328 91.720008) (size 0.5) (drill 0.2) (layers "F.Cu" "B.Cu") (net 143))
  (via (at 158.724 79.134204) (size 0.5) (drill 0.2) (layers "F.Cu" "B.Cu") (net 143))
  (via locked (at 156.002242 83.090328) (size 0.5) (drill 0.2) (layers "F.Cu" "B.Cu") (net 143))
  (via locked (at 154.983928 79.087358) (size 0.5) (drill 0.2) (layers "F.Cu" "B.Cu") (net 143))
  (via (at 170.636328 98.060008) (size 0.5) (drill 0.2) (layers "F.Cu" "B.Cu") (net 143))
  (via (at 187.636328 98.060008) (size 0.5) (drill 0.2) (layers "F.Cu" "B.Cu") (net 143))
  (via (at 184.636328 98.060008) (size 0.5) (drill 0.2) (layers "F.Cu" "B.Cu") (net 143))
  (via (at 108.95 107.925) (size 0.5) (drill 0.2) (layers "F.Cu" "B.Cu") (net 143))
  (via (at 108.936328 108.910008) (size 0.5) (drill 0.2) (layers "F.Cu" "B.Cu") (net 143))
  (via (at 108.525 107.425) (size 0.5) (drill 0.2) (layers "F.Cu" "B.Cu") (net 143))
  (via (at 109.336328 109.410008) (size 0.5) (drill 0.2) (layers "F.Cu" "B.Cu") (net 143))
  (via (at 108.586328 109.410008) (size 0.5) (drill 0.2) (layers "F.Cu" "B.Cu") (net 143))
  (via (at 108.5 106.8) (size 0.5) (drill 0.2) (layers "F.Cu" "B.Cu") (net 143))
  (via (at 109.336328 108.410008) (size 0.5) (drill 0.2) (layers "F.Cu" "B.Cu") (net 143))
  (via (at 108.586328 108.410008) (size 0.5) (drill 0.2) (layers "F.Cu" "B.Cu") (net 143))
  (via (at 124.806728 72.140008) (size 0.5) (drill 0.2) (layers "F.Cu" "B.Cu") (net 143))
  (via (at 117.59 90.12) (size 0.5) (drill 0.2) (layers "F.Cu" "B.Cu") (net 143))
  (via (at 146.8 109.4) (size 0.5) (drill 0.2) (layers "F.Cu" "B.Cu") (net 143))
  (via (at 163.045678 103.085678) (size 0.5) (drill 0.2) (layers "F.Cu" "B.Cu") (net 143))
  (via (at 176.467087 85.060009) (size 0.5) (drill 0.2) (layers "F.Cu" "B.Cu") (net 143))
  (via (at 254.85 90.1) (size 0.5) (drill 0.2) (layers "F.Cu" "B.Cu") (net 143))
  (via (at 135.1 122.749502) (size 0.5) (drill 0.2) (layers "F.Cu" "B.Cu") (net 143))
  (via (at 143.786328 116.517157) (size 0.5) (drill 0.2) (layers "F.Cu" "B.Cu") (net 143))
  (via (at 175.2 107) (size 0.45) (drill 0.15) (layers "F.Cu" "B.Cu") (net 143))
  (via (at 174.636328 100.060008) (size 0.5) (drill 0.2) (layers "F.Cu" "B.Cu") (net 143))
  (via (at 244.1 125.5) (size 0.5) (drill 0.2) (layers "F.Cu" "B.Cu") (net 143))
  (via (at 138.3 122.749502) (size 0.5) (drill 0.2) (layers "F.Cu" "B.Cu") (net 143))
  (via (at 252.245 96.16) (size 0.5) (drill 0.2) (layers "F.Cu" "B.Cu") (net 143))
  (via (at 175.636328 82.060008) (size 0.5) (drill 0.2) (layers "F.Cu" "B.Cu") (net 143))
  (via (at 252.245 102.485) (size 0.5) (drill 0.2) (layers "F.Cu" "B.Cu") (net 143))
  (via (at 129.1505 90.1) (size 0.5) (drill 0.2) (layers "F.Cu" "B.Cu") (net 143))
  (via (at 156.35 103.175) (size 0.5) (drill 0.2) (layers "F.Cu" "B.Cu") (net 143))
  (via (at 256.5 72.5) (size 0.5) (drill 0.2) (layers "F.Cu" "B.Cu") (net 143))
  (via (at 179.636328 95.060008) (size 0.5) (drill 0.2) (layers "F.Cu" "B.Cu") (net 143))
  (via (at 253.4 71.95) (size 0.5) (drill 0.2) (layers "F.Cu" "B.Cu") (net 143))
  (via (at 155.986328 97.660008) (size 0.5) (drill 0.2) (layers "F.Cu" "B.Cu") (net 143))
  (via (at 173.636328 97.060008) (size 0.5) (drill 0.2) (layers "F.Cu" "B.Cu") (net 143))
  (via (at 181.636328 100.060008) (size 0.5) (drill 0.2) (layers "F.Cu" "B.Cu") (net 143))
  (via (at 242.2 130.6) (size 0.5) (drill 0.2) (layers "F.Cu" "B.Cu") (net 143))
  (via (at 152.8305 104.91) (size 0.5) (drill 0.2) (layers "F.Cu" "B.Cu") (net 143))
  (via (at 171.636328 101.060008) (size 0.5) (drill 0.2) (layers "F.Cu" "B.Cu") (net 143))
  (via (at 252.27 78.36) (size 0.5) (drill 0.2) (layers "F.Cu" "B.Cu") (net 143))
  (via (at 221.269328 115.747157) (size 0.5) (drill 0.2) (layers "F.Cu" "B.Cu") (net 143))
  (via (at 134.426328 108.017157) (size 0.5) (drill 0.2) (layers "F.Cu" "B.Cu") (net 143))
  (via (at 176.636328 96.060008) (size 0.5) (drill 0.2) (layers "F.Cu" "B.Cu") (net 143))
  (via (at 178.636328 102.060008) (size 0.5) (drill 0.2) (layers "F.Cu" "B.Cu") (net 143))
  (via (at 240.1 118.9) (size 0.5) (drill 0.2) (layers "F.Cu" "B.Cu") (net 143))
  (via (at 159.41 109.99) (size 0.5) (drill 0.2) (layers "F.Cu" "B.Cu") (net 143))
  (via (at 254.851076 89.491703) (size 0.5) (drill 0.2) (layers "F.Cu" "B.Cu") (net 143))
  (via (at 237.1 122.3) (size 0.5) (drill 0.2) (layers "F.Cu" "B.Cu") (net 143))
  (via (at 155.236328 85.910008) (size 0.5) (drill 0.2) (layers "F.Cu" "B.Cu") (net 143))
  (via (at 220.675 125.4) (size 0.5) (drill 0.2) (layers "F.Cu" "B.Cu") (net 143))
  (via (at 185.636328 100.060008) (size 0.5) (drill 0.2) (layers "F.Cu" "B.Cu") (net 143))
  (via (at 252.55 128.55) (size 0.5) (drill 0.2) (layers "F.Cu" "B.Cu") (net 143))
  (via (at 236.9 125.6) (size 0.5) (drill 0.2) (layers "F.Cu" "B.Cu") (net 143))
  (via (at 159.09 102.28) (size 0.5) (drill 0.2) (layers "F.Cu" "B.Cu") (net 143))
  (via (at 252.275 113.925) (size 0.5) (drill 0.2) (layers "F.Cu" "B.Cu") (net 143))
  (via (at 256.9 71.95) (size 0.5) (drill 0.2) (layers "F.Cu" "B.Cu") (net 143))
  (via (at 174.77 79.11) (size 0.5) (drill 0.2) (layers "F.Cu" "B.Cu") (net 143))
  (via (at 155.117208 77.660008) (size 0.5) (drill 0.2) (layers "F.Cu" "B.Cu") (net 143))
  (via (at 254.25 71.95) (size 0.5) (drill 0.2) (layers "F.Cu" "B.Cu") (net 143))
  (via (at 166.59 109.7995) (size 0.5) (drill 0.2) (layers "F.Cu" "B.Cu") (net 143))
  (via (at 256 71.95) (size 0.5) (drill 0.2) (layers "F.Cu" "B.Cu") (net 143))
  (via (at 170.53 77.08) (size 0.5) (drill 0.2) (layers "F.Cu" "B.Cu") (net 143))
  (via (at 252.6 89.825) (size 0.5) (drill 0.2) (layers "F.Cu" "B.Cu") (net 143))
  (via (at 135.136328 104.837157) (size 0.5) (drill 0.2) (layers "F.Cu" "B.Cu") (net 143))
  (via (at 198.393167 93.0495) (size 0.5) (drill 0.2) (layers "F.Cu" "B.Cu") (net 143))
  (via (at 139.516328 100.717157) (size 0.5) (drill 0.2) (layers "F.Cu" "B.Cu") (net 143))
  (via (at 222.725 86.075) (size 0.5) (drill 0.2) (layers "F.Cu" "B.Cu") (net 143))
  (via (at 255.15 71.95) (size 0.5) (drill 0.2) (layers "F.Cu" "B.Cu") (net 143))
  (via (at 177.636328 99.060008) (size 0.5) (drill 0.2) (layers "F.Cu" "B.Cu") (net 143))
  (via (at 172.625 84.05) (size 0.5) (drill 0.2) (layers "F.Cu" "B.Cu") (net 143))
  (via (at 190.636328 93.060008) (size 0.5) (drill 0.2) (layers "F.Cu" "B.Cu") (net 143))
  (via (at 235.259 114.969) (size 0.5) (drill 0.2) (layers "F.Cu" "B.Cu") (net 143))
  (via (at 137.3 122.749502) (size 0.5) (drill 0.2) (layers "F.Cu" "B.Cu") (net 143))
  (via (at 255.65 72.5) (size 0.5) (drill 0.2) (layers "F.Cu" "B.Cu") (net 143))
  (via (at 155.436328 89.760008) (size 0.5) (drill 0.2) (layers "F.Cu" "B.Cu") (net 143))
  (via (at 221.803 114.01) (size 0.5) (drill 0.2) (layers "F.Cu" "B.Cu") (net 143))
  (via (at 127 88.2) (size 0.5) (drill 0.2) (layers "F.Cu" "B.Cu") (net 143))
  (via (at 175.636328 103.060008) (size 0.5) (drill 0.2) (layers "F.Cu" "B.Cu") (net 143))
  (via (at 130.7 122.749502) (size 0.5) (drill 0.2) (layers "F.Cu" "B.Cu") (net 143))
  (via (at 254.7 72.5) (size 0.5) (drill 0.2) (layers "F.Cu" "B.Cu") (net 143))
  (via (at 221.339328 118.247157) (size 0.5) (drill 0.2) (layers "F.Cu" "B.Cu") (net 143))
  (via (at 252.295 84.735) (size 0.5) (drill 0.2) (layers "F.Cu" "B.Cu") (net 143))
  (via (at 253.85 72.5) (size 0.5) (drill 0.2) (layers "F.Cu" "B.Cu") (net 143))
  (via (at 145.046328 115.717157) (size 0.5) (drill 0.2) (layers "F.Cu" "B.Cu") (net 143))
  (via (at 173.636328 86.060008) (size 0.5) (drill 0.2) (layers "F.Cu" "B.Cu") (net 143))
  (via (at 153.636328 95.310008) (size 0.5) (drill 0.2) (layers "F.Cu" "B.Cu") (net 143))
  (via (at 235.49 85.45) (size 0.5) (drill 0.2) (layers "F.Cu" "B.Cu") (net 143))
  (via (at 192.695955 88.000381) (size 0.5) (drill 0.2) (layers "F.Cu" "B.Cu") (net 143))
  (via (at 180.669171 98.027165) (size 0.5) (drill 0.2) (layers "F.Cu" "B.Cu") (net 143))
  (via (at 242.3 128.1) (size 0.5) (drill 0.2) (layers "F.Cu" "B.Cu") (net 143))
  (via (at 239.704 118.271) (size 0.5) (drill 0.2) (layers "F.Cu" "B.Cu") (net 143))
  (via (at 152.34 110.245) (size 0.5) (drill 0.2) (layers "F.Cu" "B.Cu") (net 143))
  (via (at 138.8 119.175) (size 0.5) (drill 0.2) (layers "F.Cu" "B.Cu") (net 143))
  (via (at 178.636328 92.060008) (size 0.5) (drill 0.2) (layers "F.Cu" "B.Cu") (net 143))
  (via (at 239.704 117.001) (size 0.5) (drill 0.2) (layers "F.Cu" "B.Cu") (net 143))
  (via (at 120.76 91.09) (size 0.5) (drill 0.2) (layers "F.Cu" "B.Cu") (net 143))
  (via (at 160.086328 86.110008) (size 0.5) (drill 0.2) (layers "F.Cu" "B.Cu") (net 143))
  (via (at 171.591865 80.133462) (size 0.5) (drill 0.2) (layers "F.Cu" "B.Cu") (net 143))
  (via (at 134.75 119.25) (size 0.5) (drill 0.2) (layers "F.Cu" "B.Cu") (net 143))
  (via (at 220.625 86) (size 0.5) (drill 0.2) (layers "F.Cu" "B.Cu") (net 143))
  (via (at 152.486328 101.260008) (size 0.5) (drill 0.2) (layers "F.Cu" "B.Cu") (net 143))
  (via (at 175.636328 93.060008) (size 0.5) (drill 0.2) (layers "F.Cu" "B.Cu") (net 143))
  (via (at 252.625 108.9) (size 0.5) (drill 0.2) (layers "F.Cu" "B.Cu") (net 143))
  (via (at 152.82 107.9) (size 0.5) (drill 0.2) (layers "F.Cu" "B.Cu") (net 143))
  (via (at 186.12 103.16) (size 0.5) (drill 0.2) (layers "F.Cu" "B.Cu") (net 143))
  (via (at 187.636328 96.060008) (size 0.5) (drill 0.2) (layers "F.Cu" "B.Cu") (net 143))
  (via (at 121.58 91.09) (size 0.5) (drill 0.2) (layers "F.Cu" "B.Cu") (net 143))
  (via (at 132.9 122.749502) (size 0.5) (drill 0.2) (layers "F.Cu" "B.Cu") (net 143))
  (via (at 161.186326 86.160008) (size 0.5) (drill 0.2) (layers "F.Cu" "B.Cu") (net 143))
  (via (at 189.636328 102.060008) (size 0.5) (drill 0.2) (layers "F.Cu" "B.Cu") (net 143))
  (via (at 159.336328 86.160008) (size 0.5) (drill 0.2) (layers "F.Cu" "B.Cu") (net 143))
  (via (at 131.8 122.749502) (size 0.5) (drill 0.2) (layers "F.Cu" "B.Cu") (net 143))
  (segment (start 171.591865 80.133462) (end 171.566538 80.133462) (width 0.4) (layer "In3.Cu") (net 143))
  (segment (start 197.908675 92.565008) (end 190.434992 92.565008) (width 0.25) (layer "In3.Cu") (net 143))
  (segment (start 190.434992 92.565008) (end 190.3 92.7) (width 0.25) (layer "In3.Cu") (net 143))
  (segment (start 172.071 82.571) (end 175.125336 82.571) (width 0.4) (layer "In3.Cu") (net 143))
  (segment (start 190.410008 93.060008) (end 190.3 92.95) (width 0.25) (layer "In3.Cu") (net 143))
  (segment (start 198.393167 93.0495) (end 197.908675 92.565008) (width 0.25) (layer "In3.Cu") (net 143))
  (segment (start 190.3 92.7) (end 190.3 92.95) (width 0.25) (layer "In3.Cu") (net 143))
  (segment (start 190.636328 93.060008) (end 190.410008 93.060008) (width 0.25) (layer "In3.Cu") (net 143))
  (segment (start 175.125336 82.571) (end 175.636328 82.060008) (width 0.4) (layer "In3.Cu") (net 143))
  (segment (start 169.82 77.08) (end 169.6 77.3) (width 0.4) (layer "In3.Cu") (net 143))
  (segment (start 170.6 81.1) (end 169.9 81.1) (width 0.4) (layer "In3.Cu") (net 143))
  (segment (start 170.6 81.1) (end 172.071 82.571) (width 0.4) (layer "In3.Cu") (net 143))
  (segment (start 171.566538 80.133462) (end 170.6 81.1) (width 0.4) (layer "In3.Cu") (net 143))
  (segment (start 169.6 80.8) (end 169.6 77.3) (width 0.4) (layer "In3.Cu") (net 143))
  (segment (start 169.9 81.1) (end 169.6 80.8) (width 0.4) (layer "In3.Cu") (net 143))
  (segment (start 170.53 77.08) (end 169.82 77.08) (width 0.4) (layer "In3.Cu") (net 143))
  (segment (start 247.959268 74.6) (end 256.6 74.6) (width 1) (layer "In5.Cu") (net 143))
  (segment (start 256.6 74.6) (end 257.25 75.25) (width 1) (layer "In5.Cu") (net 143))
  (segment (start 252.6 89.825) (end 253.115 90.34) (width 0.2) (layer "In5.Cu") (net 143))
  (segment (start 255.63 109.065319) (end 254.964681 108.4) (width 0.2) (layer "In5.Cu") (net 143))
  (segment (start 235.49 85.45) (end 237.47 83.47) (width 1) (layer "In5.Cu") (net 143))
  (segment (start 255.85 85.35) (end 257.25 85.35) (width 0.2) (layer "In5.Cu") (net 143))
  (segment (start 254.994681 77.95) (end 255.63 78.585319) (width 0.2) (layer "In5.Cu") (net 143))
  (segment (start 222.725 86.075) (end 220.7 86.075) (width 0.3) (layer "In5.Cu") (net 143))
  (segment (start 255.63 78.594681) (end 256.175319 79.14) (width 0.2) (layer "In5.Cu") (net 143))
  (segment (start 237.47 83.47) (end 239.43 83.47) (width 1) (layer "In5.Cu") (net 143))
  (segment (start 257.64 95.56) (end 252.845 95.56) (width 0.2) (layer "In5.Cu") (net 143))
  (segment (start 226.125 86.075) (end 222.725 86.075) (width 0.4) (layer "In5.Cu") (net 143))
  (segment (start 253.07 103.31) (end 257.26 103.31) (width 0.2) (layer "In5.Cu") (net 143))
  (segment (start 255.63 109.074681) (end 255.63 109.065319) (width 0.2) (layer "In5.Cu") (net 143))
  (segment (start 256.175319 79.14) (end 257.64 79.14) (width 0.2) (layer "In5.Cu") (net 143))
  (segment (start 255.63 78.585319) (end 255.63 78.594681) (width 0.2) (layer "In5.Cu") (net 143))
  (segment (start 254.964681 108.4) (end 253.125 108.4) (width 0.2) (layer "In5.Cu") (net 143))
  (segment (start 226.75 85.45) (end 226.125 86.075) (width 0.4) (layer "In5.Cu") (net 143))
  (segment (start 252.68 77.95) (end 254.994681 77.95) (width 0.2) (layer "In5.Cu") (net 143))
  (segment (start 254.85 90.28) (end 254.85 90.1) (width 0.2) (layer "In5.Cu") (net 143))
  (segment (start 226.85 85.45) (end 226.75 85.45) (width 0.4) (layer "In5.Cu") (net 143))
  (segment (start 235.49 85.45) (end 226.85 85.45) (width 1) (layer "In5.Cu") (net 143))
  (segment (start 254.79 90.34) (end 254.85 90.28) (width 0.2) (layer "In5.Cu") (net 143))
  (segment (start 252.845 95.56) (end 252.245 96.16) (width 0.2) (layer "In5.Cu") (net 143))
  (segment (start 240.6 82.3) (end 240.6 75.399634) (width 1) (layer "In5.Cu") (net 143))
  (segment (start 255.905319 109.35) (end 255.63 109.074681) (width 0.2) (layer "In5.Cu") (net 143))
  (segment (start 220.7 86.075) (end 220.625 86) (width 0.3) (layer "In5.Cu") (net 143))
  (segment (start 255.85 85.35) (end 255.64 85.56) (width 0.2) (layer "In5.Cu") (net 143))
  (segment (start 257.53 114.45) (end 252.8 114.45) (width 0.2) (layer "In5.Cu") (net 143))
  (segment (start 240.6 75.399634) (end 242.509634 73.49) (width 1) (layer "In5.Cu") (net 143))
  (segment (start 253.115 90.34) (end 254.79 90.34) (width 0.2) (layer "In5.Cu") (net 143))
  (segment (start 252.27 78.36) (end 252.68 77.95) (width 0.2) (layer "In5.Cu") (net 143))
  (segment (start 253.125 108.4) (end 252.625 108.9) (width 0.2) (layer "In5.Cu") (net 143))
  (segment (start 253.12 85.56) (end 252.295 84.735) (width 0.2) (layer "In5.Cu") (net 143))
  (segment (start 252.245 102.485) (end 253.07 103.31) (width 0.2) (layer "In5.Cu") (net 143))
  (segment (start 246.849268 73.49) (end 247.959268 74.6) (width 1) (layer "In5.Cu") (net 143))
  (segment (start 257.45 109.35) (end 255.905319 109.35) (width 0.2) (layer "In5.Cu") (net 143))
  (segment (start 239.43 83.47) (end 240.6 82.3) (width 1) (layer "In5.Cu") (net 143))
  (segment (start 252.8 114.45) (end 252.275 113.925) (width 0.2) (layer "In5.Cu") (net 143))
  (segment (start 255.64 85.56) (end 253.12 85.56) (width 0.2) (layer "In5.Cu") (net 143))
  (segment (start 242.509634 73.49) (end 246.849268 73.49) (width 1) (layer "In5.Cu") (net 143))
  (segment (start 155.796328 96.320008) (end 156.586328 97.110008) (width 0.2) (layer "B.Cu") (net 143))
  (segment (start 155.371328 96.320008) (end 155.796328 96.320008) (width 0.2) (layer "B.Cu") (net 143))
  (segment (start 156.586328 97.110008) (end 156.586328 97.120008) (width 0.2) (layer "B.Cu") (net 143))
  (segment (start 156.586328 97.120008) (end 156.786328 97.320008) (width 0.2) (layer "B.Cu") (net 143))
  (segment (start 156.786328 97.320008) (end 165.486328 97.320008) (width 0.2) (layer "B.Cu") (net 143))
  (segment (start 155.587849 131.076396) (end 154.727147 131.076396) (width 0.2) (layer "B.Cu") (net 143))
  (segment (start 165.369627 131.05) (end 165.323925 131.095702) (width 0.2) (layer "B.Cu") (net 143))
  (segment (start 165.938925 131.05) (end 165.369627 131.05) (width 0.2) (layer "B.Cu") (net 143))
  (segment (start 167.271328 96.520008) (end 168.086328 96.520008) (width 0.2) (layer "B.Cu") (net 143))
  (segment (start 167.271328 98.020008) (end 168.086328 98.020008) (width 0.2) (layer "B.Cu") (net 143))
  (segment (start 154.371328 92.520008) (end 155.471328 92.520008) (width 0.2) (layer "B.Cu") (net 143))
  (segment (start 155.486328 92.535008) (end 156.486328 92.535008) (width 0.2) (layer "B.Cu") (net 143))
  (segment (start 156.686328 91.720008) (end 156.686328 92.335008) (width 0.2) (layer "B.Cu") (net 143))
  (segment (start 156.686328 92.335008) (end 156.486328 92.535008) (width 0.2) (layer "B.Cu") (net 143))
  (segment (start 156.002242 83.090328) (end 155.110928 83.090328) (width 0.15) (layer "B.Cu") (net 143))
  (segment (start 160.711326 86.635008) (end 161.186326 86.160008) (width 0.2) (layer "B.Cu") (net 143))
  (segment (start 175.65 84.675) (end 175.975 85) (width 0.2) (layer "B.Cu") (net 143))
  (segment (start 175.225 93.471336) (end 175.636328 93.060008) (width 0.2) (layer "B.Cu") (net 143))
  (segment (start 186.21632 100.64) (end 185.636328 100.060008) (width 0.2) (layer "B.Cu") (net 143))
  (segment (start 180.817006 98.175) (end 180.669171 98.027165) (width 0.2) (layer "B.Cu") (net 143))
  (segment (start 157.686328 85.835008) (end 158.236328 85.835008) (width 0.2) (layer "B.Cu") (net 143))
  (segment (start 170.02 101.66) (end 170.174992 101.505008) (width 0.15) (layer "B.Cu") (net 143))
  (segment (start 163.045678 103.464322) (end 162.9145 103.5955) (width 0.15) (layer "B.Cu") (net 143))
  (segment (start 174.07 99.59) (end 174.07 99.67) (width 0.15) (layer "B.Cu") (net 143))
  (segment (start 174.97 102.6) (end 175.05 102.6) (width 0.2) (layer "B.Cu") (net 143))
  (segment (start 185.636328 102.111328) (end 185.636328 101.960008) (width 0.2) (layer "B.Cu") (net 143))
  (segment (start 120.7325 91.1175) (end 120.76 91.09) (width 0.1) (layer "B.Cu") (net 143))
  (segment (start 178.17 101.56) (end 178.17 101.59368) (width 0.2) (layer "B.Cu") (net 143))
  (segment (start 174.236328 97.211328) (end 174.085008 97.060008) (width 0.2) (layer "B.Cu") (net 143))
  (segment (start 178.16 98.39) (end 178.16 98.536336) (width 0.2) (layer "B.Cu") (net 143))
  (segment (start 178.17 101.59368) (end 178.636328 102.060008) (width 0.2) (layer "B.Cu") (net 143))
  (segment (start 170.636328 97.808672) (end 170.636328 98.060008) (width 0.2) (layer "B.Cu") (net 143))
  (segment (start 173.636328 86.413672) (end 173.636328 86.060008) (width 0.2) (layer "B.Cu") (net 143))
  (segment (start 191.707 87.349) (end 191.707 87.357) (width 0.2) (layer "B.Cu") (net 143))
  (segment (start 171.075 77.625) (end 170.53 77.08) (width 0.2) (layer "B.Cu") (net 143))
  (segment (start 174.7 79.18) (end 174.77 79.11) (width 0.2) (layer "B.Cu") (net 143))
  (segment (start 236.92 125.58) (end 236.9 125.6) (width 0.2) (layer "B.Cu") (net 143))
  (segment (start 155.986328 97.265008) (end 156.376328 96.875008) (width 0.2) (layer "B.Cu") (net 143))
  (segment (start 159.636328 86.835008) (end 159.636328 86.763672) (width 0.2) (layer "B.Cu") (net 143))
  (segment (start 155.914499 103.610501) (end 155.914499 104.195501) (width 0.15) (layer "B.Cu") (net 143))
  (segment (start 237.65 122.83) (end 237.63 122.83) (width 0.2) (layer "B.Cu") (net 143))
  (segment (start 182.026336 99.67) (end 181.636328 100.060008) (width 0.2) (layer "B.Cu") (net 143))
  (segment (start 138.8 119.175) (end 138.8 118.9) (width 0.2) (layer "B.Cu") (net 143))
  (segment (start 184.495 98.201336) (end 184.636328 98.060008) (width 0.2) (layer "B.Cu") (net 143))
  (segment (start 182.15 99.67) (end 182.026336 99.67) (width 0.2) (layer "B.Cu") (net 143))
  (segment (start 164.6395 107.920815) (end 165.555815 107.920815) (width 0.2) (layer "B.Cu") (net 143))
  (segment (start 155.436328 89.760008) (end 155.436328 90.445008) (width 0.2) (layer "B.Cu") (net 143))
  (segment (start 117.2 89) (end 117.2 89.73) (width 0.2) (layer "B.Cu") (net 143))
  (segment (start 174.07 99.67) (end 174.460008 100.060008) (width 0.15) (layer "B.Cu") (net 143))
  (segment (start 134 121.45) (end 134 119.25) (width 0.2) (layer "B.Cu") (net 143))
  (segment (start 192.68 87.984426) (end 192.695955 88.000381) (width 0.2) (layer "B.Cu") (net 143))
  (segment (start 176.407078 85) (end 176.467087 85.060009) (width 0.2) (layer "B.Cu") (net 143))
  (segment (start 160.086328 86.313672) (end 160.086328 86.110008) (width 0.2) (layer "B.Cu") (net 143))
  (segment (start 173.47 86.65) (end 173.47 86.58) (width 0.2) (layer "B.Cu") (net 143))
  (segment (start 192.68 87.575) (end 192.68 87.984426) (width 0.2) (layer "B.Cu") (net 143))
  (segment (start 158.236328 85.835008) (end 158.686328 86.285008) (width 0.2) (layer "B.Cu") (net 143))
  (segment (start 186.125 103.155) (end 186.125 102.6) (width 0.2) (layer "B.Cu") (net 143))
  (segment (start 237.63 122.83) (end 237.1 122.3) (width 0.2) (layer "B.Cu") (net 143))
  (segment (start 158.724 79.84768) (end 158.724 79.134204) (width 0.15) (layer "B.Cu") (net 143))
  (segment (start 191.29 94.425) (end 191.29 93.71368) (width 0.2) (layer "B.Cu") (net 143))
  (segment (start 175.975 85) (end 176.407078 85) (width 0.2) (layer "B.Cu") (net 143))
  (segment (start 126.285 88.1) (end 126.285 88.585) (width 0.1) (layer "B.Cu") (net 143))
  (segment (start 171.175 81.03) (end 171.175 80.550327) (width 0.2) (layer "B.Cu") (net 143))
  (segment (start 174.085008 97.060008) (end 173.636328 97.060008) (width 0.2) (layer "B.Cu") (net 143))
  (segment (start 159.09 102.28) (end 159.16 102.35) (width 0.15) (layer "B.Cu") (net 143))
  (segment (start 156.35 103.175) (end 155.914499 103.610501) (width 0.15) (layer "B.Cu") (net 143))
  (segment (start 171.415 76.2) (end 171.41 76.2) (width 0.127) (layer "B.Cu") (net 143))
  (segment (start 172.65 84.075) (end 172.625 84.05) (width 0.2) (layer "B.Cu") (net 143))
  (segment (start 175.22632 81.65) (end 175.636328 82.060008) (width 0.2) (layer "B.Cu") (net 143))
  (segment (start 121.58 91.0825) (end 122.26 90.4025) (width 0.1) (layer "B.Cu") (net 143))
  (segment (start 126.55 88.85) (end 126.55 89.3375) (width 0.1) (layer "B.Cu") (net 143))
  (segment (start 163.045678 103.085678) (end 163.045678 103.464322) (width 0.15) (layer "B.Cu") (net 143))
  (segment (start 160.686328 86.635008) (end 160.711326 86.635008) (width 0.2) (layer "B.Cu") (net 143))
  (segment (start 107.4 113.1) (end 108.5 114.2) (width 0.3) (layer "B.Cu") (net 143))
  (segment (start 240.1 118.9) (end 240.3 119.1) (width 0.12) (layer "B.Cu") (net 143))
  (segment (start 159.636328 86.763672) (end 160.086328 86.313672) (width 0.2) (layer "B.Cu") (net 143))
  (segment (start 187.41 96.286336) (end 187.636328 96.060008) (width 0.2) (layer "B.Cu") (net 143))
  (segment (start 189.59 102.65) (end 189.59 102.106336) (width 0.2) (layer "B.Cu") (net 143))
  (segment (start 139.193 118.507) (end 139.765 118.507) (width 0.2) (layer "B.Cu") (net 143))
  (segment (start 134.035 119.25) (end 133.985 119.3) (width 0.2) (layer "B.Cu") (net 143))
  (segment (start 187.41 96.62) (end 187.41 96.286336) (width 0.2) (layer "B.Cu") (net 143))
  (segment (start 198.147659 93.295008) (end 198.393167 93.0495) (width 0.2) (layer "B.Cu") (net 143))
  (segment (start 152.82 107.9) (end 152.840815 107.920815) (width 0.15) (layer "B.Cu") (net 143))
  (segment (start 134.75 119.25) (end 134.035 119.25) (width 0.2) (layer "B.Cu") (net 143))
  (segment (start 165.965 108.265) (end 166.59 108.89) (width 0.2) (layer "B.Cu") (net 143))
  (segment (start 126.285 88.585) (end 126.55 88.85) (width 0.1) (layer "B.Cu") (net 143))
  (segment (start 192.350381 88.000381) (end 192.695955 88.000381) (width 0.2) (layer "B.Cu") (net 143))
  (segment (start 159.4145 109.9855) (end 159.41 109.99) (width 0.1) (layer "B.Cu") (net 143))
  (segment (start 176 95.395) (end 176 95.42368) (width 0.2) (layer "B.Cu") (net 143))
  (segment (start 240.3 119.785) (end 240.615 120.1) (width 0.12) (layer "B.Cu") (net 143))
  (segment (start 152.786328 95.035008) (end 153.361328 95.035008) (width 0.2) (layer "B.Cu") (net 143))
  (segment (start 154.185 79.1) (end 154.971286 79.1) (width 0.2) (layer "B.Cu") (net 143))
  (segment (start 108.586328 109.410008) (end 107.4 110.596336) (width 0.3) (layer "B.Cu") (net 143))
  (segment (start 191.707 87.357) (end 192.350381 88.000381) (width 0.2) (layer "B.Cu") (net 143))
  (segment (start 123.23 90.096) (end 122.5665 90.096) (width 0.1) (layer "B.Cu") (net 143))
  (segment (start 193.265 88.725) (end 193.265 88.569426) (width 0.2) (layer "B.Cu") (net 143))
  (segment (start 162.9145 103.5955) (end 162.9145 104.195501) (width 0.15) (layer "B.Cu") (net 143))
  (segment (start 120.76 91.09) (end 121.58 91.09) (width 0.1) (layer "B.Cu") (net 143))
  (segment (start 153.361328 95.035008) (end 153.636328 95.310008) (width 0.2) (layer "B.Cu") (net 143))
  (segment (start 174.714264 79.755) (end 174.7 79.755) (width 0.2) (layer "B.Cu") (net 143))
  (segment (start 170.174992 101.505008) (end 170.994992 101.505008) (width 0.15) (layer "B.Cu") (net 143))
  (segment (start 186.28 100.64) (end 186.21632 100.64) (width 0.2) (layer "B.Cu") (net 143))
  (segment (start 171.075 97.37) (end 170.636328 97.808672) (width 0.2) (layer "B.Cu") (net 143))
  (segment (start 122.5665 90.096) (end 122.26 90.4025) (width 0.1) (layer "B.Cu") (net 143))
  (segment (start 173.1 97.596336) (end 173.636328 97.060008) (width 0.2) (layer "B.Cu") (net 143))
  (segment (start 159.336328 86.160008) (end 158.811328 86.160008) (width 0.2) (layer "B.Cu") (net 143))
  (segment (start 121.58 91.09) (end 121.58 91.0825) (width 0.1) (layer "B.Cu") (net 143))
  (segment (start 173.47 86.58) (end 173.636328 86.413672) (width 0.2) (layer "B.Cu") (net 143))
  (segment (start 117.2 89.73) (end 117.59 90.12) (width 0.2) (layer "B.Cu") (net 143))
  (segment (start 166.59 108.89) (end 166.59 109.7995) (width 0.2) (layer "B.Cu") (net 143))
  (segment (start 175.145 80.185736) (end 174.714264 79.755) (width 0.2) (layer "B.Cu") (net 143))
  (segment (start 180.15132 95.575) (end 179.636328 95.060008) (width 0.2) (layer "B.Cu") (net 143))
  (segment (start 107.4 110.596336) (end 107.4 113.1) (width 0.3) (layer "B.Cu") (net 143))
  (segment (start 118.0975 88.7675) (end 117.4325 88.7675) (width 0.2) (layer "B.Cu") (net 143))
  (segment (start 180.669171 97.305829) (end 180.669171 98.027165) (width 0.2) (layer "B.Cu") (net 143))
  (segment (start 173.1 97.73) (end 173.1 97.596336) (width 0.2) (layer "B.Cu") (net 143))
  (segment (start 176 95.42368) (end 176.636328 96.060008) (width 0.2) (layer "B.Cu") (net 143))
  (segment (start 127 88.2) (end 126.385 88.2) (width 0.2) (layer "B.Cu") (net 143))
  (segment (start 175.559992 103.060008) (end 175.636328 103.060008) (width 0.2) (layer "B.Cu") (net 143))
  (segment (start 152.840559 104.920059) (end 152.8305 104.91) (width 0.15) (layer "B.Cu") (net 143))
  (segment (start 158.811328 86.160008) (end 158.686328 86.285008) (width 0.2) (layer "B.Cu") (net 143))
  (segment (start 175.225 93.755) (end 175.225 93.471336) (width 0.2) (layer "B.Cu") (net 143))
  (segment (start 186.12 103.16) (end 186.18 103.1) (width 0.2) (layer "B.Cu") (net 143))
  (segment (start 181.375 98.175) (end 180.817006 98.175) (width 0.2) (layer "B.Cu") (net 143))
  (segment (start 176.467087 84.757913) (end 176.467087 85.060009) (width 0.2) (layer "B.Cu") (net 143))
  (segment (start 174.236328 97.360008) (end 174.236328 97.211328) (width 0.2) (layer "B.Cu") (net 143))
  (segment (start 171.439992 101.060008) (end 171.636328 101.060008) (width 0.15) (layer "B.Cu") (net 143))
  (segment (start 155.236328 85.910008) (end 155.236328 85.463672) (width 0.2) (layer "B.Cu") (net 143))
  (segment (start 176.825 84.4) (end 176.467087 84.757913) (width 0.2) (layer "B.Cu") (net 143))
  (segment (start 178.05 91.905) (end 178.48132 91.905) (width 0.2) (layer "B.Cu") (net 143))
  (segment (start 175.145 81.65) (end 175.22632 81.65) (width 0.2) (layer "B.Cu") (net 143))
  (segment (start 192.88 87.375) (end 192.68 87.575) (width 0.2) (layer "B.Cu") (net 143))
  (segment (start 155.574992 85.125008) (end 156.186328 85.125008) (width 0.2) (layer "B.Cu") (net 143))
  (segment (start 154.971286 79.1) (end 154.983928 79.087358) (width 0.2) (layer "B.Cu") (net 143))
  (segment (start 197.386328 93.295008) (end 198.147659 93.295008) (width 0.2) (layer "B.Cu") (net 143))
  (segment (start 128.2625 90.55) (end 128.7005 90.55) (width 0.1) (layer "B.Cu") (net 143))
  (segment (start 191.29 93.71368) (end 190.636328 93.060008) (width 0.2) (layer "B.Cu") (net 143))
  (segment (start 186.18 103.1) (end 187.02 103.1) (width 0.2) (layer "B.Cu") (net 143))
  (segment (start 240.3 119.1) (end 240.3 119.785) (width 0.12) (layer "B.Cu") (net 143))
  (segment (start 187.42 97.84368) (end 187.636328 98.060008) (width 0.2) (layer "B.Cu") (net 143))
  (segment (start 154.371328 92.520008) (end 154.371328 94.575008) (width 0.2) (layer "B.Cu") (net 143))
  (segment (start 171.41 76.2) (end 170.53 77.08) (width 0.127) (layer "B.Cu") (net 143))
  (segment (start 186.12 103.16) (end 186.125 103.155) (width 0.2) (layer "B.Cu") (net 143))
  (segment (start 172.65 84.73) (end 172.65 84.075) (width 0.2) (layer "B.Cu") (net 143))
  (segment (start 119.81 90.9075) (end 120.02 91.1175) (width 0.1) (layer "B.Cu") (net 143))
  (segment (start 174.460008 100.060008) (end 174.636328 100.060008) (width 0.15) (layer "B.Cu") (net 143))
  (segment (start 119.81 89.98) (end 119.81 90.9075) (width 0.1) (layer "B.Cu") (net 143))
  (segment (start 170.994992 101.505008) (end 171.439992 101.060008) (width 0.15) (layer "B.Cu") (net 143))
  (segment (start 165.555815 107.920815) (end 165.9 108.265) (width 0.2) (layer "B.Cu") (net 143))
  (segment (start 178.48132 91.905) (end 178.636328 92.060008) (width 0.2) (layer "B.Cu") (net 143))
  (segment (start 189.59 102.106336) (end 189.636328 102.060008) (width 0.2) (layer "B.Cu") (net 143))
  (segment (start 117.4325 88.7675) (end 117.2 89) (width 0.2) (layer "B.Cu") (net 143))
  (segment (start 180.95 97.02) (end 180.95 97.025) (width 0.2) (layer "B.Cu") (net 143))
  (segment (start 180.95 97.025) (end 180.669171 97.305829) (width 0.2) (layer "B.Cu") (net 143))
  (segment (start 155.236328 85.463672) (end 155.574992 85.125008) (width 0.2) (layer "B.Cu") (net 143))
  (segment (start 165.9 108.265) (end 165.965 108.265) (width 0.2) (layer "B.Cu") (net 143))
  (segment (start 112.1 114.2) (end 112.9 113.4) (width 0.3) (layer "B.Cu") (net 143))
  (segment (start 180.33 95.575) (end 180.15132 95.575) (width 0.2) (layer "B.Cu") (net 143))
  (segment (start 155.986328 97.660008) (end 155.986328 97.265008) (width 0.2) (layer "B.Cu") (net 143))
  (segment (start 158.714992 86.285008) (end 158.686328 86.285008) (width 0.2) (layer "B.Cu") (net 143))
  (segment (start 112.9 113.4) (end 114.3 113.4) (width 0.3) (layer "B.Cu") (net 143))
  (segment (start 108.5 114.2) (end 112.1 114.2) (width 0.3) (layer "B.Cu") (net 143))
  (segment (start 159.16 102.981173) (end 158.9145 103.226672) (width 0.15) (layer "B.Cu") (net 143))
  (segment (start 175.05 102.6) (end 175.510008 103.060008) (width 0.2) (layer "B.Cu") (net 143))
  (segment (start 184.495 98.725) (end 184.495 98.201336) (width 0.2) (layer "B.Cu") (net 143))
  (segment (start 186.125 102.6) (end 185.636328 102.111328) (width 0.2) (layer "B.Cu") (net 143))
  (segment (start 175.645 84.675) (end 175.65 84.675) (width 0.2) (layer "B.Cu") (net 143))
  (segment (start 187.42 97.425) (end 187.42 97.84368) (width 0.2) (layer "B.Cu") (net 143))
  (segment (start 178.16 98.536336) (end 177.636328 99.060008) (width 0.2) (layer "B.Cu") (net 143))
  (segment (start 152.840815 107.920815) (end 153.6895 107.920815) (width 0.15) (layer "B.Cu") (net 143))
  (segment (start 174.7 79.755) (end 174.7 79.18) (width 0.2) (layer "B.Cu") (net 143))
  (segment (start 237.65 125.58) (end 236.92 125.58) (width 0.2) (layer "B.Cu") (net 143))
  (segment (start 175.510008 103.060008) (end 175.636328 103.060008) (width 0.2) (layer "B.Cu") (net 143))
  (segment (start 153.6895 104.920059) (end 152.840559 104.920059) (width 0.15) (layer "B.Cu") (net 143))
  (segment (start 193.265 88.569426) (end 192.695955 88.000381) (width 0.2) (layer "B.Cu") (net 143))
  (segment (start 171.175 80.550327) (end 171.591865 80.133462) (width 0.2) (layer "B.Cu") (net 143))
  (segment (start 159.4145 109.145499) (end 159.4145 109.9855) (width 0.1) (layer "B.Cu") (net 143))
  (segment (start 159.16 102.35) (end 159.16 102.981173) (width 0.15) (layer "B.Cu") (net 143))
  (segment (start 152.486328 101.260008) (end 153.07203 101.260008) (width 0.2) (layer "B.Cu") (net 143))
  (segment (start 138.8 118.9) (end 139.193 118.507) (width 0.2) (layer "B.Cu") (net 143))
  (segment (start 171.075 77.78) (end 171.075 77.625) (width 0.2) (layer "B.Cu") (net 143))
  (segment (start 155.436328 90.445008) (end 155.451328 90.460008) (width 0.2) (layer "B.Cu") (net 143))
  (segment (start 120.02 91.1175) (end 120.7325 91.1175) (width 0.1) (layer "B.Cu") (net 143))
  (segment (start 126.385 88.2) (end 126.285 88.1) (width 0.2) (layer "B.Cu") (net 143))
  (segment (start 175.145 81.65) (end 175.145 80.185736) (width 0.2) (layer "B.Cu") (net 143))
  (segment (start 154.371328 94.575008) (end 153.636328 95.310008) (width 0.2) (layer "B.Cu") (net 143))
  (segment (start 158.9145 103.226672) (end 158.9145 104.195501) (width 0.15) (layer "B.Cu") (net 143))
  (segment (start 128.7005 90.55) (end 129.1505 90.1) (width 0.1) (layer "B.Cu") (net 143))
  (segment (start 189.136328 87.560008) (end 188.636328 88.060008) (width 0.2) (layer "F.Cu") (net 144))
  (segment (start 185.136328 91.560008) (end 184.636328 92.060008) (width 0.2) (layer "F.Cu") (net 144))
  (segment (start 189.136328 89.560008) (end 188.636328 90.060008) (width 0.2) (layer "F.Cu") (net 144))
  (segment (start 186.136328 92.560008) (end 186.636328 93.060008) (width 0.2) (layer "F.Cu") (net 144))
  (segment (start 186.136328 86.560008) (end 185.636328 86.060008) (width 0.2) (layer "F.Cu") (net 144))
  (segment (start 187.136328 91.560008) (end 187.636328 92.060008) (width 0.2) (layer "F.Cu") (net 144))
  (segment (start 187.136328 89.560008) (end 187.636328 89.060008) (width 0.2) (layer "F.Cu") (net 144))
  (segment (start 189.136328 98.560008) (end 189.636328 99.060008) (width 0.2) (layer "F.Cu") (net 144))
  (segment (start 187.136328 87.560008) (end 187.636328 87.060008) (width 0.2) (layer "F.Cu") (net 144))
  (segment (start 188.136328 88.560008) (end 188.636328 88.060008) (width 0.2) (layer "F.Cu") (net 144))
  (segment (start 130.7 82.323) (end 130.7 81.6) (width 0.127) (layer "F.Cu") (net 144))
  (segment (start 191.136328 90.560008) (end 191.636328 91.060008) (width 0.2) (layer "F.Cu") (net 144))
  (via (at 133.036328 80.935008) (size 0.5) (drill 0.2) (layers "F.Cu" "B.Cu") (net 144))
  (via (at 134.036328 80.935008) (size 0.5) (drill 0.2) (layers "F.Cu" "B.Cu") (net 144))
  (via (at 133.036328 81.935008) (size 0.5) (drill 0.2) (layers "F.Cu" "B.Cu") (net 144))
  (via (at 134.036328 81.935008) (size 0.5) (drill 0.2) (layers "F.Cu" "B.Cu") (net 144))
  (via (at 133.536328 81.435008) (size 0.5) (drill 0.2) (layers "F.Cu" "B.Cu") (net 144))
  (via (at 134.536328 81.435008) (size 0.5) (drill 0.2) (layers "F.Cu" "B.Cu") (net 144))
  (via (at 133.536328 82.435008) (size 0.5) (drill 0.2) (layers "F.Cu" "B.Cu") (net 144))
  (via (at 134.536328 82.435008) (size 0.5) (drill 0.2) (layers "F.Cu" "B.Cu") (net 144))
  (via (at 188.636328 90.060008) (size 0.5) (drill 0.2) (layers "F.Cu" "B.Cu") (net 144))
  (via (at 184.636328 92.060008) (size 0.5) (drill 0.2) (layers "F.Cu" "B.Cu") (net 144))
  (via (at 187.636328 89.060008) (size 0.5) (drill 0.2) (layers "F.Cu" "B.Cu") (net 144))
  (via (at 189.636328 99.060008) (size 0.5) (drill 0.2) (layers "F.Cu" "B.Cu") (net 144))
  (via (at 185.7 94.080508) (size 0.5) (drill 0.2) (layers "F.Cu" "B.Cu") (net 144))
  (via (at 185.636328 86.060008) (size 0.5) (drill 0.2) (layers "F.Cu" "B.Cu") (net 144))
  (via (at 187.636328 87.060008) (size 0.5) (drill 0.2) (layers "F.Cu" "B.Cu") (net 144))
  (via (at 191.636328 91.060008) (size 0.5) (drill 0.2) (layers "F.Cu" "B.Cu") (net 144))
  (via (at 186.636328 93.060008) (size 0.5) (drill 0.2) (layers "F.Cu" "B.Cu") (net 144))
  (via (at 187.636328 92.060008) (size 0.5) (drill 0.2) (layers "F.Cu" "B.Cu") (net 144))
  (via (at 132.536328 81.435008) (size 0.5) (drill 0.2) (layers "F.Cu" "B.Cu") (net 144))
  (via (at 188.636328 88.060008) (size 0.5) (drill 0.2) (layers "F.Cu" "B.Cu") (net 144))
  (via (at 132.586328 82.435008) (size 0.5) (drill 0.2) (layers "F.Cu" "B.Cu") (net 144))
  (segment (start 184.366328 92.060008) (end 184.186328 91.880008) (width 0.1) (layer "B.Cu") (net 144))
  (segment (start 187.335008 89.060008) (end 187.636328 89.060008) (width 0.2) (layer "B.Cu") (net 144))
  (segment (start 134.536328 80.663672) (end 134.536328 80.763672) (width 0.4) (layer "B.Cu") (net 144))
  (segment (start 185.7 94.796336) (end 185.611328 94.885008) (width 0.4) (layer "B.Cu") (net 144))
  (segment (start 192.645 90.86) (end 193.1 91.315) (width 0.2) (layer "B.Cu") (net 144))
  (segment (start 188.361328 89.785008) (end 188.636328 90.060008) (width 0.2) (layer "B.Cu") (net 144))
  (segment (start 184.914992 94.885008) (end 184.6 95.2) (width 0.4) (layer "B.Cu") (net 144))
  (segment (start 187.366328 92.060008) (end 187.186328 91.880008) (width 0.1) (layer "B.Cu") (net 144))
  (segment (start 192.079992 91.060008) (end 191.636328 91.060008) (width 0.2) (layer "B.Cu") (net 144))
  (segment (start 134.536328 80.763672) (end 134.364992 80.935008) (width 0.4) (layer "B.Cu") (net 144))
  (segment (start 184.946336 91.75) (end 185.3 91.75) (width 0.2) (layer "B.Cu") (net 144))
  (segment (start 189.086328 89.913672) (end 188.939992 90.060008) (width 0.2) (layer "B.Cu") (net 144))
  (segment (start 187.27 87.426336) (end 187.636328 87.060008) (width 0.2) (layer "B.Cu") (net 144))
  (segment (start 186.65 99.05) (end 188.775 99.05) (width 0.4) (layer "B.Cu") (net 144))
  (segment (start 186.636328 93.060008) (end 186.546328 93.060008) (width 0.1) (layer "B.Cu") (net 144))
  (segment (start 187.946328 89.785008) (end 188.361328 89.785008) (width 0.2) (layer "B.Cu") (net 144))
  (segment (start 189.925 98.47) (end 189.636328 98.758672) (width 0.2) (layer "B.Cu") (net 144))
  (segment (start 186.546328 93.060008) (end 186.136328 93.470008) (width 0.1) (layer "B.Cu") (net 144))
  (segment (start 185.3 91.75) (end 185.625 91.425) (width 0.2) (layer "B.Cu") (net 144))
  (segment (start 184.656328 92.060008) (end 185.086328 92.490008) (width 0.1) (layer "B.Cu") (net 144))
  (segment (start 188.186328 88.215008) (end 188.209992 88.215008) (width 0.2) (layer "B.Cu") (net 144))
  (segment (start 185.364992 86.060008) (end 185.636328 86.060008) (width 0.2) (layer "B.Cu") (net 144))
  (segment (start 188.939992 90.060008) (end 188.636328 90.060008) (width 0.2) (layer "B.Cu") (net 144))
  (segment (start 187.636328 92.060008) (end 187.366328 92.060008) (width 0.1) (layer "B.Cu") (net 144))
  (segment (start 192.2 90.86) (end 192.645 90.86) (width 0.2) (layer "B.Cu") (net 144))
  (segment (start 184.636328 92.060008) (end 184.656328 92.060008) (width 0.1) (layer "B.Cu") (net 144))
  (segment (start 184.6 97) (end 186.65 99.05) (width 0.4) (layer "B.Cu") (net 144))
  (segment (start 134.364992 80.935008) (end 134.036328 80.935008) (width 0.4) (layer "B.Cu") (net 144))
  (segment (start 185.87632 86.3) (end 185.636328 86.060008) (width 0.2) (layer "B.Cu") (net 144))
  (segment (start 134.536328 80.663672) (end 134.536328 81.435008) (width 0.4) (layer "B.Cu") (net 144))
  (segment (start 189.636328 98.758672) (end 189.636328 99.060008) (width 0.2) (layer "B.Cu") (net 144))
  (segment (start 187.186328 88.880008) (end 187.186328 88.911328) (width 0.2) (layer "B.Cu") (net 144))
  (segment (start 187.186328 88.911328) (end 187.335008 89.060008) (width 0.2) (layer "B.Cu") (net 144))
  (segment (start 189.086328 89.880008) (end 189.086328 89.913672) (width 0.2) (layer "B.Cu") (net 144))
  (segment (start 188.775 99.05) (end 189.62632 99.05) (width 0.2) (layer "B.Cu") (net 144))
  (segment (start 185.186328 86.238672) (end 185.364992 86.060008) (width 0.2) (layer "B.Cu") (net 144))
  (segment (start 192.2 90.86) (end 192.2 90.94) (width 0.2) (layer "B.Cu") (net 144))
  (segment (start 185.7 93.906336) (end 186.136328 93.470008) (width 0.4) (layer "B.Cu") (net 144))
  (segment (start 188.375 88.05) (end 188.62632 88.05) (width 0.2) (layer "B.Cu") (net 144))
  (segment (start 186.636328 93.060008) (end 187.036328 93.060008) (width 0.1) (layer "B.Cu") (net 144))
  (segment (start 185.7 94.080508) (end 185.7 94.796336) (width 0.4) (layer "B.Cu") (net 144))
  (segment (start 184.636328 92.060008) (end 184.946336 91.75) (width 0.2) (layer "B.Cu") (net 144))
  (segment (start 188.62632 88.05) (end 188.636328 88.060008) (width 0.2) (layer "B.Cu") (net 144))
  (segment (start 184.636328 92.060008) (end 184.366328 92.060008) (width 0.1) (layer "B.Cu") (net 144))
  (segment (start 185.7 94.080508) (end 185.7 93.906336) (width 0.4) (layer "B.Cu") (net 144))
  (segment (start 185.611328 94.885008) (end 184.914992 94.885008) (width 0.4) (layer "B.Cu") (net 144))
  (segment (start 135.65 79.55) (end 134.536328 80.663672) (width 0.4) (layer "B.Cu") (net 144))
  (segment (start 192.2 90.94) (end 192.079992 91.060008) (width 0.2) (layer "B.Cu") (net 144))
  (segment (start 186.315 86.3) (end 185.87632 86.3) (width 0.2) (layer "B.Cu") (net 144))
  (segment (start 184.6 95.2) (end 184.6 97) (width 0.4) (layer "B.Cu") (net 144))
  (segment (start 188.209992 88.215008) (end 188.375 88.05) (width 0.2) (layer "B.Cu") (net 144))
  (segment (start 144.299179 100.697157) (end 143.661328 100.697157) (width 0.4) (layer "F.Cu") (net 145))
  (segment (start 135.021336 103.875) (end 134.544171 103.875) (width 0.2) (layer "F.Cu") (net 145))
  (segment (start 135.021336 103.875) (end 136.8375 103.875) (width 0.2) (layer "F.Cu") (net 145))
  (segment (start 134.236328 111.412157) (end 135.862157 111.412157) (width 0.15) (layer "F.Cu") (net 145))
  (segment (start 143.05 103.1625) (end 143.03 103.1825) (width 0.2) (layer "F.Cu") (net 145))
  (segment (start 143.661328 100.697157) (end 143.661328 101.442157) (width 0.2) (layer "F.Cu") (net 145))
  (segment (start 135.862157 111.412157) (end 136.5 112.05) (width 0.15) (layer "F.Cu") (net 145))
  (segment (start 136.8375 103.875) (end 136.8425 103.87) (width 0.2) (layer "F.Cu") (net 145))
  (segment (start 136.5 112.05) (end 137.85 112.05) (width 0.15) (layer "F.Cu") (net 145))
  (segment (start 143.05 102.053485) (end 143.05 103.1625) (width 0.2) (layer "F.Cu") (net 145))
  (segment (start 134.236328 110.747157) (end 134.246328 110.737157) (width 0.15) (layer "F.Cu") (net 145))
  (segment (start 137.85 112.05) (end 138.03 111.87) (width 0.15) (layer "F.Cu") (net 145))
  (segment (start 138.03 111.87) (end 138.03 111.0575) (width 0.15) (layer "F.Cu") (net 145))
  (segment (start 134.236328 111.412157) (end 134.236328 110.747157) (width 0.15) (layer "F.Cu") (net 145))
  (segment (start 143.661328 101.442157) (end 143.05 102.053485) (width 0.2) (layer "F.Cu") (net 145))
  (via (at 135.021336 103.875) (size 0.5) (drill 0.2) (layers "F.Cu" "B.Cu") (net 145))
  (via (at 144.299179 100.697157) (size 0.5) (drill 0.2) (layers "F.Cu" "B.Cu") (net 145))
  (via (at 134.246328 110.737157) (size 0.5) (drill 0.2) (layers "F.Cu" "B.Cu") (net 145))
  (via (at 145.036328 101.260008) (size 0.5) (drill 0.2) (layers "F.Cu" "B.Cu") (net 145))
  (via (at 145.036328 100.660008) (size 0.5) (drill 0.2) (layers "F.Cu" "B.Cu") (net 145))
  (via (at 145.036328 101.860008) (size 0.5) (drill 0.2) (layers "F.Cu" "B.Cu") (net 145))
  (segment (start 148.521328 105.497157) (end 149.161334 105.497157) (width 0.1) (layer "F.Cu") (net 146))
  (segment (start 171.136328 100.560008) (end 170.636328 101.060008) (width 0.1) (layer "F.Cu") (net 146))
  (via (at 170.636328 101.060008) (size 0.5) (drill 0.2) (layers "F.Cu" "B.Cu") (net 146))
  (via (at 252.3 86) (size 0.5) (drill 0.2) (layers "F.Cu" "B.Cu") (net 146))
  (via (at 149.161334 105.497157) (size 0.5) (drill 0.2) (layers "F.Cu" "B.Cu") (net 146))
  (segment (start 248.31653 85.5795) (end 251.8795 85.5795) (width 0.1) (layer "In7.Cu") (net 146))
  (segment (start 185.175 90.875) (end 185.175 91.19265) (width 0.1) (layer "In7.Cu") (net 146))
  (segment (start 188.216328 94.233978) (end 188.462358 94.480008) (width 0.1) (layer "In7.Cu") (net 146))
  (segment (start 176.85 91.5) (end 177.35 91) (width 0.1) (layer "In7.Cu") (net 146))
  (segment (start 180.55 90.75) (end 181.19 90.11) (width 0.1) (layer "In7.Cu") (net 146))
  (segment (start 184.925 90.625) (end 185.175 90.875) (width 0.1) (layer "In7.Cu") (net 146))
  (segment (start 171.056328 100.640008) (end 171.056328 98.868672) (width 0.1) (layer "In7.Cu") (net 146))
  (segment (start 187.065008 92.840008) (end 187.065008 93.082658) (width 0.1) (layer "In7.Cu") (net 146))
  (segment (start 200.802 91.875) (end 237.542158 91.875) (width 0.1) (layer "In7.Cu") (net 146))
  (segment (start 183.85 90.625) (end 184.925 90.625) (width 0.1) (layer "In7.Cu") (net 146))
  (segment (start 247.75 86.14603) (end 248.31653 85.5795) (width 0.1) (layer "In7.Cu") (net 146))
  (segment (start 171.425 98.5) (end 171.790306 98.5) (width 0.1) (layer "In7.Cu") (net 146))
  (segment (start 170.636328 101.060008) (end 171.056328 100.640008) (width 0.1) (layer "In7.Cu") (net 146))
  (segment (start 241.953188 87.46397) (end 243.87206 87.46397) (width 0.1) (layer "In7.Cu") (net 146))
  (segment (start 244.55603 86.78) (end 247.36397 86.78) (width 0.1) (layer "In7.Cu") (net 146))
  (segment (start 188.216328 94.025) (end 188.216328 94.233978) (width 0.1) (layer "In7.Cu") (net 146))
  (segment (start 171.056328 98.868672) (end 171.425 98.5) (width 0.1) (layer "In7.Cu") (net 146))
  (segment (start 186.865008 92.640008) (end 187.065008 92.840008) (width 0.1) (layer "In7.Cu") (net 146))
  (segment (start 187.831336 93.640008) (end 188.216328 94.025) (width 0.1) (layer "In7.Cu") (net 146))
  (segment (start 251.8795 85.5795) (end 252.3 86) (width 0.1) (layer "In7.Cu") (net 146))
  (segment (start 187.622358 93.640008) (end 187.831336 93.640008) (width 0.1) (layer "In7.Cu") (net 146))
  (segment (start 190.949992 94.480008) (end 191.205 94.225) (width 0.1) (layer "In7.Cu") (net 146))
  (segment (start 247.75 86.39397) (end 247.75 86.14603) (width 0.1) (layer "In7.Cu") (net 146))
  (segment (start 183.335 90.11) (end 183.85 90.625) (width 0.1) (layer "In7.Cu") (net 146))
  (segment (start 179.7 90.75) (end 180.55 90.75) (width 0.1) (layer "In7.Cu") (net 146))
  (segment (start 187.065008 93.082658) (end 187.622358 93.640008) (width 0.1) (layer "In7.Cu") (net 146))
  (segment (start 181.19 90.11) (end 183.335 90.11) (width 0.1) (layer "In7.Cu") (net 146))
  (segment (start 243.87206 87.46397) (end 244.55603 86.78) (width 0.1) (layer "In7.Cu") (net 146))
  (segment (start 247.36397 86.78) (end 247.75 86.39397) (width 0.1) (layer "In7.Cu") (net 146))
  (segment (start 174.85 91.5) (end 176.85 91.5) (width 0.1) (layer "In7.Cu") (net 146))
  (segment (start 188.462358 94.480008) (end 190.949992 94.480008) (width 0.1) (layer "In7.Cu") (net 146))
  (segment (start 186.622358 92.640008) (end 186.865008 92.640008) (width 0.1) (layer "In7.Cu") (net 146))
  (segment (start 173.2 97.090306) (end 173.2 93.15) (width 0.1) (layer "In7.Cu") (net 146))
  (segment (start 185.175 91.19265) (end 186.622358 92.640008) (width 0.1) (layer "In7.Cu") (net 146))
  (segment (start 198.452 94.225) (end 200.802 91.875) (width 0.1) (layer "In7.Cu") (net 146))
  (segment (start 173.2 93.15) (end 174.85 91.5) (width 0.1) (layer "In7.Cu") (net 146))
  (segment (start 177.35 91) (end 179.45 91) (width 0.1) (layer "In7.Cu") (net 146))
  (segment (start 179.45 91) (end 179.7 90.75) (width 0.1) (layer "In7.Cu") (net 146))
  (segment (start 171.790306 98.5) (end 173.2 97.090306) (width 0.1) (layer "In7.Cu") (net 146))
  (segment (start 191.205 94.225) (end 198.452 94.225) (width 0.1) (layer "In7.Cu") (net 146))
  (segment (start 237.542158 91.875) (end 241.953188 87.46397) (width 0.1) (layer "In7.Cu") (net 146))
  (segment (start 170.239992 101.060008) (end 170.636328 101.060008) (width 0.1) (layer "In9.Cu") (net 146))
  (segment (start 149.161334 105.497157) (end 151.552843 105.497157) (width 0.1) (layer "In9.Cu") (net 146))
  (segment (start 151.552843 105.497157) (end 152.75 104.3) (width 0.1) (layer "In9.Cu") (net 146))
  (segment (start 152.75 104.3) (end 167 104.3) (width 0.1) (layer "In9.Cu") (net 146))
  (segment (start 167 104.3) (end 170.239992 101.060008) (width 0.1) (layer "In9.Cu") (net 146))
  (segment (start 252.905 86.605) (end 252.3 86) (width 0.1) (layer "B.Cu") (net 146))
  (segment (start 252.905 86.665) (end 252.905 86.605) (width 0.1) (layer "B.Cu") (net 146))
  (segment (start 187.136328 93.560008) (end 187.636328 94.060008) (width 0.2) (layer "F.Cu") (net 147))
  (segment (start 182.136328 86.560008) (end 181.636328 86.060008) (width 0.2) (layer "F.Cu") (net 147))
  (segment (start 188.136328 94.560008) (end 187.636328 94.060008) (width 0.2) (layer "F.Cu") (net 147))
  (segment (start 191.136328 92.560008) (end 191.636328 93.060008) (width 0.2) (layer "F.Cu") (net 147))
  (segment (start 191.55 99) (end 191.55 98.97368) (width 0.1) (layer "F.Cu") (net 147))
  (segment (start 184.136328 88.560008) (end 183.636328 88.060008) (width 0.2) (layer "F.Cu") (net 147))
  (segment (start 189.136328 93.560008) (end 189.636328 94.060008) (width 0.2) (layer "F.Cu") (net 147))
  (segment (start 182.136328 88.560008) (end 181.636328 88.060008) (width 0.2) (layer "F.Cu") (net 147))
  (segment (start 191.621 97.064) (end 191.55985 97.00285) (width 0.1) (layer "F.Cu") (net 147))
  (segment (start 182.136328 90.560008) (end 181.636328 91.060008) (width 0.2) (layer "F.Cu") (net 147))
  (segment (start 183.136328 89.560008) (end 182.636328 89.060008) (width 0.2) (layer "F.Cu") (net 147))
  (segment (start 182.136328 92.560008) (end 181.638905 93.057431) (width 0.2) (layer "F.Cu") (net 147))
  (segment (start 191.55985 96.98353) (end 191.136328 96.560008) (width 0.2) (layer "F.Cu") (net 147))
  (segment (start 183.136328 87.560008) (end 182.636328 87.060008) (width 0.2) (layer "F.Cu") (net 147))
  (segment (start 144.977 83.7) (end 145.7 83.7) (width 0.127) (layer "F.Cu") (net 147))
  (segment (start 189.136328 91.560008) (end 189.636328 92.060008) (width 0.2) (layer "F.Cu") (net 147))
  (segment (start 191.55 98.97368) (end 191.136328 98.560008) (width 0.2) (layer "F.Cu") (net 147))
  (segment (start 188.136328 90.560008) (end 188.636328 91.060008) (width 0.2) (layer "F.Cu") (net 147))
  (segment (start 184.136328 86.560008) (end 183.636328 86.060008) (width 0.2) (layer "F.Cu") (net 147))
  (segment (start 185.136328 93.560008) (end 184.636328 94.060008) (width 0.2) (layer "F.Cu") (net 147))
  (segment (start 191.136328 94.560008) (end 191.636328 95.060008) (width 0.2) (layer "F.Cu") (net 147))
  (segment (start 184.136328 90.560008) (end 183.636328 91.060008) (width 0.2) (layer "F.Cu") (net 147))
  (segment (start 188.136328 92.560008) (end 188.636328 93.060008) (width 0.2) (layer "F.Cu") (net 147))
  (segment (start 191.136328 100.541828) (end 190.6945 100.1) (width 0.2) (layer "F.Cu") (net 147))
  (segment (start 185.136328 87.560008) (end 184.636328 87.060008) (width 0.2) (layer "F.Cu") (net 147))
  (segment (start 183.136328 91.560008) (end 182.636328 92.060008) (width 0.2) (layer "F.Cu") (net 147))
  (segment (start 181.638905 93.057431) (end 181.638905 93.066389) (width 0.2) (layer "F.Cu") (net 147))
  (segment (start 184.136328 92.560008) (end 183.636328 93.060008) (width 0.2) (layer "F.Cu") (net 147))
  (segment (start 191.55985 97.00285) (end 191.55985 96.98353) (width 0.1) (layer "F.Cu") (net 147))
  (segment (start 183.136328 93.560008) (end 182.636328 94.060008) (width 0.2) (layer "F.Cu") (net 147))
  (via (at 145.936328 79.785008) (size 0.5) (drill 0.2) (layers "F.Cu" "B.Cu") (net 147))
  (via (at 147.936328 79.785008) (size 0.5) (drill 0.2) (layers "F.Cu" "B.Cu") (net 147))
  (via (at 145.936328 81.785008) (size 0.5) (drill 0.2) (layers "F.Cu" "B.Cu") (net 147))
  (via (at 147.936328 81.785008) (size 0.5) (drill 0.2) (layers "F.Cu" "B.Cu") (net 147))
  (via (at 145.9 85.375) (size 0.5) (drill 0.2) (layers "F.Cu" "B.Cu") (net 147))
  (via (at 147.936328 83.785008) (size 0.5) (drill 0.2) (layers "F.Cu" "B.Cu") (net 147))
  (via (at 147.936328 85.785008) (size 0.5) (drill 0.2) (layers "F.Cu" "B.Cu") (net 147))
  (via (at 146.936328 78.785008) (size 0.5) (drill 0.2) (layers "F.Cu" "B.Cu") (net 147))
  (via (at 146.936328 80.785008) (size 0.5) (drill 0.2) (layers "F.Cu" "B.Cu") (net 147))
  (via (at 146.936328 82.785008) (size 0.5) (drill 0.2) (layers "F.Cu" "B.Cu") (net 147))
  (via (at 146.936328 84.785008) (size 0.5) (drill 0.2) (layers "F.Cu" "B.Cu") (net 147))
  (via (at 168 99.85) (size 0.5) (drill 0.2) (layers "F.Cu" "B.Cu") (net 147))
  (via (at 169.05 97.6) (size 0.5) (drill 0.2) (layers "F.Cu" "B.Cu") (net 147))
  (via (at 189.636328 92.060008) (size 0.5) (drill 0.2) (layers "F.Cu" "B.Cu") (net 147))
  (via (at 169.05 98.3) (size 0.5) (drill 0.2) (layers "F.Cu" "B.Cu") (net 147))
  (via (at 191.636328 95.060008) (size 0.5) (drill 0.2) (layers "F.Cu" "B.Cu") (net 147))
  (via (at 169.05 96.8) (size 0.5) (drill 0.2) (layers "F.Cu" "B.Cu") (net 147))
  (via (at 184.636328 87.060008) (size 0.5) (drill 0.2) (layers "F.Cu" "B.Cu") (net 147))
  (via (at 191.55 99) (size 0.5) (drill 0.2) (layers "F.Cu" "B.Cu") (net 147))
  (via (at 169.1 100.25) (size 0.5) (drill 0.2) (layers "F.Cu" "B.Cu") (net 147))
  (via (at 181.636328 91.060008) (size 0.5) (drill 0.2) (layers "F.Cu" "B.Cu") (net 147))
  (via (at 181.636328 86.060008) (size 0.5) (drill 0.2) (layers "F.Cu" "B.Cu") (net 147))
  (via (at 187.636328 94.060008) (size 0.5) (drill 0.2) (layers "F.Cu" "B.Cu") (net 147))
  (via (at 190.6945 100.1) (size 0.5) (drill 0.2) (layers "F.Cu" "B.Cu") (net 147))
  (via (at 169.05 99.05) (size 0.5) (drill 0.2) (layers "F.Cu" "B.Cu") (net 147))
  (via (at 168 98.75) (size 0.5) (drill 0.2) (layers "F.Cu" "B.Cu") (net 147))
  (via (at 181.636328 88.060008) (size 0.5) (drill 0.2) (layers "F.Cu" "B.Cu") (net 147))
  (via (at 189.636328 94.060008) (size 0.5) (drill 0.2) (layers "F.Cu" "B.Cu") (net 147))
  (via (at 183.636328 88.060008) (size 0.5) (drill 0.2) (layers "F.Cu" "B.Cu") (net 147))
  (via (at 188.636328 91.060008) (size 0.5) (drill 0.2) (layers "F.Cu" "B.Cu") (net 147))
  (via (at 183.636328 93.060008) (size 0.5) (drill 0.2) (layers "F.Cu" "B.Cu") (net 147))
  (via (at 182.636328 89.060008) (size 0.5) (drill 0.2) (layers "F.Cu" "B.Cu") (net 147))
  (via (at 181.638905 93.066389) (size 0.5) (drill 0.2) (layers "F.Cu" "B.Cu") (net 147))
  (via (at 182.636328 94.060008) (size 0.5) (drill 0.2) (layers "F.Cu" "B.Cu") (net 147))
  (via (at 169.05 95.95) (size 0.5) (drill 0.2) (layers "F.Cu" "B.Cu") (net 147))
  (via (at 169.95 97.3) (size 0.5) (drill 0.2) (layers "F.Cu" "B.Cu") (net 147))
  (via (at 182.636328 87.060008) (size 0.5) (drill 0.2) (layers "F.Cu" "B.Cu") (net 147))
  (via (at 188.636328 93.060008) (size 0.5) (drill 0.2) (layers "F.Cu" "B.Cu") (net 147))
  (via (at 184.636328 94.060008) (size 0.5) (drill 0.2) (layers "F.Cu" "B.Cu") (net 147))
  (via (at 191.636328 93.060008) (size 0.5) (drill 0.2) (layers "F.Cu" "B.Cu") (net 147))
  (via (at 168 97.25) (size 0.5) (drill 0.2) (layers "F.Cu" "B.Cu") (net 147))
  (via (at 183.636328 91.060008) (size 0.5) (drill 0.2) (layers "F.Cu" "B.Cu") (net 147))
  (via (at 191.621 97.064) (size 0.5) (drill 0.2) (layers "F.Cu" "B.Cu") (net 147))
  (via (at 182.636328 92.060008) (size 0.5) (drill 0.2) (layers "F.Cu" "B.Cu") (net 147))
  (via (at 183.636328 86.060008) (size 0.5) (drill 0.2) (layers "F.Cu" "B.Cu") (net 147))
  (segment (start 181.638905 93.327431) (end 181.256328 93.710008) (width 0.1) (layer "B.Cu") (net 147))
  (segment (start 182.366328 92.060008) (end 182.186328 91.880008) (width 0.1) (layer "B.Cu") (net 147))
  (segment (start 145.936328 80.213672) (end 145.936328 79.785008) (width 0.4) (layer "B.Cu") (net 147))
  (segment (start 192.10132 93.525) (end 191.636328 93.060008) (width 0.2) (layer "B.Cu") (net 147))
  (segment (start 182.210008 88.880008) (end 182.186328 88.880008) (width 0.2) (layer "B.Cu") (net 147))
  (segment (start 181.636328 91.060008) (end 181.366328 91.060008) (width 0.1) (layer "B.Cu") (net 147))
  (segment (start 183.289992 86.060008) (end 183.636328 86.060008) (width 0.2) (layer "B.Cu") (net 147))
  (segment (start 184.366328 94.060008) (end 184.186328 93.880008) (width 0.1) (layer "B.Cu") (net 147))
  (segment (start 145.936328 80.436328) (end 146.285008 80.785008) (width 0.4) (layer "B.Cu") (net 147))
  (segment (start 191.805 95.625) (end 191.775 95.625) (width 0.2) (layer "B.Cu") (net 147))
  (segment (start 181.265 90.15) (end 181.265 90.365) (width 0.2) (layer "B.Cu") (net 147))
  (segment (start 183.636328 93.060008) (end 183.366328 93.060008) (width 0.1) (layer "B.Cu") (net 147))
  (segment (start 183.186328 86.163672) (end 183.289992 86.060008) (width 0.2) (layer "B.Cu") (net 147))
  (segment (start 188.366328 91.060008) (end 188.186328 91.240008) (width 0.1) (layer "B.Cu") (net 147))
  (segment (start 191.55 99) (end 191.55 98.93) (width 0.2) (layer "B.Cu") (net 147))
  (segment (start 182.366328 94.060008) (end 182.186328 93.880008) (width 0.1) (layer "B.Cu") (net 147))
  (segment (start 192.155 93.525) (end 192.10132 93.525) (width 0.2) (layer "B.Cu") (net 147))
  (segment (start 183.219992 88.240008) (end 183.399992 88.060008) (width 0.2) (layer "B.Cu") (net 147))
  (segment (start 181.340008 86.15) (end 181.546336 86.15) (width 0.2) (layer "B.Cu") (net 147))
  (segment (start 181.2 86.290008) (end 181.340008 86.15) (width 0.2) (layer "B.Cu") (net 147))
  (segment (start 183.366328 93.060008) (end 183.186328 93.240008) (width 0.1) (layer "B.Cu") (net 147))
  (segment (start 191.775 95.625) (end 191.636328 95.486328) (width 0.2) (layer "B.Cu") (net 147))
  (segment (start 183.366328 91.060008) (end 183.186328 91.240008) (width 0.1) (layer "B.Cu") (net 147))
  (segment (start 183.399992 88.060008) (end 183.636328 88.060008) (width 0.2) (layer "B.Cu") (net 147))
  (segment (start 181.186328 88.240008) (end 181.186328 88.163672) (width 0.2) (layer "B.Cu") (net 147))
  (segment (start 191.28 101.265) (end 191.715 101.7) (width 0.2) (layer "B.Cu") (net 147))
  (segment (start 190.6945 100.1395) (end 191.28 100.725) (width 0.2) (layer "B.Cu") (net 147))
  (segment (start 188.636328 91.060008) (end 188.366328 91.060008) (width 0.1) (layer "B.Cu") (net 147))
  (segment (start 183.186328 86.240008) (end 183.186328 86.163672) (width 0.2) (layer "B.Cu") (net 147))
  (segment (start 189.636328 94.060008) (end 189.636328 94.380008) (width 0.1) (layer "B.Cu") (net 147))
  (segment (start 146.285008 80.785008) (end 146.936328 80.785008) (width 0.4) (layer "B.Cu") (net 147))
  (segment (start 182.186328 88.966328) (end 182.280008 89.060008) (width 0.2) (layer "B.Cu") (net 147))
  (segment (start 181.366328 91.060008) (end 181.186328 91.240008) (width 0.1) (layer "B.Cu") (net 147))
  (segment (start 190.6945 100.1) (end 190.6945 100.1395) (width 0.2) (layer "B.Cu") (net 147))
  (segment (start 183.365 90.15) (end 183.35 90.15) (width 0.2) (layer "B.Cu") (net 147))
  (segment (start 183.35 90.15) (end 182.636328 89.436328) (width 0.2) (layer "B.Cu") (net 147))
  (segment (start 182.636328 92.060008) (end 182.366328 92.060008) (width 0.1) (layer "B.Cu") (net 147))
  (segment (start 189.636328 92.060008) (end 189.986328 92.060008) (width 0.1) (layer "B.Cu") (net 147))
  (segment (start 182.335008 87.060008) (end 182.636328 87.060008) (width 0.2) (layer "B.Cu") (net 147))
  (segment (start 181.546336 86.15) (end 181.636328 86.060008) (width 0.2) (layer "B.Cu") (net 147))
  (segment (start 187.636328 94.330008) (end 187.456328 94.510008) (width 0.1) (layer "B.Cu") (net 147))
  (segment (start 182.186328 86.880008) (end 182.186328 86.911328) (width 0.2) (layer "B.Cu") (net 147))
  (segment (start 191.28 100.725) (end 191.28 101.265) (width 0.2) (layer "B.Cu") (net 147))
  (segment (start 184.310008 87.060008) (end 184.636328 87.060008) (width 0.2) (layer "B.Cu") (net 147))
  (segment (start 187.636328 94.060008) (end 187.636328 94.330008) (width 0.1) (layer "B.Cu") (net 147))
  (segment (start 185.39132 87.815) (end 184.636328 87.060008) (width 0.2) (layer "B.Cu") (net 147))
  (segment (start 144.8 80.4) (end 145.75 80.4) (width 0.4) (layer "B.Cu") (net 147))
  (segment (start 184.186328 86.936328) (end 184.310008 87.060008) (width 0.2) (layer "B.Cu") (net 147))
  (segment (start 191.55 98.93) (end 191.83 98.65) (width 0.2) (layer "B.Cu") (net 147))
  (segment (start 183.186328 88.240008) (end 183.219992 88.240008) (width 0.2) (layer "B.Cu") (net 147))
  (segment (start 181.186328 88.163672) (end 181.289992 88.060008) (width 0.2) (layer "B.Cu") (net 147))
  (segment (start 191.77 96.915) (end 191.77 96.6) (width 0.2) (layer "B.Cu") (net 147))
  (segment (start 191.621 97.064) (end 191.77 96.915) (width 0.2) (layer "B.Cu") (net 147))
  (segment (start 182.280008 89.060008) (end 182.636328 89.060008) (width 0.2) (layer "B.Cu") (net 147))
  (segment (start 182.636328 94.060008) (end 182.366328 94.060008) (width 0.1) (layer "B.Cu") (net 147))
  (segment (start 183.636328 91.060008) (end 183.366328 91.060008) (width 0.1) (layer "B.Cu") (net 147))
  (segment (start 185.5 87.815) (end 185.39132 87.815) (width 0.2) (layer "B.Cu") (net 147))
  (segment (start 145.75 80.4) (end 145.936328 80.213672) (width 0.4) (layer "B.Cu") (net 147))
  (segment (start 182.186328 88.880008) (end 182.186328 88.966328) (width 0.2) (layer "B.Cu") (net 147))
  (segment (start 189.636328 92.060008) (end 190.131328 92.060008) (width 0.1) (layer "B.Cu") (net 147))
  (segment (start 181.289992 88.060008) (end 181.636328 88.060008) (width 0.2) (layer "B.Cu") (net 147))
  (segment (start 182.636328 89.436328) (end 182.636328 89.060008) (width 0.2) (layer "B.Cu") (net 147))
  (segment (start 181.636328 90.736328) (end 181.636328 91.060008) (width 0.2) (layer "B.Cu") (net 147))
  (segment (start 183.186328 86.240008) (end 183.209992 86.240008) (width 0.2) (layer "B.Cu") (net 147))
  (segment (start 181.638905 93.066389) (end 181.638905 93.327431) (width 0.1) (layer "B.Cu") (net 147))
  (segment (start 191.636328 95.486328) (end 191.636328 95.060008) (width 0.2) (layer "B.Cu") (net 147))
  (segment (start 184.186328 86.880008) (end 184.186328 86.936328) (width 0.2) (layer "B.Cu") (net 147))
  (segment (start 181.265 90.365) (end 181.636328 90.736328) (width 0.2) (layer "B.Cu") (net 147))
  (segment (start 184.636328 94.060008) (end 184.366328 94.060008) (width 0.1) (layer "B.Cu") (net 147))
  (segment (start 182.186328 86.911328) (end 182.335008 87.060008) (width 0.2) (layer "B.Cu") (net 147))
  (segment (start 145.936328 80.213672) (end 145.936328 80.436328) (width 0.4) (layer "B.Cu") (net 147))
  (segment (start 222.335 125.4) (end 222.335 126.4) (width 0.2) (layer "F.Cu") (net 149))
  (segment (start 176.136328 100.560008) (end 175.636328 101.060008) (width 0.1) (layer "F.Cu") (net 149))
  (segment (start 223.15 126.4) (end 222.335 126.4) (width 0.2) (layer "F.Cu") (net 149))
  (via (at 223.15 126.4) (size 0.5) (drill 0.2) (layers "F.Cu" "B.Cu") (net 149))
  (via (at 175.636328 101.060008) (size 0.5) (drill 0.2) (layers "F.Cu" "B.Cu") (net 149))
  (segment (start 210.75 107.6) (end 214.9 111.75) (width 0.1) (layer "B.Cu") (net 149))
  (segment (start 186.35 105.75) (end 188.2 107.6) (width 0.1) (layer "B.Cu") (net 149))
  (segment (start 218.899988 112.800012) (end 222.300012 112.800012) (width 0.1) (layer "B.Cu") (net 149))
  (segment (start 222.300012 112.800012) (end 226.75 117.25) (width 0.1) (layer "B.Cu") (net 149))
  (segment (start 226.75 117.25) (end 226.75 120.65) (width 0.1) (layer "B.Cu") (net 149))
  (segment (start 178.65 105.75) (end 186.35 105.75) (width 0.1) (layer "B.Cu") (net 149))
  (segment (start 223.65 131.6725) (end 224.4 130.9225) (width 0.2) (layer "B.Cu") (net 149))
  (segment (start 188.2 107.6) (end 210.75 107.6) (width 0.1) (layer "B.Cu") (net 149))
  (segment (start 214.9 111.75) (end 217.849976 111.75) (width 0.1) (layer "B.Cu") (net 149))
  (segment (start 176.216328 103.316328) (end 178.65 105.75) (width 0.1) (layer "B.Cu") (net 149))
  (segment (start 175.6 102.640008) (end 175.810298 102.640008) (width 0.1) (layer "B.Cu") (net 149))
  (segment (start 175.216328 101.480008) (end 175.216328 102.256336) (width 0.1) (layer "B.Cu") (net 149))
  (segment (start 217.849976 111.75) (end 218.899988 112.800012) (width 0.1) (layer "B.Cu") (net 149))
  (segment (start 226.75 120.65) (end 223.15 124.25) (width 0.1) (layer "B.Cu") (net 149))
  (segment (start 175.810298 102.640008) (end 176.216328 103.046038) (width 0.1) (layer "B.Cu") (net 149))
  (segment (start 224.4 127.65) (end 223.15 126.4) (width 0.2) (layer "B.Cu") (net 149))
  (segment (start 175.636328 101.060008) (end 175.216328 101.480008) (width 0.1) (layer "B.Cu") (net 149))
  (segment (start 176.216328 103.046038) (end 176.216328 103.316328) (width 0.1) (layer "B.Cu") (net 149))
  (segment (start 175.216328 102.256336) (end 175.6 102.640008) (width 0.1) (layer "B.Cu") (net 149))
  (segment (start 223.15 124.25) (end 223.15 126.4) (width 0.1) (layer "B.Cu") (net 149))
  (segment (start 224.4 130.9225) (end 224.4 127.65) (width 0.2) (layer "B.Cu") (net 149))
  (segment (start 140.225857 94.525) (end 139.025 94.525) (width 0.2) (layer "F.Cu") (net 151))
  (segment (start 141.85 94.525) (end 142.625 93.75) (width 0.2) (layer "F.Cu") (net 151))
  (segment (start 140.225857 94.525) (end 141.85 94.525) (width 0.2) (layer "F.Cu") (net 151))
  (segment (start 139.025 94.525) (end 139 94.5) (width 0.2) (layer "F.Cu") (net 151))
  (segment (start 141.906328 89.610008) (end 141.906328 88.880008) (width 0.2) (layer "F.Cu") (net 151))
  (via (at 139 94.5) (size 0.5) (drill 0.2) (layers "F.Cu" "B.Cu") (net 151))
  (via (at 141.906328 88.880008) (size 0.5) (drill 0.2) (layers "F.Cu" "B.Cu") (net 151))
  (via (at 140.96 77.66) (size 0.5) (drill 0.2) (layers "F.Cu" "B.Cu") (net 151))
  (segment (start 140.3 82.42) (end 140.3 87.27368) (width 0.127) (layer "In2.Cu") (net 151))
  (segment (start 140.96 77.66) (end 140.96 81.76) (width 0.127) (layer "In2.Cu") (net 151))
  (segment (start 140.3 87.27368) (end 141.906328 88.880008) (width 0.127) (layer "In2.Cu") (net 151))
  (segment (start 140.96 81.76) (end 140.3 82.42) (width 0.127) (layer "In2.Cu") (net 151))
  (segment (start 140.95 78.5) (end 140.95 77.67) (width 0.127) (layer "B.Cu") (net 151))
  (segment (start 141.906328 89.793672) (end 140.6 91.1) (width 0.2) (layer "B.Cu") (net 151))
  (segment (start 138.431655 91.1) (end 137.75 91.781655) (width 0.2) (layer "B.Cu") (net 151))
  (segment (start 140.95 77.67) (end 140.96 77.66) (width 0.127) (layer "B.Cu") (net 151))
  (segment (start 137.75 91.781655) (end 137.75 93.25) (width 0.2) (layer "B.Cu") (net 151))
  (segment (start 140.536328 93.770008) (end 140.536328 92.855008) (width 0.2) (layer "B.Cu") (net 151))
  (segment (start 139 94.5) (end 139.806336 94.5) (width 0.2) (layer "B.Cu") (net 151))
  (segment (start 139.806336 94.5) (end 140.536328 93.770008) (width 0.2) (layer "B.Cu") (net 151))
  (segment (start 137.75 93.25) (end 139 94.5) (width 0.2) (layer "B.Cu") (net 151))
  (segment (start 140.6 91.1) (end 138.431655 91.1) (width 0.2) (layer "B.Cu") (net 151))
  (segment (start 141.906328 88.880008) (end 141.906328 89.793672) (width 0.2) (layer "B.Cu") (net 151))
  (segment (start 140.225857 95.175) (end 141.49132 95.175) (width 0.2) (layer "F.Cu") (net 152))
  (segment (start 142.625 95.1992) (end 141.51552 95.1992) (width 0.2) (layer "F.Cu") (net 152))
  (segment (start 141.51552 95.1992) (end 141.49132 95.175) (width 0.2) (layer "F.Cu") (net 152))
  (via (at 141.49132 95.175) (size 0.5) (drill 0.2) (layers "F.Cu" "B.Cu") (net 152))
  (via (at 139.319312 77.209318) (size 0.5) (drill 0.2) (layers "F.Cu" "B.Cu") (net 152))
  (segment (start 139.9 80.3) (end 139.9 87.6) (width 0.127) (layer "In2.Cu") (net 152))
  (segment (start 139.319312 79.719312) (end 139.9 80.3) (width 0.127) (layer "In2.Cu") (net 152))
  (segment (start 139.9 87.6) (end 141.49132 89.19132) (width 0.127) (layer "In2.Cu") (net 152))
  (segment (start 139.319312 77.209318) (end 139.319312 79.719312) (width 0.127) (layer "In2.Cu") (net 152))
  (segment (start 141.49132 89.19132) (end 141.49132 95.175) (width 0.127) (layer "In2.Cu") (net 152))
  (segment (start 127.05 98.096148) (end 123.053852 94.1) (width 0.2) (layer "B.Cu") (net 152))
  (segment (start 138.025 95.175) (end 141.49132 95.175) (width 0.2) (layer "B.Cu") (net 152))
  (segment (start 138.025 95.175) (end 137.225 94.375) (width 0.2) (layer "B.Cu") (net 152))
  (segment (start 120.125 95.905) (end 120.49 96.27) (width 0.2) (layer "B.Cu") (net 152))
  (segment (start 123.053852 94.1) (end 120.425 94.1) (width 0.2) (layer "B.Cu") (net 152))
  (segment (start 139.05 78.5) (end 139.05 77.47863) (width 0.127) (layer "B.Cu") (net 152))
  (segment (start 134.806336 94.375) (end 134.386328 94.795008) (width 0.2) (layer "B.Cu") (net 152))
  (segment (start 132.1 100.7) (end 128.775 100.7) (width 0.2) (layer "B.Cu") (net 152))
  (segment (start 120.425 94.1) (end 120.125 94.4) (width 0.2) (layer "B.Cu") (net 152))
  (segment (start 120.125 94.4) (end 120.125 95.905) (width 0.2) (layer "B.Cu") (net 152))
  (segment (start 139.05 77.47863) (end 139.319312 77.209318) (width 0.127) (layer "B.Cu") (net 152))
  (segment (start 121.705 96.27) (end 122.01 95.965) (width 0.2) (layer "B.Cu") (net 152))
  (segment (start 120.49 96.27) (end 121.705 96.27) (width 0.2) (layer "B.Cu") (net 152))
  (segment (start 127.05 98.975) (end 127.05 98.096148) (width 0.2) (layer "B.Cu") (net 152))
  (segment (start 133.979992 94.795008) (end 133.4 95.375) (width 0.2) (layer "B.Cu") (net 152))
  (segment (start 141.49132 92.950016) (end 141.49132 95.175) (width 0.2) (layer "B.Cu") (net 152))
  (segment (start 134.386328 94.795008) (end 133.979992 94.795008) (width 0.2) (layer "B.Cu") (net 152))
  (segment (start 137.225 94.375) (end 134.806336 94.375) (width 0.2) (layer "B.Cu") (net 152))
  (segment (start 133.4 95.375) (end 133.4 99.4) (width 0.2) (layer "B.Cu") (net 152))
  (segment (start 128.775 100.7) (end 127.05 98.975) (width 0.2) (layer "B.Cu") (net 152))
  (segment (start 122.01 95.965) (end 122.525 95.965) (width 0.2) (layer "B.Cu") (net 152))
  (segment (start 133.4 99.4) (end 132.1 100.7) (width 0.2) (layer "B.Cu") (net 152))
  (segment (start 153.099328 113.617008) (end 153.099328 112.952008) (width 0.2) (layer "F.Cu") (net 153))
  (segment (start 140.225857 95.825) (end 141.575 95.825) (width 0.2) (layer "F.Cu") (net 153))
  (segment (start 141.575 95.825) (end 141.77817 96.02817) (width 0.2) (layer "F.Cu") (net 153))
  (segment (start 142.5 96.75) (end 141.77817 96.02817) (width 0.2) (layer "F.Cu") (net 153))
  (via (at 153.099328 112.952008) (size 0.5) (drill 0.2) (layers "F.Cu" "B.Cu") (net 153))
  (via (at 123.7 120.5) (size 0.5) (drill 0.2) (layers "F.Cu" "B.Cu") (net 153))
  (via (at 123.1495 102.3) (size 0.5) (drill 0.2) (layers "F.Cu" "B.Cu") (net 153))
  (via (at 141.77817 96.02817) (size 0.5) (drill 0.2) (layers "F.Cu" "B.Cu") (net 153))
  (segment (start 141.77817 96.02817) (end 146.10449 96.02817) (width 0.15) (layer "In7.Cu") (net 153))
  (segment (start 151.85 111.70268) (end 153.099328 112.952008) (width 0.15) (layer "In7.Cu") (net 153))
  (segment (start 119.9 107.5) (end 123.1495 104.2505) (width 0.1) (layer "In7.Cu") (net 153))
  (segment (start 123.1495 104.2505) (end 123.1495 102.3) (width 0.1) (layer "In7.Cu") (net 153))
  (segment (start 119.9 116.7) (end 119.9 107.5) (width 0.1) (layer "In7.Cu") (net 153))
  (segment (start 146.10449 96.02817) (end 149.951328 99.875008) (width 0.15) (layer "In7.Cu") (net 153))
  (segment (start 151.85 101.754354) (end 151.85 111.70268) (width 0.15) (layer "In7.Cu") (net 153))
  (segment (start 123.7 120.5) (end 119.9 116.7) (width 0.1) (layer "In7.Cu") (net 153))
  (segment (start 149.951328 99.875008) (end 149.970654 99.875008) (width 0.15) (layer "In7.Cu") (net 153))
  (segment (start 149.970654 99.875008) (end 151.85 101.754354) (width 0.15) (layer "In7.Cu") (net 153))
  (segment (start 127.697156 100.497156) (end 128.3 101.1) (width 0.2) (layer "B.Cu") (net 153))
  (segment (start 134.395 95.305) (end 137.255 95.305) (width 0.2) (layer "B.Cu") (net 153))
  (segment (start 141.570008 95.820008) (end 139.709992 95.820008) (width 0.2) (layer "B.Cu") (net 153))
  (segment (start 122.85 121.3) (end 122.85 120.55) (width 0.1) (layer "B.Cu") (net 153))
  (segment (start 138.81 99.74) (end 139.260657 100.190657) (width 0.127) (layer "B.Cu") (net 153))
  (segment (start 121.1 120.5) (end 122.9 120.5) (width 0.1) (layer "B.Cu") (net 153))
  (segment (start 142.536328 95.270012) (end 142.536328 92.855008) (width 0.2) (layer "B.Cu") (net 153))
  (segment (start 140.019343 100.190657) (end 140.25 99.96) (width 0.127) (layer "B.Cu") (net 153))
  (segment (start 137.770008 95.820008) (end 139.709992 95.820008) (width 0.2) (layer "B.Cu") (net 153))
  (segment (start 122.85 120.55) (end 122.9 120.5) (width 0.1) (layer "B.Cu") (net 153))
  (segment (start 139.709992 96.709992) (end 139.709992 95.820008) (width 0.127) (layer "B.Cu") (net 153))
  (segment (start 136.84 102.005) (end 136.84 100.325) (width 0.127) (layer "B.Cu") (net 153))
  (segment (start 122.736328 103.015008) (end 123.07 102.681336) (width 0.2) (layer "B.Cu") (net 153))
  (segment (start 139.260657 100.190657) (end 140.019343 100.190657) (width 0.127) (layer "B.Cu") (net 153))
  (segment (start 123.07 102.681336) (end 123.07 100.68) (width 0.2) (layer "B.Cu") (net 153))
  (segment (start 136.84 100.325) (end 137.425 99.74) (width 0.127) (layer "B.Cu") (net 153))
  (segment (start 140.25 97.25) (end 139.709992 96.709992) (width 0.127) (layer "B.Cu") (net 153))
  (segment (start 123.252844 100.497156) (end 127.697156 100.497156) (width 0.2) (layer "B.Cu") (net 153))
  (segment (start 120.95 121.3) (end 120.95 120.65) (width 0.1) (layer "B.Cu") (net 153))
  (segment (start 133.9375 99.4625) (end 133.9375 95.7625) (width 0.2) (layer "B.Cu") (net 153))
  (segment (start 120.95 120.65) (end 121.1 120.5) (width 0.1) (layer "B.Cu") (net 153))
  (segment (start 137.425 99.74) (end 137.65 99.74) (width 0.127) (layer "B.Cu") (net 153))
  (segment (start 136.955 102.12) (end 136.84 102.005) (width 0.127) (layer "B.Cu") (net 153))
  (segment (start 132.3 101.1) (end 133.9375 99.4625) (width 0.2) (layer "B.Cu") (net 153))
  (segment (start 122.9 120.5) (end 123.7 120.5) (width 0.1) (layer "B.Cu") (net 153))
  (segment (start 137.255 95.305) (end 137.770008 95.820008) (width 0.2) (layer "B.Cu") (net 153))
  (segment (start 128.3 101.1) (end 132.3 101.1) (width 0.2) (layer "B.Cu") (net 153))
  (segment (start 141.77817 96.02817) (end 141.570008 95.820008) (width 0.2) (layer "B.Cu") (net 153))
  (segment (start 133.9375 95.7625) (end 134.395 95.305) (width 0.2) (layer "B.Cu") (net 153))
  (segment (start 140.25 99.96) (end 140.25 97.25) (width 0.127) (layer "B.Cu") (net 153))
  (segment (start 141.77817 96.02817) (end 142.536328 95.270012) (width 0.2) (layer "B.Cu") (net 153))
  (segment (start 137.65 99.74) (end 138.81 99.74) (width 0.127) (layer "B.Cu") (net 153))
  (segment (start 123.07 100.68) (end 123.252844 100.497156) (width 0.2) (layer "B.Cu") (net 153))
  (segment (start 153.172557 79.577157) (end 152.882 79.2866) (width 0.127) (layer "F.Cu") (net 154))
  (segment (start 153.496328 79.577157) (end 153.172557 79.577157) (width 0.127) (layer "F.Cu") (net 154))
  (segment (start 152.882 79.2866) (end 152.882 77.6356) (width 0.127) (layer "F.Cu") (net 154))
  (segment (start 153.6948 76.8228) (end 153.6948 76.137) (width 0.127) (layer "F.Cu") (net 154))
  (segment (start 152.882 77.6356) (end 153.6948 76.8228) (width 0.127) (layer "F.Cu") (net 154))
  (segment (start 153.512399 79.590001) (end 154.012399 80.09) (width 0.127) (layer "F.Cu") (net 154))
  (segment (start 172.695823 80.119503) (end 172.666833 80.119503) (width 0.1) (layer "F.Cu") (net 154))
  (segment (start 173.136328 80.560008) (end 172.695823 80.119503) (width 0.1) (layer "F.Cu") (net 154))
  (via locked (at 154.012399 80.09) (size 0.5) (drill 0.2) (layers "F.Cu" "B.Cu") (net 154))
  (via (at 172.666833 80.119503) (size 0.5) (drill 0.2) (layers "F.Cu" "B.Cu") (net 154))
  (segment (start 154.012399 80.09) (end 153.985 80.09) (width 0.1) (layer "In7.Cu") (net 154))
  (segment (start 172.666833 80.633167) (end 172.666833 80.119503) (width 0.1) (layer "In7.Cu") (net 154))
  (segment (start 156.4 84.5) (end 167.37 84.5) (width 0.1) (layer "In7.Cu") (net 154))
  (segment (start 169.125 83) (end 170.745 81.38) (width 0.1) (layer "In7.Cu") (net 154))
  (segment (start 153.325 81.425) (end 156.4 84.5) (width 0.1) (layer "In7.Cu") (net 154))
  (segment (start 153.985 80.09) (end 153.325 80.75) (width 0.1) (layer "In7.Cu") (net 154))
  (segment (start 171.92 81.38) (end 172.666833 80.633167) (width 0.1) (layer "In7.Cu") (net 154))
  (segment (start 167.37 84.5) (end 168.87 83) (width 0.1) (layer "In7.Cu") (net 154))
  (segment (start 153.325 80.75) (end 153.325 81.425) (width 0.1) (layer "In7.Cu") (net 154))
  (segment (start 170.745 81.38) (end 171.92 81.38) (width 0.1) (layer "In7.Cu") (net 154))
  (segment (start 168.87 83) (end 169.125 83) (width 0.1) (layer "In7.Cu") (net 154))
  (segment (start 152.6026 76.1902) (end 152.6026 80.2518) (width 0.127) (layer "F.Cu") (net 155))
  (segment (start 152.6026 80.2518) (end 152.9328 80.582) (width 0.127) (layer "F.Cu") (net 155))
  (segment (start 152.9328 80.582) (end 153.4916 80.582) (width 0.127) (layer "F.Cu") (net 155))
  (segment (start 153.486999 80.580601) (end 153.986999 81.0806) (width 0.127) (layer "F.Cu") (net 155))
  (segment (start 170.733686 80.157366) (end 170.56796 80.157366) (width 0.1) (layer "F.Cu") (net 155))
  (segment (start 171.136328 80.560008) (end 170.733686 80.157366) (width 0.1) (layer "F.Cu") (net 155))
  (via locked (at 153.986999 81.0806) (size 0.5) (drill 0.2) (layers "F.Cu" "B.Cu") (net 155))
  (via (at 170.56796 80.157366) (size 0.5) (drill 0.2) (layers "F.Cu" "B.Cu") (net 155))
  (segment (start 156.508004 80.865037) (end 156.508004 82.408004) (width 0.1) (layer "In7.Cu") (net 155))
  (segment (start 169.025 81.6) (end 170.467634 80.157366) (width 0.1) (layer "In7.Cu") (net 155))
  (segment (start 156.508004 82.408004) (end 157.5 83.4) (width 0.1) (layer "In7.Cu") (net 155))
  (segment (start 154.467599 80.6) (end 156.242967 80.6) (width 0.1) (layer "In7.Cu") (net 155))
  (segment (start 166.77 83.4) (end 168.57 81.6) (width 0.1) (layer "In7.Cu") (net 155))
  (segment (start 170.467634 80.157366) (end 170.56796 80.157366) (width 0.1) (layer "In7.Cu") (net 155))
  (segment (start 168.57 81.6) (end 169.025 81.6) (width 0.1) (layer "In7.Cu") (net 155))
  (segment (start 156.242967 80.6) (end 156.508004 80.865037) (width 0.1) (layer "In7.Cu") (net 155))
  (segment (start 153.986999 81.0806) (end 154.467599 80.6) (width 0.1) (layer "In7.Cu") (net 155))
  (segment (start 157.5 83.4) (end 166.77 83.4) (width 0.1) (layer "In7.Cu") (net 155))
  (segment (start 156.482327 81.566358) (end 156.982327 82.066357) (width 0.127) (layer "F.Cu") (net 156))
  (segment (start 171.656828 79.080508) (end 171.656828 78.99) (width 0.1) (layer "F.Cu") (net 156))
  (segment (start 172.136328 79.560008) (end 171.656828 79.080508) (width 0.1) (layer "F.Cu") (net 156))
  (via locked (at 156.982327 82.066357) (size 0.5) (drill 0.2) (layers "F.Cu" "B.Cu") (net 156))
  (via (at 171.656828 78.99) (size 0.5) (drill 0.2) (layers "F.Cu" "B.Cu") (net 156))
  (segment (start 157.887867 82.36) (end 157.641928 82.114061) (width 0.1) (layer "In7.Cu") (net 156))
  (segment (start 161.54 82.55) (end 161.44 82.55) (width 0.1) (layer "In7.Cu") (net 156))
  (segment (start 163.64 82.55) (end 163.54 82.55) (width 0.1) (layer "In7.Cu") (net 156))
  (segment (start 157.429796 82.326193) (end 157.675734 82.572131) (width 0.1) (layer "In7.Cu") (net 156))
  (segment (start 162.015 82.425) (end 162.015 82.175) (width 0.1) (layer "In7.Cu") (net 156))
  (segment (start 157.675735 82.784264) (end 157.64 82.82) (width 0.1) (layer "In7.Cu") (net 156))
  (segment (start 157.675734 82.784263) (end 157.675735 82.784264) (width 0.1) (layer "In7.Cu") (net 156))
  (segment (start 162.94 82.55) (end 162.84 82.55) (width 0.1) (layer "In7.Cu") (net 156))
  (segment (start 162.715 82.425) (end 162.715 82.175) (width 0.1) (layer "In7.Cu") (net 156))
  (segment (start 163.415 82.425) (end 163.415 82.175) (width 0.1) (layer "In7.Cu") (net 156))
  (segment (start 158.16 82.3) (end 158.1 82.36) (width 0.1) (layer "In7.Cu") (net 156))
  (segment (start 169.532156 79.385) (end 169.532157 79.385) (width 0.1) (layer "In7.Cu") (net 156))
  (segment (start 169.249313 79.950685) (end 169.1 80.1) (width 0.1) (layer "In7.Cu") (net 156))
  (segment (start 163.29 82.05) (end 163.19 82.05) (width 0.1) (layer "In7.Cu") (net 156))
  (segment (start 163.065 82.175) (end 163.065 82.425) (width 0.1) (layer "In7.Cu") (net 156))
  (segment (start 171.656828 78.99) (end 171.346828 79.3) (width 0.1) (layer "In7.Cu") (net 156))
  (segment (start 161.665 82.175) (end 161.665 82.425) (width 0.1) (layer "In7.Cu") (net 156))
  (segment (start 166.3 82.3) (end 163.89 82.3) (width 0.1) (layer "In7.Cu") (net 156))
  (segment (start 168.5 80.1) (end 166.3 82.3) (width 0.1) (layer "In7.Cu") (net 156))
  (segment (start 157.64 82.82) (end 157.43 82.82) (width 0.1) (layer "In7.Cu") (net 156))
  (segment (start 161.89 82.05) (end 161.79 82.05) (width 0.1) (layer "In7.Cu") (net 156))
  (segment (start 169.1 80.1) (end 168.5 80.1) (width 0.1) (layer "In7.Cu") (net 156))
  (segment (start 162.24 82.55) (end 162.14 82.55) (width 0.1) (layer "In7.Cu") (net 156))
  (segment (start 171.346828 79.3) (end 169.9 79.3) (width 0.1) (layer "In7.Cu") (net 156))
  (segment (start 162.59 82.05) (end 162.49 82.05) (width 0.1) (layer "In7.Cu") (net 156))
  (segment (start 162.365 82.175) (end 162.365 82.425) (width 0.1) (layer "In7.Cu") (net 156))
  (segment (start 169.9 79.3) (end 169.815 79.385) (width 0.1) (layer "In7.Cu") (net 156))
  (segment (start 157.887866 82.36) (end 157.887867 82.36) (width 0.1) (layer "In7.Cu") (net 156))
  (segment (start 156.982327 82.372327) (end 156.982327 82.066357) (width 0.1) (layer "In7.Cu") (net 156))
  (segment (start 157.43 82.82) (end 156.982327 82.372327) (width 0.1) (layer "In7.Cu") (net 156))
  (segment (start 169.249314 79.384999) (end 169.249314 79.385) (width 0.1) (layer "In7.Cu") (net 156))
  (segment (start 161.19 82.3) (end 158.16 82.3) (width 0.1) (layer "In7.Cu") (net 156))
  (arc (start 163.765 82.425) (mid 163.728388 82.513388) (end 163.64 82.55) (width 0.1) (layer "In7.Cu") (net 156))
  (arc (start 162.365 82.425) (mid 162.328388 82.513388) (end 162.24 82.55) (width 0.1) (layer "In7.Cu") (net 156))
  (arc (start 169.532157 79.385) (mid 169.390736 79.326421) (end 169.249314 79.384999) (width 0.1) (layer "In7.Cu") (net 156))
  (arc (start 163.89 82.3) (mid 163.801612 82.336612) (end 163.765 82.425) (width 0.1) (layer "In7.Cu") (net 156))
  (arc (start 162.49 82.05) (mid 162.401612 82.086612) (end 162.365 82.175) (width 0.1) (layer "In7.Cu") (net 156))
  (arc (start 161.79 82.05) (mid 161.701612 82.086612) (end 161.665 82.175) (width 0.1) (layer "In7.Cu") (net 156))
  (arc (start 163.415 82.175) (mid 163.378388 82.086612) (end 163.29 82.05) (width 0.1) (layer "In7.Cu") (net 156))
  (arc (start 161.665 82.425) (mid 161.628388 82.513388) (end 161.54 82.55) (width 0.1) (layer "In7.Cu") (net 156))
  (arc (start 161.44 82.55) (mid 161.351612 82.513388) (end 161.315 82.425) (width 0.1) (layer "In7.Cu") (net 156))
  (arc (start 163.54 82.55) (mid 163.451612 82.513388) (end 163.415 82.425) (width 0.1) (layer "In7.Cu") (net 156))
  (arc (start 163.19 82.05) (mid 163.101612 82.086612) (end 163.065 82.175) (width 0.1) (layer "In7.Cu") (net 156))
  (arc (start 157.641928 82.114061) (mid 157.535862 82.070127) (end 157.429796 82.114061) (width 0.1) (layer "In7.Cu") (net 156))
  (arc (start 157.675734 82.572131) (mid 157.719668 82.678197) (end 157.675734 82.784263) (width 0.1) (layer "In7.Cu") (net 156))
  (arc (start 162.715 82.175) (mid 162.678388 82.086612) (end 162.59 82.05) (width 0.1) (layer "In7.Cu") (net 156))
  (arc (start 162.14 82.55) (mid 162.051612 82.513388) (end 162.015 82.425) (width 0.1) (layer "In7.Cu") (net 156))
  (arc (start 163.065 82.425) (mid 163.028388 82.513388) (end 162.94 82.55) (width 0.1) (layer "In7.Cu") (net 156))
  (arc (start 169.249314 79.385) (mid 169.190736 79.526421) (end 169.249314 79.667842) (width 0.1) (layer "In7.Cu") (net 156))
  (arc (start 169.249314 79.667842) (mid 169.307892 79.809264) (end 169.249313 79.950685) (width 0.1) (layer "In7.Cu") (net 156))
  (arc (start 162.015 82.175) (mid 161.978388 82.086612) (end 161.89 82.05) (width 0.1) (layer "In7.Cu") (net 156))
  (arc (start 158.1 82.36) (mid 157.993933 82.403934) (end 157.887866 82.36) (width 0.1) (layer "In7.Cu") (net 156))
  (arc (start 162.84 82.55) (mid 162.751612 82.513388) (end 162.715 82.425) (width 0.1) (layer "In7.Cu") (net 156))
  (arc (start 169.815 79.385) (mid 169.673578 79.443579) (end 169.532156 79.385) (width 0.1) (layer "In7.Cu") (net 156))
  (arc (start 157.429796 82.114061) (mid 157.385862 82.220127) (end 157.429796 82.326193) (width 0.1) (layer "In7.Cu") (net 156))
  (arc (start 161.315 82.425) (mid 161.278388 82.336612) (end 161.19 82.3) (width 0.1) (layer "In7.Cu") (net 156))
  (segment (start 156.482327 80.575758) (end 156.982327 81.075757) (width 0.127) (layer "F.Cu") (net 157))
  (segment (start 173.673 78.063) (end 174.136328 78.526328) (width 0.1) (layer "F.Cu") (net 157))
  (segment (start 174.136328 78.526328) (end 174.136328 78.560008) (width 0.1) (layer "F.Cu") (net 157))
  (segment (start 173.673 78.001) (end 173.673 78.063) (width 0.1) (layer "F.Cu") (net 157))
  (via locked (at 156.982327 81.075757) (size 0.5) (drill 0.2) (layers "F.Cu" "B.Cu") (net 157))
  (via (at 173.673 78.001) (size 0.5) (drill 0.2) (layers "F.Cu" "B.Cu") (net 157))
  (segment (start 171.379178 77.6) (end 170.579178 78.4) (width 0.1) (layer "In7.Cu") (net 157))
  (segment (start 173.14 77.83) (end 172.91 77.6) (width 0.1) (layer "In7.Cu") (net 157))
  (segment (start 173.14 78.19) (end 173.14 77.83) (width 0.1) (layer "In7.Cu") (net 157))
  (segment (start 173.59 78.4) (end 173.35 78.4) (width 0.1) (layer "In7.Cu") (net 157))
  (segment (start 173.673 78.317) (end 173.59 78.4) (width 0.1) (layer "In7.Cu") (net 157))
  (segment (start 168.725 78.8) (end 168.075 78.8) (width 0.1) (layer "In7.Cu") (net 157))
  (segment (start 168.075 78.8) (end 165.675 81.2) (width 0.1) (layer "In7.Cu") (net 157))
  (segment (start 157.445757 81.525757) (end 157.445757 81.225757) (width 0.1) (layer "In7.Cu") (net 157))
  (segment (start 173.35 78.4) (end 173.14 78.19) (width 0.1) (layer "In7.Cu") (net 157))
  (segment (start 170.579178 78.4) (end 169.125 78.4) (width 0.1) (layer "In7.Cu") (net 157))
  (segment (start 165.675 81.2) (end 158.17 81.2) (width 0.1) (layer "In7.Cu") (net 157))
  (segment (start 173.673 78.001) (end 173.673 78.317) (width 0.1) (layer "In7.Cu") (net 157))
  (segment (start 172.91 77.6) (end 171.379178 77.6) (width 0.1) (layer "In7.Cu") (net 157))
  (segment (start 158.17 81.2) (end 158.045757 81.075757) (width 0.1) (layer "In7.Cu") (net 157))
  (segment (start 158.045757 81.075757) (end 157.895757 81.075757) (width 0.1) (layer "In7.Cu") (net 157))
  (segment (start 169.125 78.4) (end 168.725 78.8) (width 0.1) (layer "In7.Cu") (net 157))
  (segment (start 157.745757 81.225757) (end 157.745757 81.525757) (width 0.1) (layer "In7.Cu") (net 157))
  (segment (start 157.295757 81.075757) (end 156.982327 81.075757) (width 0.1) (layer "In7.Cu") (net 157))
  (arc (start 157.445757 81.225757) (mid 157.401823 81.119691) (end 157.295757 81.075757) (width 0.1) (layer "In7.Cu") (net 157))
  (arc (start 157.745757 81.525757) (mid 157.701823 81.631823) (end 157.595757 81.675757) (width 0.1) (layer "In7.Cu") (net 157))
  (arc (start 157.595757 81.675757) (mid 157.489691 81.631823) (end 157.445757 81.525757) (width 0.1) (layer "In7.Cu") (net 157))
  (arc (start 157.895757 81.075757) (mid 157.789691 81.119691) (end 157.745757 81.225757) (width 0.1) (layer "In7.Cu") (net 157))
  (segment (start 155.491727 80.575758) (end 155.991727 81.075757) (width 0.127) (layer "F.Cu") (net 158))
  (segment (start 173.816828 79.097728) (end 173.816828 79.186828) (width 0.1) (layer "F.Cu") (net 158))
  (segment (start 173.816828 79.186828) (end 174.136328 79.506328) (width 0.1) (layer "F.Cu") (net 158))
  (segment (start 174.136328 79.506328) (end 174.136328 79.560008) (width 0.1) (layer "F.Cu") (net 158))
  (via locked (at 155.991727 81.075757) (size 0.5) (drill 0.2) (layers "F.Cu" "B.Cu") (net 158))
  (via (at 173.816828 79.097728) (size 0.5) (drill 0.2) (layers "F.Cu" "B.Cu") (net 158))
  (segment (start 156.1375 82.6375) (end 156.5 83) (width 0.1) (layer "In7.Cu") (net 158))
  (segment (start 157.3 84) (end 166.98 84) (width 0.1) (layer "In7.Cu") (net 158))
  (segment (start 169.025 82.3) (end 170.585 80.74) (width 0.1) (layer "In7.Cu") (net 158))
  (segment (start 155.991727 81.075757) (end 155.58 81.487484) (width 0.1) (layer "In7.Cu") (net 158))
  (segment (start 155.8475 82.6375) (end 156.1375 82.6375) (width 0.1) (layer "In7.Cu") (net 158))
  (segment (start 172.15 80.31) (end 172.15 79.85) (width 0.1) (layer "In7.Cu") (net 158))
  (segment (start 170.585 80.74) (end 171.72 80.74) (width 0.1) (layer "In7.Cu") (net 158))
  (segment (start 155.58 82.37) (end 155.8475 82.6375) (width 0.1) (layer "In7.Cu") (net 158))
  (segment (start 155.58 81.487484) (end 155.58 82.37) (width 0.1) (layer "In7.Cu") (net 158))
  (segment (start 156.5 83.2) (end 157.3 84) (width 0.1) (layer "In7.Cu") (net 158))
  (segment (start 166.98 84) (end 168.68 82.3) (width 0.1) (layer "In7.Cu") (net 158))
  (segment (start 172.4 79.6) (end 173.314556 79.6) (width 0.1) (layer "In7.Cu") (net 158))
  (segment (start 172.15 79.85) (end 172.4 79.6) (width 0.1) (layer "In7.Cu") (net 158))
  (segment (start 156.5 83) (end 156.5 83.2) (width 0.1) (layer "In7.Cu") (net 158))
  (segment (start 168.68 82.3) (end 169.025 82.3) (width 0.1) (layer "In7.Cu") (net 158))
  (segment (start 171.72 80.74) (end 172.15 80.31) (width 0.1) (layer "In7.Cu") (net 158))
  (segment (start 173.314556 79.6) (end 173.816828 79.097728) (width 0.1) (layer "In7.Cu") (net 158))
  (segment (start 153.71315 82.959692) (end 153.713149 82.959693) (width 0.1) (layer "F.Cu") (net 159))
  (segment (start 154.411055 82.221055) (end 153.781079 82.221055) (width 0.1) (layer "F.Cu") (net 159))
  (segment (start 154.112661 83.125865) (end 154.112662 83.125864) (width 0.1) (layer "F.Cu") (net 159))
  (segment (start 164.907859 78.910007) (end 171.079993 78.910007) (width 0.1) (layer "F.Cu") (net 159))
  (segment (start 153.33 82.859386) (end 153.430307 82.959693) (width 0.1) (layer "F.Cu") (net 159))
  (segment (start 153.995992 83.525377) (end 153.995991 83.525377) (width 0.1) (layer "F.Cu") (net 159))
  (segment (start 154.496328 82.577157) (end 154.496328 82.306328) (width 0.1) (layer "F.Cu") (net 159))
  (segment (start 153.713149 82.959693) (end 153.82982 82.843023) (width 0.1) (layer "F.Cu") (net 159))
  (segment (start 153.995991 83.525377) (end 154.030614 83.56) (width 0.1) (layer "F.Cu") (net 159))
  (segment (start 171.136328 78.853672) (end 171.136328 78.560008) (width 0.1) (layer "F.Cu") (net 159))
  (segment (start 160.257866 83.56) (end 164.907859 78.910007) (width 0.1) (layer "F.Cu") (net 159))
  (segment (start 153.33 82.672134) (end 153.33 82.859386) (width 0.1) (layer "F.Cu") (net 159))
  (segment (start 154.112662 83.125864) (end 153.995992 83.242535) (width 0.1) (layer "F.Cu") (net 159))
  (segment (start 154.030614 83.56) (end 160.257866 83.56) (width 0.1) (layer "F.Cu") (net 159))
  (segment (start 171.079993 78.910007) (end 171.136328 78.853672) (width 0.1) (layer "F.Cu") (net 159))
  (segment (start 153.781079 82.221055) (end 153.33 82.672134) (width 0.1) (layer "F.Cu") (net 159))
  (segment (start 154.112662 82.843023) (end 154.112662 82.843022) (width 0.1) (layer "F.Cu") (net 159))
  (segment (start 154.496328 82.306328) (end 154.411055 82.221055) (width 0.1) (layer "F.Cu") (net 159))
  (arc (start 153.82982 82.843023) (mid 153.97124 82.784444) (end 154.112662 82.843023) (width 0.1) (layer "F.Cu") (net 159))
  (arc (start 153.430307 82.959693) (mid 153.571729 83.018271) (end 153.71315 82.959692) (width 0.1) (layer "F.Cu") (net 159))
  (arc (start 153.995992 83.242535) (mid 153.937413 83.383955) (end 153.995992 83.525377) (width 0.1) (layer "F.Cu") (net 159))
  (arc (start 154.112662 82.843022) (mid 154.17124 82.984444) (end 154.112661 83.125865) (width 0.1) (layer "F.Cu") (net 159))
  (segment (start 171.455828 77.052164) (end 171.628484 77.052164) (width 0.1) (layer "F.Cu") (net 160))
  (segment (start 158.285128 80.728957) (end 158.284085 80.73) (width 0.127) (layer "F.Cu") (net 160))
  (segment (start 157.92 80.73) (end 157.767157 80.577157) (width 0.127) (layer "F.Cu") (net 160))
  (segment (start 158.284085 80.73) (end 157.92 80.73) (width 0.127) (layer "F.Cu") (net 160))
  (segment (start 157.767157 80.577157) (end 157.496328 80.577157) (width 0.127) (layer "F.Cu") (net 160))
  (segment (start 171.628484 77.052164) (end 172.136328 77.560008) (width 0.1) (layer "F.Cu") (net 160))
  (via locked (at 158.285128 80.728957) (size 0.5) (drill 0.2) (layers "F.Cu" "B.Cu") (net 160))
  (via (at 171.455828 77.052164) (size 0.5) (drill 0.2) (layers "F.Cu" "B.Cu") (net 160))
  (segment (start 166.312561 79.884219) (end 166.31256 79.884219) (width 0.1) (layer "In7.Cu") (net 160))
  (segment (start 167.055024 79.31853) (end 167.055024 79.318531) (width 0.1) (layer "In7.Cu") (net 160))
  (segment (start 170.2925 77.6725) (end 170.2925 77.5225) (width 0.1) (layer "In7.Cu") (net 160))
  (segment (start 165.888292 79.954928) (end 165.888293 79.954928) (width 0.1) (layer "In7.Cu") (net 160))
  (segment (start 167.55 78.823554) (end 167.479289 78.894266) (width 0.1) (layer "In7.Cu") (net 160))
  (segment (start 166.453981 79.212465) (end 166.453981 79.212464) (width 0.1) (layer "In7.Cu") (net 160))
  (segment (start 167.302512 78.894267) (end 167.302513 78.894265) (width 0.1) (layer "In7.Cu") (net 160))
  (segment (start 165.291043 80.728957) (end 158.285128 80.728957) (width 0.1) (layer "In7.Cu") (net 160))
  (segment (start 167.55 78.646778) (end 167.549999 78.646778) (width 0.1) (layer "In7.Cu") (net 160))
  (segment (start 170.635492 77.8725) (end 170.4925 77.8725) (width 0.1) (layer "In7.Cu") (net 160))
  (segment (start 166.383269 79.459951) (end 166.38327 79.459951) (width 0.1) (layer "In7.Cu") (net 160))
  (segment (start 169.6925 77.8725) (end 169.0275 77.8725) (width 0.1) (layer "In7.Cu") (net 160))
  (segment (start 166.453981 79.212464) (end 166.38327 79.283174) (width 0.1) (layer "In7.Cu") (net 160))
  (segment (start 166.878247 78.964974) (end 167.055025 79.141753) (width 0.1) (layer "In7.Cu") (net 160))
  (segment (start 166.948958 78.717488) (end 166.948958 78.717487) (width 0.1) (layer "In7.Cu") (net 160))
  (segment (start 166.38327 79.459951) (end 166.560048 79.63673) (width 0.1) (layer "In7.Cu") (net 160))
  (segment (start 167.55 78.823555) (end 167.55 78.823554) (width 0.1) (layer "In7.Cu") (net 160))
  (segment (start 167.055024 79.318531) (end 166.984315 79.389241) (width 0.1) (layer "In7.Cu") (net 160))
  (segment (start 168.2 78.367562) (end 168.2 78.3) (width 0.1) (layer "In7.Cu") (net 160))
  (segment (start 171.455828 77.052164) (end 170.635492 77.8725) (width 0.1) (layer "In7.Cu") (net 160))
  (segment (start 166.807537 79.389242) (end 166.630758 79.212464) (width 0.1) (layer "In7.Cu") (net 160))
  (segment (start 166.560047 79.813507) (end 166.560047 79.813508) (width 0.1) (layer "In7.Cu") (net 160))
  (segment (start 166.31256 79.884219) (end 166.135781 79.707441) (width 0.1) (layer "In7.Cu") (net 160))
  (segment (start 165.959004 79.707442) (end 165.959004 79.707441) (width 0.1) (layer "In7.Cu") (net 160))
  (segment (start 166.878246 78.964974) (end 166.878247 78.964974) (width 0.1) (layer "In7.Cu") (net 160))
  (segment (start 166.560047 79.813508) (end 166.489338 79.884218) (width 0.1) (layer "In7.Cu") (net 160))
  (segment (start 165.888292 80.131705) (end 165.291043 80.728957) (width 0.1) (layer "In7.Cu") (net 160))
  (segment (start 169.8925 77.5225) (end 169.8925 77.6725) (width 0.1) (layer "In7.Cu") (net 160))
  (segment (start 166.948958 78.717487) (end 166.878247 78.788197) (width 0.1) (layer "In7.Cu") (net 160))
  (segment (start 168 78.1) (end 167.95 78.1) (width 0.1) (layer "In7.Cu") (net 160))
  (segment (start 169.0275 77.8725) (end 168.8 78.1) (width 0.1) (layer "In7.Cu") (net 160))
  (segment (start 165.959004 79.707441) (end 165.888293 79.778151) (width 0.1) (layer "In7.Cu") (net 160))
  (segment (start 167.92 78.1) (end 167.55 78.47) (width 0.1) (layer "In7.Cu") (net 160))
  (segment (start 166.807538 79.389242) (end 166.807537 79.389242) (width 0.1) (layer "In7.Cu") (net 160))
  (segment (start 168.6 78.3) (end 168.6 78.367562) (width 0.1) (layer "In7.Cu") (net 160))
  (segment (start 167.95 78.1) (end 167.92 78.1) (width 0.1) (layer "In7.Cu") (net 160))
  (segment (start 167.302513 78.894265) (end 167.125735 78.717487) (width 0.1) (layer "In7.Cu") (net 160))
  (arc (start 168.8 78.1) (mid 168.658579 78.158579) (end 168.6 78.3) (width 0.1) (layer "In7.Cu") (net 160))
  (arc (start 170.4925 77.8725) (mid 170.351079 77.813921) (end 170.2925 77.6725) (width 0.1) (layer "In7.Cu") (net 160))
  (arc (start 166.878247 78.788197) (mid 166.841635 78.876585) (end 166.878246 78.964974) (width 0.1) (layer "In7.Cu") (net 160))
  (arc (start 168.4 78.567562) (mid 168.258579 78.508983) (end 168.2 78.367562) (width 0.1) (layer "In7.Cu") (net 160))
  (arc (start 169.8925 77.6725) (mid 169.833921 77.813921) (end 169.6925 77.8725) (width 0.1) (layer "In7.Cu") (net 160))
  (arc (start 167.55 78.47) (mid 167.513387 78.55839) (end 167.55 78.646778) (width 0.1) (layer "In7.Cu") (net 160))
  (arc (start 170.2925 77.5225) (mid 170.233921 77.381079) (end 170.0925 77.3225) (width 0.1) (layer "In7.Cu") (net 160))
  (arc (start 167.055025 79.141753) (mid 167.091636 79.230142) (end 167.055024 79.31853) (width 0.1) (layer "In7.Cu") (net 160))
  (arc (start 166.38327 79.283174) (mid 166.346658 79.371562) (end 166.383269 79.459951) (width 0.1) (layer "In7.Cu") (net 160))
  (arc (start 166.560048 79.63673) (mid 166.596659 79.725119) (end 166.560047 79.813507) (width 0.1) (layer "In7.Cu") (net 160))
  (arc (start 170.0925 77.3225) (mid 169.951079 77.381079) (end 169.8925 77.5225) (width 0.1) (layer "In7.Cu") (net 160))
  (arc (start 166.630758 79.212464) (mid 166.542369 79.175853) (end 166.453981 79.212465) (width 0.1) (layer "In7.Cu") (net 160))
  (arc (start 166.984315 79.389241) (mid 166.895927 79.425853) (end 166.807538 79.389242) (width 0.1) (layer "In7.Cu") (net 160))
  (arc (start 167.125735 78.717487) (mid 167.037346 78.680876) (end 166.948958 78.717488) (width 0.1) (layer "In7.Cu") (net 160))
  (arc (start 166.489338 79.884218) (mid 166.40095 79.92083) (end 166.312561 79.884219) (width 0.1) (layer "In7.Cu") (net 160))
  (arc (start 165.888293 79.954928) (mid 165.924904 80.043317) (end 165.888292 80.131705) (width 0.1) (layer "In7.Cu") (net 160))
  (arc (start 168.2 78.3) (mid 168.141421 78.158579) (end 168 78.1) (width 0.1) (layer "In7.Cu") (net 160))
  (arc (start 167.479289 78.894266) (mid 167.390901 78.930878) (end 167.302512 78.894267) (width 0.1) (layer "In7.Cu") (net 160))
  (arc (start 168.6 78.367562) (mid 168.541421 78.508983) (end 168.4 78.567562) (width 0.1) (layer "In7.Cu") (net 160))
  (arc (start 166.135781 79.707441) (mid 166.047392 79.67083) (end 165.959004 79.707442) (width 0.1) (layer "In7.Cu") (net 160))
  (arc (start 167.549999 78.646778) (mid 167.586611 78.735166) (end 167.55 78.823555) (width 0.1) (layer "In7.Cu") (net 160))
  (arc (start 165.888293 79.778151) (mid 165.851681 79.866539) (end 165.888292 79.954928) (width 0.1) (layer "In7.Cu") (net 160))
  (segment (start 174.136328 77.456328) (end 174.136328 77.560008) (width 0.1) (layer "F.Cu") (net 161))
  (segment (start 155.982528 79.070556) (end 156.482527 78.570556) (width 0.127) (layer "F.Cu") (net 161))
  (segment (start 173.76 77.02) (end 173.76 77.08) (width 0.1) (layer "F.Cu") (net 161))
  (segment (start 173.76 77.08) (end 174.136328 77.456328) (width 0.1) (layer "F.Cu") (net 161))
  (via locked (at 155.982528 79.070556) (size 0.5) (drill 0.2) (layers "F.Cu" "B.Cu") (net 161))
  (via (at 173.76 77.02) (size 0.5) (drill 0.2) (layers "F.Cu" "B.Cu") (net 161))
  (segment (start 173.32 77.02) (end 173.76 77.02) (width 0.1) (layer "In7.Cu") (net 161))
  (segment (start 172.49 76.19) (end 173.32 77.02) (width 0.1) (layer "In7.Cu") (net 161))
  (segment (start 156.511972 79.6) (end 159.1 79.6) (width 0.1) (layer "In7.Cu") (net 161))
  (segment (start 167.65 76.7) (end 169.5 76.7) (width 0.1) (layer "In7.Cu") (net 161))
  (segment (start 169.5 76.7) (end 170.01 76.19) (width 0.1) (layer "In7.Cu") (net 161))
  (segment (start 159.325 79.375) (end 159.325 79.021673) (width 0.1) (layer "In7.Cu") (net 161))
  (segment (start 160 79.6) (end 164.75 79.6) (width 0.1) (layer "In7.Cu") (net 161))
  (segment (start 155.982528 79.070556) (end 156.511972 79.6) (width 0.1) (layer "In7.Cu") (net 161))
  (segment (start 164.75 79.6) (end 167.65 76.7) (width 0.1) (layer "In7.Cu") (net 161))
  (segment (start 159.775 79.021673) (end 159.775 79.375) (width 0.1) (layer "In7.Cu") (net 161))
  (segment (start 170.01 76.19) (end 172.49 76.19) (width 0.1) (layer "In7.Cu") (net 161))
  (arc (start 159.55 78.796673) (mid 159.709099 78.862574) (end 159.775 79.021673) (width 0.1) (layer "In7.Cu") (net 161))
  (arc (start 159.325 79.021673) (mid 159.390901 78.862574) (end 159.55 78.796673) (width 0.1) (layer "In7.Cu") (net 161))
  (arc (start 159.775 79.375) (mid 159.840901 79.534099) (end 160 79.6) (width 0.1) (layer "In7.Cu") (net 161))
  (arc (start 159.1 79.6) (mid 159.259099 79.534099) (end 159.325 79.375) (width 0.1) (layer "In7.Cu") (net 161))
  (segment (start 172.6095 78.99) (end 172.6095 79.03318) (width 0.1) (layer "F.Cu") (net 162))
  (segment (start 157.95 82.78) (end 157.747157 82.577157) (width 0.127) (layer "F.Cu") (net 162))
  (segment (start 172.6095 79.03318) (end 173.136328 79.560008) (width 0.1) (layer "F.Cu") (net 162))
  (segment (start 158.26 82.78) (end 157.95 82.78) (width 0.127) (layer "F.Cu") (net 162))
  (segment (start 157.747157 82.577157) (end 157.496328 82.577157) (width 0.127) (layer "F.Cu") (net 162))
  (via (at 158.26 82.78) (size 0.5) (drill 0.2) (layers "F.Cu" "B.Cu") (net 162))
  (via (at 172.6095 78.99) (size 0.5) (drill 0.2) (layers "F.Cu" "B.Cu") (net 162))
  (segment (start 166.86526 82.691521) (end 166.865259 82.691521) (width 0.1) (layer "In7.Cu") (net 162))
  (segment (start 171.719992 79.640008) (end 170.229992 79.640008) (width 0.1) (layer "In7.Cu") (net 162))
  (segment (start 166.865259 82.691521) (end 166.900876 82.727138) (width 0.1) (layer "In7.Cu") (net 162))
  (segment (start 167.130424 82.037441) (end 167.360235 82.267253) (width 0.1) (layer "In7.Cu") (net 162))
  (segment (start 167.625401 81.542464) (end 167.855212 81.772276) (width 0.1) (layer "In7.Cu") (net 162))
  (segment (start 168.155734 80.799999) (end 168.155734 80.8) (width 0.1) (layer "In7.Cu") (net 162))
  (segment (start 165.738106 83.188106) (end 165.638106 83.188106) (width 0.1) (layer "In7.Cu") (net 162))
  (segment (start 158.968106 82.938106) (end 158.81 82.78) (width 0.1) (layer "In7.Cu") (net 162))
  (segment (start 172.6095 78.99) (end 172.3395 79.26) (width 0.1) (layer "In7.Cu") (net 162))
  (segment (start 165.163106 82.713106) (end 165.163106 83.063106) (width 0.1) (layer "In7.Cu") (net 162))
  (segment (start 166.404765 82.913106) (end 166.363106 82.913106) (width 0.1) (layer "In7.Cu") (net 162))
  (segment (start 165.863106 82.713106) (end 165.863106 83.063106) (width 0.1) (layer "In7.Cu") (net 162))
  (segment (start 165.038106 83.188106) (end 164.938106 83.188106) (width 0.1) (layer "In7.Cu") (net 162))
  (segment (start 167.660756 81.294978) (end 167.625401 81.330332) (width 0.1) (layer "In7.Cu") (net 162))
  (segment (start 166.511708 82.868298) (end 166.510831 82.869172) (width 0.1) (layer "In7.Cu") (net 162))
  (segment (start 168.155734 80.8) (end 168.120378 80.835355) (width 0.1) (layer "In7.Cu") (net 162))
  (segment (start 172.1 79.26) (end 171.719992 79.640008) (width 0.1) (layer "In7.Cu") (net 162))
  (segment (start 167.165779 81.789955) (end 167.130424 81.825309) (width 0.1) (layer "In7.Cu") (net 162))
  (segment (start 168.120378 81.047487) (end 168.350189 81.277299) (width 0.1) (layer "In7.Cu") (net 162))
  (segment (start 168.367866 80.8) (end 168.367867 80.8) (width 0.1) (layer "In7.Cu") (net 162))
  (segment (start 168.102701 81.524788) (end 167.872889 81.294977) (width 0.1) (layer "In7.Cu") (net 162))
  (segment (start 165.513106 83.063106) (end 165.513106 82.713106) (width 0.1) (layer "In7.Cu") (net 162))
  (segment (start 167.112749 82.514741) (end 167.112747 82.514742) (width 0.1) (layer "In7.Cu") (net 162))
  (segment (start 172.3395 79.26) (end 172.1 79.26) (width 0.1) (layer "In7.Cu") (net 162))
  (segment (start 163.988106 82.938106) (end 158.968106 82.938106) (width 0.1) (layer "In7.Cu") (net 162))
  (segment (start 164.463106 82.713106) (end 164.463106 83.063106) (width 0.1) (layer "In7.Cu") (net 162))
  (segment (start 158.81 82.78) (end 158.26 82.78) (width 0.1) (layer "In7.Cu") (net 162))
  (segment (start 164.338106 83.188106) (end 164.238106 83.188106) (width 0.1) (layer "In7.Cu") (net 162))
  (segment (start 168.102703 81.524787) (end 168.102701 81.524788) (width 0.1) (layer "In7.Cu") (net 162))
  (segment (start 167.607724 82.019765) (end 167.377912 81.789954) (width 0.1) (layer "In7.Cu") (net 162))
  (segment (start 166.213106 82.763106) (end 166.213106 82.713106) (width 0.1) (layer "In7.Cu") (net 162))
  (segment (start 166.511707 82.868299) (end 166.511708 82.868298) (width 0.1) (layer "In7.Cu") (net 162))
  (segment (start 166.7241 82.903914) (end 166.688484 82.868298) (width 0.1) (layer "In7.Cu") (net 162))
  (segment (start 167.607726 82.019764) (end 167.607724 82.019765) (width 0.1) (layer "In7.Cu") (net 162))
  (segment (start 169.07 80.8) (end 168.58 80.8) (width 0.1) (layer "In7.Cu") (net 162))
  (segment (start 164.813106 83.063106) (end 164.813106 82.713106) (width 0.1) (layer "In7.Cu") (net 162))
  (segment (start 170.229992 79.640008) (end 169.07 80.8) (width 0.1) (layer "In7.Cu") (net 162))
  (segment (start 166.900875 82.903915) (end 166.900876 82.903914) (width 0.1) (layer "In7.Cu") (net 162))
  (arc (start 164.463106 83.063106) (mid 164.426494 83.151494) (end 164.338106 83.188106) (width 0.1) (layer "In7.Cu") (net 162))
  (arc (start 164.113106 83.063106) (mid 164.076494 82.974718) (end 163.988106 82.938106) (width 0.1) (layer "In7.Cu") (net 162))
  (arc (start 167.112747 82.514742) (mid 166.989003 82.463486) (end 166.86526 82.514743) (width 0.1) (layer "In7.Cu") (net 162))
  (arc (start 166.038106 82.538106) (mid 165.914362 82.589362) (end 165.863106 82.713106) (width 0.1) (layer "In7.Cu") (net 162))
  (arc (start 167.130424 81.825309) (mid 167.08649 81.931375) (end 167.130424 82.037441) (width 0.1) (layer "In7.Cu") (net 162))
  (arc (start 164.238106 83.188106) (mid 164.149718 83.151494) (end 164.113106 83.063106) (width 0.1) (layer "In7.Cu") (net 162))
  (arc (start 167.625401 81.330332) (mid 167.581467 81.436398) (end 167.625401 81.542464) (width 0.1) (layer "In7.Cu") (net 162))
  (arc (start 167.360235 82.267253) (mid 167.411491 82.390997) (end 167.360235 82.514741) (width 0.1) (layer "In7.Cu") (net 162))
  (arc (start 164.938106 83.188106) (mid 164.849718 83.151494) (end 164.813106 83.063106) (width 0.1) (layer "In7.Cu") (net 162))
  (arc (start 168.120378 80.835355) (mid 168.076444 80.941421) (end 168.120378 81.047487) (width 0.1) (layer "In7.Cu") (net 162))
  (arc (start 167.872889 81.294977) (mid 167.766822 81.251043) (end 167.660756 81.294978) (width 0.1) (layer "In7.Cu") (net 162))
  (arc (start 165.163106 83.063106) (mid 165.126494 83.151494) (end 165.038106 83.188106) (width 0.1) (layer "In7.Cu") (net 162))
  (arc (start 166.900876 82.727138) (mid 166.937487 82.815527) (end 166.900875 82.903915) (width 0.1) (layer "In7.Cu") (net 162))
  (arc (start 168.350189 81.524787) (mid 168.226445 81.576044) (end 168.102703 81.524787) (width 0.1) (layer "In7.Cu") (net 162))
  (arc (start 165.338106 82.538106) (mid 165.214362 82.589362) (end 165.163106 82.713106) (width 0.1) (layer "In7.Cu") (net 162))
  (arc (start 166.900876 82.903914) (mid 166.812488 82.940526) (end 166.7241 82.903914) (width 0.1) (layer "In7.Cu") (net 162))
  (arc (start 167.360235 82.514741) (mid 167.236491 82.565998) (end 167.112749 82.514741) (width 0.1) (layer "In7.Cu") (net 162))
  (arc (start 166.688484 82.868298) (mid 166.600095 82.831687) (end 166.511707 82.868299) (width 0.1) (layer "In7.Cu") (net 162))
  (arc (start 168.367867 80.8) (mid 168.261801 80.756065) (end 168.155734 80.799999) (width 0.1) (layer "In7.Cu") (net 162))
  (arc (start 166.363106 82.913106) (mid 166.25704 82.869172) (end 166.213106 82.763106) (width 0.1) (layer "In7.Cu") (net 162))
  (arc (start 164.638106 82.538106) (mid 164.514362 82.589362) (end 164.463106 82.713106) (width 0.1) (layer "In7.Cu") (net 162))
  (arc (start 167.377912 81.789954) (mid 167.271845 81.74602) (end 167.165779 81.789955) (width 0.1) (layer "In7.Cu") (net 162))
  (arc (start 166.510831 82.869172) (mid 166.462168 82.901688) (end 166.404765 82.913106) (width 0.1) (layer "In7.Cu") (net 162))
  (arc (start 168.350189 81.277299) (mid 168.401445 81.401043) (end 168.350189 81.524787) (width 0.1) (layer "In7.Cu") (net 162))
  (arc (start 165.863106 83.063106) (mid 165.826494 83.151494) (end 165.738106 83.188106) (width 0.1) (layer "In7.Cu") (net 162))
  (arc (start 167.855212 82.019764) (mid 167.731468 82.071021) (end 167.607726 82.019764) (width 0.1) (layer "In7.Cu") (net 162))
  (arc (start 165.513106 82.713106) (mid 165.46185 82.589362) (end 165.338106 82.538106) (width 0.1) (layer "In7.Cu") (net 162))
  (arc (start 166.213106 82.713106) (mid 166.16185 82.589362) (end 166.038106 82.538106) (width 0.1) (layer "In7.Cu") (net 162))
  (arc (start 164.813106 82.713106) (mid 164.76185 82.589362) (end 164.638106 82.538106) (width 0.1) (layer "In7.Cu") (net 162))
  (arc (start 166.86526 82.514743) (mid 166.828647 82.603133) (end 166.86526 82.691521) (width 0.1) (layer "In7.Cu") (net 162))
  (arc (start 167.855212 81.772276) (mid 167.906468 81.89602) (end 167.855212 82.019764) (width 0.1) (layer "In7.Cu") (net 162))
  (arc (start 168.58 80.8) (mid 168.473933 80.843934) (end 168.367866 80.8) (width 0.1) (layer "In7.Cu") (net 162))
  (arc (start 165.638106 83.188106) (mid 165.549718 83.151494) (end 165.513106 83.063106) (width 0.1) (layer "In7.Cu") (net 162))
  (segment (start 157.767157 81.577157) (end 157.496328 81.577157) (width 0.127) (layer "F.Cu") (net 163))
  (segment (start 157.95 81.76) (end 157.767157 81.577157) (width 0.127) (layer "F.Cu") (net 163))
  (segment (start 172.136328 78.560008) (end 171.636328 78.060008) (width 0.1) (layer "F.Cu") (net 163))
  (segment (start 158.27 81.76) (end 157.95 81.76) (width 0.127) (layer "F.Cu") (net 163))
  (via (at 158.27 81.76) (size 0.5) (drill 0.2) (layers "F.Cu" "B.Cu") (net 163))
  (via (at 171.636328 78.060008) (size 0.5) (drill 0.2) (layers "F.Cu" "B.Cu") (net 163))
  (segment (start 166.987912 80.599954) (end 167.200047 80.812088) (width 0.1) (layer "In7.Cu") (net 163))
  (segment (start 166.740424 80.635309) (end 166.775779 80.599955) (width 0.1) (layer "In7.Cu") (net 163))
  (segment (start 168.3 79.5) (end 168.63 79.5) (width 0.1) (layer "In7.Cu") (net 163))
  (segment (start 166.917202 81.307065) (end 166.952557 81.271709) (width 0.1) (layer "In7.Cu") (net 163))
  (segment (start 170.846336 78.85) (end 171.636328 78.060008) (width 0.1) (layer "In7.Cu") (net 163))
  (segment (start 165.000357 81.920357) (end 165.000357 81.595357) (width 0.1) (layer "In7.Cu") (net 163))
  (segment (start 165.500357 82.070357) (end 165.550357 82.070357) (width 0.1) (layer "In7.Cu") (net 163))
  (segment (start 166.740424 80.847441) (end 166.952558 81.059576) (width 0.1) (layer "In7.Cu") (net 163))
  (segment (start 164.650357 81.595357) (end 164.650357 81.920357) (width 0.1) (layer "In7.Cu") (net 163))
  (segment (start 167.482889 80.104977) (end 167.695024 80.317111) (width 0.1) (layer "In7.Cu") (net 163))
  (segment (start 163.43 81.58) (end 163.620357 81.770357) (width 0.1) (layer "In7.Cu") (net 163))
  (segment (start 163.229286 81.58) (end 163.43 81.58) (width 0.1) (layer "In7.Cu") (net 163))
  (segment (start 166.492935 81.094931) (end 166.70507 81.307065) (width 0.1) (layer "In7.Cu") (net 163))
  (segment (start 167.235401 80.140332) (end 167.270756 80.104978) (width 0.1) (layer "In7.Cu") (net 163))
  (segment (start 167.730378 79.645355) (end 167.765734 79.61) (width 0.1) (layer "In7.Cu") (net 163))
  (segment (start 163.620357 81.770357) (end 163.800357 81.770357) (width 0.1) (layer "In7.Cu") (net 163))
  (segment (start 167.235401 80.352464) (end 167.447535 80.564599) (width 0.1) (layer "In7.Cu") (net 163))
  (segment (start 164.300357 81.920357) (end 164.300357 81.595357) (width 0.1) (layer "In7.Cu") (net 163))
  (segment (start 163.039286 81.77) (end 163.229286 81.58) (width 0.1) (layer "In7.Cu") (net 163))
  (segment (start 168.19 79.61) (end 168.3 79.5) (width 0.1) (layer "In7.Cu") (net 163))
  (segment (start 167.977867 79.61) (end 167.977866 79.61) (width 0.1) (layer "In7.Cu") (net 163))
  (segment (start 164.800357 82.070357) (end 164.850357 82.070357) (width 0.1) (layer "In7.Cu") (net 163))
  (segment (start 167.412179 80.812088) (end 167.447534 80.776732) (width 0.1) (layer "In7.Cu") (net 163))
  (segment (start 165.350357 81.595357) (end 165.350357 81.920357) (width 0.1) (layer "In7.Cu") (net 163))
  (segment (start 168.63 79.5) (end 169.28 78.85) (width 0.1) (layer "In7.Cu") (net 163))
  (segment (start 158.28 81.77) (end 163.039286 81.77) (width 0.1) (layer "In7.Cu") (net 163))
  (segment (start 167.730378 79.857487) (end 167.942512 80.069622) (width 0.1) (layer "In7.Cu") (net 163))
  (segment (start 166.245447 81.130286) (end 166.280802 81.094932) (width 0.1) (layer "In7.Cu") (net 163))
  (segment (start 158.27 81.76) (end 158.28 81.77) (width 0.1) (layer "In7.Cu") (net 163))
  (segment (start 167.765734 79.61) (end 167.765734 79.609999) (width 0.1) (layer "In7.Cu") (net 163))
  (segment (start 166.029643 81.770357) (end 166.245446 81.554551) (width 0.1) (layer "In7.Cu") (net 163))
  (segment (start 169.28 78.85) (end 170.846336 78.85) (width 0.1) (layer "In7.Cu") (net 163))
  (segment (start 164.100357 82.070357) (end 164.150357 82.070357) (width 0.1) (layer "In7.Cu") (net 163))
  (segment (start 167.907156 80.317111) (end 167.942511 80.281755) (width 0.1) (layer "In7.Cu") (net 163))
  (segment (start 165.850357 81.770357) (end 166.029643 81.770357) (width 0.1) (layer "In7.Cu") (net 163))
  (arc (start 167.977866 79.61) (mid 168.083933 79.653934) (end 168.19 79.61) (width 0.1) (layer "In7.Cu") (net 163))
  (arc (start 167.765734 79.609999) (mid 167.871801 79.566065) (end 167.977867 79.61) (width 0.1) (layer "In7.Cu") (net 163))
  (arc (start 166.245446 81.554551) (mid 166.289381 81.448485) (end 166.245447 81.342418) (width 0.1) (layer "In7.Cu") (net 163))
  (arc (start 164.650357 81.920357) (mid 164.694291 82.026423) (end 164.800357 82.070357) (width 0.1) (layer "In7.Cu") (net 163))
  (arc (start 167.730378 79.857487) (mid 167.686444 79.751421) (end 167.730378 79.645355) (width 0.1) (layer "In7.Cu") (net 163))
  (arc (start 166.70507 81.307065) (mid 166.811136 81.350999) (end 166.917202 81.307065) (width 0.1) (layer "In7.Cu") (net 163))
  (arc (start 164.150357 82.070357) (mid 164.256423 82.026423) (end 164.300357 81.920357) (width 0.1) (layer "In7.Cu") (net 163))
  (arc (start 165.700357 81.920357) (mid 165.744291 81.814291) (end 165.850357 81.770357) (width 0.1) (layer "In7.Cu") (net 163))
  (arc (start 167.200047 80.812088) (mid 167.306113 80.856022) (end 167.412179 80.812088) (width 0.1) (layer "In7.Cu") (net 163))
  (arc (start 167.447534 80.776732) (mid 167.491468 80.670667) (end 167.447535 80.564599) (width 0.1) (layer "In7.Cu") (net 163))
  (arc (start 164.475357 81.420357) (mid 164.599101 81.471613) (end 164.650357 81.595357) (width 0.1) (layer "In7.Cu") (net 163))
  (arc (start 166.245447 81.342418) (mid 166.201513 81.236352) (end 166.245447 81.130286) (width 0.1) (layer "In7.Cu") (net 163))
  (arc (start 165.000357 81.595357) (mid 165.051613 81.471613) (end 165.175357 81.420357) (width 0.1) (layer "In7.Cu") (net 163))
  (arc (start 164.850357 82.070357) (mid 164.956423 82.026423) (end 165.000357 81.920357) (width 0.1) (layer "In7.Cu") (net 163))
  (arc (start 167.942511 80.281755) (mid 167.986445 80.17569) (end 167.942512 80.069622) (width 0.1) (layer "In7.Cu") (net 163))
  (arc (start 165.350357 81.920357) (mid 165.394291 82.026423) (end 165.500357 82.070357) (width 0.1) (layer "In7.Cu") (net 163))
  (arc (start 166.740424 80.847441) (mid 166.69649 80.741375) (end 166.740424 80.635309) (width 0.1) (layer "In7.Cu") (net 163))
  (arc (start 167.235401 80.352464) (mid 167.191467 80.246398) (end 167.235401 80.140332) (width 0.1) (layer "In7.Cu") (net 163))
  (arc (start 165.175357 81.420357) (mid 165.299101 81.471613) (end 165.350357 81.595357) (width 0.1) (layer "In7.Cu") (net 163))
  (arc (start 166.280802 81.094932) (mid 166.386868 81.050997) (end 166.492935 81.094931) (width 0.1) (layer "In7.Cu") (net 163))
  (arc (start 166.775779 80.599955) (mid 166.881845 80.55602) (end 166.987912 80.599954) (width 0.1) (layer "In7.Cu") (net 163))
  (arc (start 163.800357 81.770357) (mid 163.906423 81.814291) (end 163.950357 81.920357) (width 0.1) (layer "In7.Cu") (net 163))
  (arc (start 163.950357 81.920357) (mid 163.994291 82.026423) (end 164.100357 82.070357) (width 0.1) (layer "In7.Cu") (net 163))
  (arc (start 167.270756 80.104978) (mid 167.376822 80.061043) (end 167.482889 80.104977) (width 0.1) (layer "In7.Cu") (net 163))
  (arc (start 167.695024 80.317111) (mid 167.80109 80.361045) (end 167.907156 80.317111) (width 0.1) (layer "In7.Cu") (net 163))
  (arc (start 166.952557 81.271709) (mid 166.996491 81.165644) (end 166.952558 81.059576) (width 0.1) (layer "In7.Cu") (net 163))
  (arc (start 164.300357 81.595357) (mid 164.351613 81.471613) (end 164.475357 81.420357) (width 0.1) (layer "In7.Cu") (net 163))
  (arc (start 165.550357 82.070357) (mid 165.656423 82.026423) (end 165.700357 81.920357) (width 0.1) (layer "In7.Cu") (net 163))
  (segment (start 154.496328 81.577157) (end 154.496328 81.843672) (width 0.1) (layer "F.Cu") (net 164))
  (segment (start 160.382134 83.86) (end 165.032125 79.210009) (width 0.1) (layer "F.Cu") (net 164))
  (segment (start 153.906346 83.86) (end 160.382134 83.86) (width 0.1) (layer "F.Cu") (net 164))
  (segment (start 165.032125 79.210009) (end 171.080009 79.210009) (width 0.1) (layer "F.Cu") (net 164))
  (segment (start 153.03 82.983654) (end 153.03 82.547866) (width 0.1) (layer "F.Cu") (net 164))
  (segment (start 153.03 82.983654) (end 153.906346 83.86) (width 0.1) (layer "F.Cu") (net 164))
  (segment (start 171.136328 79.266328) (end 171.136328 79.560008) (width 0.1) (layer "F.Cu") (net 164))
  (segment (start 154.496328 81.843672) (end 154.418945 81.921055) (width 0.1) (layer "F.Cu") (net 164))
  (segment (start 154.418945 81.921055) (end 153.656811 81.921055) (width 0.1) (layer "F.Cu") (net 164))
  (segment (start 171.080009 79.210009) (end 171.136328 79.266328) (width 0.1) (layer "F.Cu") (net 164))
  (segment (start 153.656811 81.921055) (end 153.03 82.547866) (width 0.1) (layer "F.Cu") (net 164))
  (segment (start 156.506329 79.585358) (end 157.006328 79.085358) (width 0.127) (layer "F.Cu") (net 165))
  (segment (start 175.136328 78.436328) (end 175.136328 78.560008) (width 0.1) (layer "F.Cu") (net 165))
  (segment (start 174.636328 77.936328) (end 175.136328 78.436328) (width 0.1) (layer "F.Cu") (net 165))
  (via locked (at 157.006328 79.085358) (size 0.5) (drill 0.2) (layers "F.Cu" "B.Cu") (net 165))
  (via (at 174.636328 77.936328) (size 0.5) (drill 0.2) (layers "F.Cu" "B.Cu") (net 165))
  (segment (start 173.345 76.475) (end 172.71 75.84) (width 0.1) (layer "In7.Cu") (net 165))
  (segment (start 157.230843 78.860843) (end 157.006328 79.085358) (width 0.1) (layer "In7.Cu") (net 165))
  (segment (start 174.636328 77.936328) (end 174.24 77.54) (width 0.1) (layer "In7.Cu") (net 165))
  (segment (start 157.639153 79.021666) (end 157.47833 78.860843) (width 0.1) (layer "In7.Cu") (net 165))
  (segment (start 160.44 79) (end 159.54 78.1) (width 0.1) (layer "In7.Cu") (net 165))
  (segment (start 167.35 76) (end 164.35 79) (width 0.1) (layer "In7.Cu") (net 165))
  (segment (start 157.317507 78.205045) (end 157.886641 78.774178) (width 0.1) (layer "In7.Cu") (net 165))
  (segment (start 158.71 78.34) (end 158.71 78.3) (width 0.1) (layer "In7.Cu") (net 165))
  (segment (start 174.025 76.475) (end 173.345 76.475) (width 0.1) (layer "In7.Cu") (net 165))
  (segment (start 157.47833 78.860843) (end 157.478329 78.860843) (width 0.1) (layer "In7.Cu") (net 165))
  (segment (start 174.24 76.69) (end 174.025 76.475) (width 0.1) (layer "In7.Cu") (net 165))
  (segment (start 159.11 78.3) (end 159.11 78.34) (width 0.1) (layer "In7.Cu") (net 165))
  (segment (start 174.24 77.54) (end 174.24 76.69) (width 0.1) (layer "In7.Cu") (net 165))
  (segment (start 158.51 78.1) (end 157.991686 78.1) (width 0.1) (layer "In7.Cu") (net 165))
  (segment (start 157.72582 78.118381) (end 157.564996 77.957557) (width 0.1) (layer "In7.Cu") (net 165))
  (segment (start 157.991686 78.1) (end 157.973308 78.118381) (width 0.1) (layer "In7.Cu") (net 165))
  (segment (start 157.317508 77.957557) (end 157.317507 77.957557) (width 0.1) (layer "In7.Cu") (net 165))
  (segment (start 172.71 75.84) (end 169.76 75.84) (width 0.1) (layer "In7.Cu") (net 165))
  (segment (start 169.76 75.84) (end 169.6 76) (width 0.1) (layer "In7.Cu") (net 165))
  (segment (start 169.6 76) (end 167.35 76) (width 0.1) (layer "In7.Cu") (net 165))
  (segment (start 164.35 79) (end 160.44 79) (width 0.1) (layer "In7.Cu") (net 165))
  (segment (start 159.54 78.1) (end 159.31 78.1) (width 0.1) (layer "In7.Cu") (net 165))
  (arc (start 157.564996 77.957557) (mid 157.441252 77.906301) (end 157.317508 77.957557) (width 0.1) (layer "In7.Cu") (net 165))
  (arc (start 157.317507 77.957557) (mid 157.266251 78.081301) (end 157.317507 78.205045) (width 0.1) (layer "In7.Cu") (net 165))
  (arc (start 159.31 78.1) (mid 159.168579 78.158579) (end 159.11 78.3) (width 0.1) (layer "In7.Cu") (net 165))
  (arc (start 157.886641 79.021666) (mid 157.762897 79.072922) (end 157.639153 79.021666) (width 0.1) (layer "In7.Cu") (net 165))
  (arc (start 157.478329 78.860843) (mid 157.354586 78.809587) (end 157.230843 78.860843) (width 0.1) (layer "In7.Cu") (net 165))
  (arc (start 159.11 78.34) (mid 159.051421 78.481421) (end 158.91 78.54) (width 0.1) (layer "In7.Cu") (net 165))
  (arc (start 157.886641 78.774178) (mid 157.937897 78.897922) (end 157.886641 79.021666) (width 0.1) (layer "In7.Cu") (net 165))
  (arc (start 158.91 78.54) (mid 158.768579 78.481421) (end 158.71 78.34) (width 0.1) (layer "In7.Cu") (net 165))
  (arc (start 158.71 78.3) (mid 158.651421 78.158579) (end 158.51 78.1) (width 0.1) (layer "In7.Cu") (net 165))
  (arc (start 157.973308 78.118381) (mid 157.849564 78.169637) (end 157.72582 78.118381) (width 0.1) (layer "In7.Cu") (net 165))
  (segment (start 155.496328 79.577157) (end 155.996328 80.077156) (width 0.127) (layer "F.Cu") (net 166))
  (segment (start 173.136328 77.560008) (end 172.62632 77.05) (width 0.1) (layer "F.Cu") (net 166))
  (segment (start 172.62632 77.05) (end 172.6095 77.05) (width 0.1) (layer "F.Cu") (net 166))
  (via locked (at 155.996328 80.077156) (size 0.5) (drill 0.2) (layers "F.Cu" "B.Cu") (net 166))
  (via (at 172.6095 77.05) (size 0.5) (drill 0.2) (layers "F.Cu" "B.Cu") (net 166))
  (segment (start 170.247852 76.632164) (end 169.480016 77.4) (width 0.1) (layer "In7.Cu") (net 166))
  (segment (start 165 80.2) (end 158.78 80.2) (width 0.1) (layer "In7.Cu") (net 166))
  (segment (start 157.440473 80.059527) (end 157.41135 80.059527) (width 0.1) (layer "In7.Cu") (net 166))
  (segment (start 157.615473 80.284527) (end 157.615473 80.234527) (width 0.1) (layer "In7.Cu") (net 166))
  (segment (start 156.73635 80.309276) (end 156.73635 80.284527) (width 0.1) (layer "In7.Cu") (net 166))
  (segment (start 157.18635 80.284527) (end 157.18635 80.309276) (width 0.1) (layer "In7.Cu") (net 166))
  (segment (start 157.965473 80.234527) (end 157.965473 80.284527) (width 0.1) (layer "In7.Cu") (net 166))
  (segment (start 158.639527 80.059527) (end 158.140473 80.059527) (width 0.1) (layer "In7.Cu") (net 166))
  (segment (start 158.78 80.2) (end 158.639527 80.059527) (width 0.1) (layer "In7.Cu") (net 166))
  (segment (start 156.013957 80.059527) (end 155.996328 80.077156) (width 0.1) (layer "In7.Cu") (net 166))
  (segment (start 172.191664 76.632164) (end 170.247852 76.632164) (width 0.1) (layer "In7.Cu") (net 166))
  (segment (start 156.51135 80.059527) (end 156.46135 80.059527) (width 0.1) (layer "In7.Cu") (net 166))
  (segment (start 169.480016 77.4) (end 167.8 77.4) (width 0.1) (layer "In7.Cu") (net 166))
  (segment (start 172.6095 77.05) (end 172.191664 76.632164) (width 0.1) (layer "In7.Cu") (net 166))
  (segment (start 167.8 77.4) (end 165 80.2) (width 0.1) (layer "In7.Cu") (net 166))
  (segment (start 156.46135 80.059527) (end 156.013957 80.059527) (width 0.1) (layer "In7.Cu") (net 166))
  (arc (start 157.41135 80.059527) (mid 157.252251 80.125428) (end 157.18635 80.284527) (width 0.1) (layer "In7.Cu") (net 166))
  (arc (start 157.790473 80.459527) (mid 157.666729 80.408271) (end 157.615473 80.284527) (width 0.1) (layer "In7.Cu") (net 166))
  (arc (start 156.73635 80.284527) (mid 156.670449 80.125428) (end 156.51135 80.059527) (width 0.1) (layer "In7.Cu") (net 166))
  (arc (start 157.965473 80.284527) (mid 157.914217 80.408271) (end 157.790473 80.459527) (width 0.1) (layer "In7.Cu") (net 166))
  (arc (start 156.96135 80.534276) (mid 156.802251 80.468375) (end 156.73635 80.309276) (width 0.1) (layer "In7.Cu") (net 166))
  (arc (start 157.615473 80.234527) (mid 157.564217 80.110783) (end 157.440473 80.059527) (width 0.1) (layer "In7.Cu") (net 166))
  (arc (start 157.18635 80.309276) (mid 157.120449 80.468375) (end 156.96135 80.534276) (width 0.1) (layer "In7.Cu") (net 166))
  (arc (start 158.140473 80.059527) (mid 158.016729 80.110783) (end 157.965473 80.234527) (width 0.1) (layer "In7.Cu") (net 166))
  (segment (start 111.448477 114.422157) (end 110.648477 113.622157) (width 0.2) (layer "F.Cu") (net 167))
  (segment (start 219.16 122.84) (end 219.845 122.84) (width 0.15) (layer "F.Cu") (net 167))
  (segment (start 110.648477 113.622157) (end 109.248477 113.622157) (width 0.2) (layer "F.Cu") (net 167))
  (segment (start 112.286328 114.422157) (end 111.448477 114.422157) (width 0.2) (layer "F.Cu") (net 167))
  (segment (start 219.845 122.84) (end 219.85 122.835) (width 0.15) (layer "F.Cu") (net 167))
  (segment (start 220.85 122.7) (end 219.985 122.7) (width 0.2) (layer "F.Cu") (net 167))
  (segment (start 219.985 122.7) (end 219.85 122.835) (width 0.2) (layer "F.Cu") (net 167))
  (via (at 145.95 114.1) (size 0.5) (drill 0.2) (layers "F.Cu" "B.Cu") (net 167))
  (via (at 155.05 116.05) (size 0.5) (drill 0.2) (layers "F.Cu" "B.Cu") (net 167))
  (via (at 219.16 122.84) (size 0.5) (drill 0.2) (layers "F.Cu" "B.Cu") (net 167))
  (via (at 110.648481 113.622157) (size 0.5) (drill 0.2) (layers "F.Cu" "B.Cu") (net 167))
  (segment (start 155.05 116.05) (end 147.9 116.05) (width 0.15) (layer "In7.Cu") (net 167))
  (segment (start 147.9 116.05) (end 145.95 114.1) (width 0.15) (layer "In7.Cu") (net 167))
  (segment (start 155.05 116.05) (end 156.8 114.3) (width 0.15) (layer "In9.Cu") (net 167))
  (segment (start 137.582444 113.1) (end 143.009845 113.1) (width 0.15) (layer "In9.Cu") (net 167))
  (segment (start 137.060287 113.622157) (end 137.582444 113.1) (width 0.15) (layer "In9.Cu") (net 167))
  (segment (start 218.55 110.85) (end 218.55 114.95) (width 0.15) (layer "In9.Cu") (net 167))
  (segment (start 156.8 114.3) (end 166.0369 114.3) (width 0.15) (layer "In9.Cu") (net 167))
  (segment (start 218.55 114.95) (end 219.16 115.56) (width 0.15) (layer "In9.Cu") (net 167))
  (segment (start 217.75 110.05) (end 218.55 110.85) (width 0.15) (layer "In9.Cu") (net 167))
  (segment (start 190.65 110.05) (end 217.75 110.05) (width 0.15) (layer "In9.Cu") (net 167))
  (segment (start 174.236899 106.1) (end 186.7 106.1) (width 0.15) (layer "In9.Cu") (net 167))
  (segment (start 144.209845 114.3) (end 145.75 114.3) (width 0.15) (layer "In9.Cu") (net 167))
  (segment (start 110.648481 113.622157) (end 137.060287 113.622157) (width 0.15) (layer "In9.Cu") (net 167))
  (segment (start 186.7 106.1) (end 190.65 110.05) (width 0.15) (layer "In9.Cu") (net 167))
  (segment (start 143.009845 113.1) (end 144.209845 114.3) (width 0.15) (layer "In9.Cu") (net 167))
  (segment (start 166.0369 114.3) (end 174.236899 106.1) (width 0.15) (layer "In9.Cu") (net 167))
  (segment (start 145.75 114.3) (end 145.95 114.1) (width 0.15) (layer "In9.Cu") (net 167))
  (segment (start 219.16 115.56) (end 219.16 122.84) (width 0.15) (layer "In9.Cu") (net 167))
  (segment (start 159.537499 103.233) (end 159.375 103.395499) (width 0.1) (layer "F.Cu") (net 168))
  (segment (start 159.694751 103.860249) (end 159.575 103.98) (width 0.1) (layer "F.Cu") (net 168))
  (segment (start 159.694751 103.715249) (end 159.694751 103.860249) (width 0.1) (layer "F.Cu") (net 168))
  (segment (start 159.537499 102.124633) (end 159.537499 103.233) (width 0.1) (layer "F.Cu") (net 168))
  (segment (start 158.686328 99.474306) (end 158.786327 99.574305) (width 0.1) (layer "F.Cu") (net 168))
  (segment (start 158.786327 101.373461) (end 159.537499 102.124633) (width 0.1) (layer "F.Cu") (net 168))
  (segment (start 159.375 103.395499) (end 159.694751 103.715249) (width 0.1) (layer "F.Cu") (net 168))
  (segment (start 158.786327 99.574305) (end 158.786327 101.373461) (width 0.1) (layer "F.Cu") (net 168))
  (via (at 159.375 103.395499) (size 0.5) (drill 0.2) (layers "F.Cu" "B.Cu") (net 168))
  (segment (start 159.414499 104.195501) (end 159.414499 103.910501) (width 0.1) (layer "B.Cu") (net 168))
  (segment (start 159.514499 103.810501) (end 159.514499 103.5955) (width 0.1) (layer "B.Cu") (net 168))
  (segment (start 159.514499 103.5955) (end 159.314498 103.395499) (width 0.1) (layer "B.Cu") (net 168))
  (segment (start 159.414499 103.910501) (end 159.514499 103.810501) (width 0.1) (layer "B.Cu") (net 168))
  (segment (start 157.3145 103.671234) (end 157.3145 103.395499) (width 0.1) (layer "F.Cu") (net 169))
  (segment (start 157.06 103.97) (end 157.06 103.925734) (width 0.1) (layer "F.Cu") (net 169))
  (segment (start 157.06 103.925734) (end 157.3145 103.671234) (width 0.1) (layer "F.Cu") (net 169))
  (segment (start 157.3145 103.395499) (end 157.514499 103.1955) (width 0.1) (layer "F.Cu") (net 169))
  (segment (start 157.786327 100.431539) (end 157.514499 100.703367) (width 0.1) (layer "F.Cu") (net 169))
  (segment (start 157.514499 103.1955) (end 157.514499 100.703367) (width 0.1) (layer "F.Cu") (net 169))
  (segment (start 157.686328 99.474306) (end 157.786327 99.574305) (width 0.1) (layer "F.Cu") (net 169))
  (segment (start 157.786327 99.574305) (end 157.786327 100.431539) (width 0.1) (layer "F.Cu") (net 169))
  (via (at 157.3145 103.395499) (size 0.5) (drill 0.2) (layers "F.Cu" "B.Cu") (net 169))
  (segment (start 157.514501 103.810501) (end 157.514501 103.5955) (width 0.1) (layer "B.Cu") (net 169))
  (segment (start 157.414501 103.910501) (end 157.514501 103.810501) (width 0.1) (layer "B.Cu") (net 169))
  (segment (start 157.514501 103.5955) (end 157.3145 103.395499) (width 0.1) (layer "B.Cu") (net 169))
  (segment (start 157.414501 104.195501) (end 157.414501 103.910501) (width 0.1) (layer "B.Cu") (net 169))
  (segment (start 155.014499 102.598367) (end 155.014499 103.1955) (width 0.1) (layer "F.Cu") (net 170))
  (segment (start 154.54 103.945734) (end 154.8145 103.671234) (width 0.1) (layer "F.Cu") (net 170))
  (segment (start 154.54 103.97) (end 154.54 103.945734) (width 0.1) (layer "F.Cu") (net 170))
  (segment (start 154.8145 103.671234) (end 154.8145 103.395499) (width 0.1) (layer "F.Cu") (net 170))
  (segment (start 156.186328 99.474306) (end 156.286327 99.574305) (width 0.1) (layer "F.Cu") (net 170))
  (segment (start 155.014499 103.1955) (end 154.8145 103.395499) (width 0.1) (layer "F.Cu") (net 170))
  (segment (start 156.286327 99.574305) (end 156.286327 101.326539) (width 0.1) (layer "F.Cu") (net 170))
  (segment (start 156.286327 101.326539) (end 155.014499 102.598367) (width 0.1) (layer "F.Cu") (net 170))
  (via (at 154.8145 103.395499) (size 0.5) (drill 0.2) (layers "F.Cu" "B.Cu") (net 170))
  (segment (start 154.914501 104.195501) (end 154.914501 103.910501) (width 0.1) (layer "B.Cu") (net 170))
  (segment (start 154.914501 103.910501) (end 155.014501 103.810501) (width 0.1) (layer "B.Cu") (net 170))
  (segment (start 155.014501 103.810501) (end 155.014501 103.5955) (width 0.1) (layer "B.Cu") (net 170))
  (segment (start 155.014501 103.5955) (end 154.8145 103.395499) (width 0.1) (layer "B.Cu") (net 170))
  (segment (start 160.286327 101.248461) (end 161.0145 101.976634) (width 0.1) (layer "F.Cu") (net 171))
  (segment (start 160.85 103.395499) (end 160.885499 103.395499) (width 0.1) (layer "F.Cu") (net 171))
  (segment (start 160.286327 99.574305) (end 160.286327 101.248461) (width 0.1) (layer "F.Cu") (net 171))
  (segment (start 160.186328 99.474306) (end 160.286327 99.574305) (width 0.1) (layer "F.Cu") (net 171))
  (segment (start 161.0145 103.1955) (end 160.814501 103.395499) (width 0.1) (layer "F.Cu") (net 171))
  (segment (start 161.0145 101.976634) (end 161.0145 103.1955) (width 0.1) (layer "F.Cu") (net 171))
  (segment (start 160.885499 103.395499) (end 161.18 103.69) (width 0.1) (layer "F.Cu") (net 171))
  (segment (start 161.18 103.69) (end 161.18 103.865) (width 0.1) (layer "F.Cu") (net 171))
  (segment (start 161.18 103.865) (end 161.075 103.97) (width 0.1) (layer "F.Cu") (net 171))
  (via (at 160.85 103.395499) (size 0.5) (drill 0.2) (layers "F.Cu" "B.Cu") (net 171))
  (segment (start 161.014502 103.810501) (end 161.014502 103.5955) (width 0.1) (layer "B.Cu") (net 171))
  (segment (start 160.914502 104.195501) (end 160.914502 103.910501) (width 0.1) (layer "B.Cu") (net 171))
  (segment (start 161.014502 103.5955) (end 160.814501 103.395499) (width 0.1) (layer "B.Cu") (net 171))
  (segment (start 160.914502 103.910501) (end 161.014502 103.810501) (width 0.1) (layer "B.Cu") (net 171))
  (segment (start 157.71 103.7) (end 157.71 103.87) (width 0.1) (layer "F.Cu") (net 172))
  (segment (start 158.086329 99.574305) (end 158.086329 100.555805) (width 0.1) (layer "F.Cu") (net 172))
  (segment (start 158.0145 103.395499) (end 157.814501 103.1955) (width 0.1) (layer "F.Cu") (net 172))
  (segment (start 157.71 103.87) (end 157.81 103.97) (width 0.1) (layer "F.Cu") (net 172))
  (segment (start 158.186328 99.474306) (end 158.086329 99.574305) (width 0.1) (layer "F.Cu") (net 172))
  (segment (start 157.814501 103.1955) (end 157.814501 100.827633) (width 0.1) (layer "F.Cu") (net 172))
  (segment (start 158.0145 103.395499) (end 157.71 103.7) (width 0.1) (layer "F.Cu") (net 172))
  (segment (start 158.086329 100.555805) (end 157.814501 100.827633) (width 0.1) (layer "F.Cu") (net 172))
  (via (at 158.0145 103.395499) (size 0.5) (drill 0.2) (layers "F.Cu" "B.Cu") (net 172))
  (segment (start 157.9145 104.195501) (end 157.9145 103.910501) (width 0.1) (layer "B.Cu") (net 172))
  (segment (start 157.814501 103.595498) (end 158.0145 103.395499) (width 0.1) (layer "B.Cu") (net 172))
  (segment (start 157.9145 103.910501) (end 157.8145 103.810501) (width 0.1) (layer "B.Cu") (net 172))
  (segment (start 157.8145 103.810501) (end 157.814501 103.595498) (width 0.1) (layer "B.Cu") (net 172))
  (segment (start 156.586329 101.450805) (end 155.314501 102.722633) (width 0.1) (layer "F.Cu") (net 173))
  (segment (start 155.29 103.619999) (end 155.29 103.97) (width 0.1) (layer "F.Cu") (net 173))
  (segment (start 156.686328 99.474306) (end 156.586329 99.574305) (width 0.1) (layer "F.Cu") (net 173))
  (segment (start 156.586329 99.574305) (end 156.586329 101.450805) (width 0.1) (layer "F.Cu") (net 173))
  (segment (start 155.314501 103.1955) (end 155.5145 103.395499) (width 0.1) (layer "F.Cu") (net 173))
  (segment (start 155.314501 102.722633) (end 155.314501 103.1955) (width 0.1) (layer "F.Cu") (net 173))
  (segment (start 155.5145 103.395499) (end 155.29 103.619999) (width 0.1) (layer "F.Cu") (net 173))
  (via (at 155.5145 103.395499) (size 0.5) (drill 0.2) (layers "F.Cu" "B.Cu") (net 173))
  (segment (start 155.4145 103.910501) (end 155.3145 103.810501) (width 0.1) (layer "B.Cu") (net 173))
  (segment (start 155.3145 103.810501) (end 155.314501 103.595498) (width 0.1) (layer "B.Cu") (net 173))
  (segment (start 155.314501 103.595498) (end 155.5145 103.395499) (width 0.1) (layer "B.Cu") (net 173))
  (segment (start 155.4145 104.195501) (end 155.4145 103.910501) (width 0.1) (layer "B.Cu") (net 173))
  (segment (start 159.837501 103.233) (end 160 103.395499) (width 0.1) (layer "F.Cu") (net 174))
  (segment (start 160.325 103.921234) (end 160 103.596234) (width 0.1) (layer "F.Cu") (net 174))
  (segment (start 159.086329 99.574305) (end 159.086329 101.249195) (width 0.1) (layer "F.Cu") (net 174))
  (segment (start 159.186328 99.474306) (end 159.086329 99.574305) (width 0.1) (layer "F.Cu") (net 174))
  (segment (start 159.837501 102.000367) (end 159.837501 103.233) (width 0.1) (layer "F.Cu") (net 174))
  (segment (start 160.325 103.98) (end 160.325 103.921234) (width 0.1) (layer "F.Cu") (net 174))
  (segment (start 159.086329 101.249195) (end 159.837501 102.000367) (width 0.1) (layer "F.Cu") (net 174))
  (segment (start 160 103.596234) (end 160 103.395499) (width 0.1) (layer "F.Cu") (net 174))
  (via (at 160 103.395499) (size 0.5) (drill 0.2) (layers "F.Cu" "B.Cu") (net 174))
  (segment (start 159.914498 103.910501) (end 159.814498 103.810501) (width 0.1) (layer "B.Cu") (net 174))
  (segment (start 159.814499 103.595498) (end 160.014498 103.395499) (width 0.1) (layer "B.Cu") (net 174))
  (segment (start 159.914498 104.195501) (end 159.914498 103.910501) (width 0.1) (layer "B.Cu") (net 174))
  (segment (start 159.814498 103.810501) (end 159.814499 103.595498) (width 0.1) (layer "B.Cu") (net 174))
  (segment (start 161.314502 103.1955) (end 161.514501 103.395499) (width 0.1) (layer "F.Cu") (net 175))
  (segment (start 161.314502 101.852368) (end 161.314502 103.1955) (width 0.1) (layer "F.Cu") (net 175))
  (segment (start 160.686328 99.474306) (end 160.586329 99.574305) (width 0.1) (layer "F.Cu") (net 175))
  (segment (start 160.586329 99.574305) (end 160.586329 101.124195) (width 0.1) (layer "F.Cu") (net 175))
  (segment (start 161.5 103.395499) (end 161.5 103.645) (width 0.1) (layer "F.Cu") (net 175))
  (segment (start 161.5 103.645) (end 161.825 103.97) (width 0.1) (layer "F.Cu") (net 175))
  (segment (start 160.586329 101.124195) (end 161.314502 101.852368) (width 0.1) (layer "F.Cu") (net 175))
  (via (at 161.5 103.395499) (size 0.5) (drill 0.2) (layers "F.Cu" "B.Cu") (net 175))
  (segment (start 161.314501 103.810501) (end 161.314502 103.595498) (width 0.1) (layer "B.Cu") (net 175))
  (segment (start 161.414501 103.910501) (end 161.314501 103.810501) (width 0.1) (layer "B.Cu") (net 175))
  (segment (start 161.414501 104.195501) (end 161.414501 103.910501) (width 0.1) (layer "B.Cu") (net 175))
  (segment (start 161.314502 103.595498) (end 161.514501 103.395499) (width 0.1) (layer "B.Cu") (net 175))
  (segment (start 148.299328 119.327008) (end 149.699328 119.327008) (width 0.2) (layer "F.Cu") (net 176))
  (segment (start 149.699328 119.327008) (end 149.974328 119.602008) (width 0.2) (layer "F.Cu") (net 176))
  (segment (start 149.974328 119.602008) (end 149.974328 119.677008) (width 0.2) (layer "F.Cu") (net 176))
  (segment (start 154.536328 113.040008) (end 154.536328 113.230008) (width 0.2) (layer "F.Cu") (net 176))
  (segment (start 154.599328 112.977008) (end 154.536328 113.040008) (width 0.2) (layer "F.Cu") (net 176))
  (segment (start 151.223 121.7) (end 150.5 121.7) (width 0.12) (layer "F.Cu") (net 176))
  (segment (start 154.536328 113.230008) (end 154.149328 113.617008) (width 0.2) (layer "F.Cu") (net 176))
  (via (at 154.599328 112.977008) (size 0.5) (drill 0.2) (layers "F.Cu" "B.Cu") (net 176))
  (via (at 149.974328 119.677008) (size 0.5) (drill 0.2) (layers "F.Cu" "B.Cu") (net 176))
  (segment (start 154.599328 112.977008) (end 149.974328 117.602008) (width 0.2) (layer "In5.Cu") (net 176))
  (segment (start 149.974328 117.602008) (end 149.974328 119.677008) (width 0.2) (layer "In5.Cu") (net 176))
  (segment (start 157.186328 99.474306) (end 157.186328 100.374306) (width 0.15) (layer "F.Cu") (net 177))
  (segment (start 159.686328 99.474306) (end 159.686328 100.374306) (width 0.15) (layer "F.Cu") (net 177))
  (via (at 157.186328 100.374306) (size 0.5) (drill 0.2) (layers "F.Cu" "B.Cu") (net 177))
  (via (at 159.686328 100.374306) (size 0.5) (drill 0.2) (layers "F.Cu" "B.Cu") (net 177))
  (segment (start 157.435 98.65) (end 157.1 98.985) (width 0.2) (layer "B.Cu") (net 177))
  (segment (start 159.89 99.2) (end 160.265 99.575) (width 0.2) (layer "B.Cu") (net 177))
  (segment (start 158.95 100.065) (end 158.985 100.065) (width 0.2) (layer "B.Cu") (net 177))
  (segment (start 158.965 100.065) (end 159.274306 100.374306) (width 0.2) (layer "B.Cu") (net 177))
  (segment (start 159.275 99.775) (end 160.065 99.775) (width 0.2) (layer "B.Cu") (net 177))
  (segment (start 160.065 99.775) (end 160.265 99.575) (width 0.2) (layer "B.Cu") (net 177))
  (segment (start 157.1 98.985) (end 157.5 99.385) (width 0.2) (layer "B.Cu") (net 177))
  (segment (start 158.2 98.425) (end 158.975 99.2) (width 0.2) (layer "B.Cu") (net 177))
  (segment (start 158.985 100.065) (end 159.275 99.775) (width 0.2) (layer "B.Cu") (net 177))
  (segment (start 158.2 98.275) (end 157.825 98.65) (width 0.2) (layer "B.Cu") (net 177))
  (segment (start 158.975 99.2) (end 159.89 99.2) (width 0.2) (layer "B.Cu") (net 177))
  (segment (start 159.274306 100.374306) (end 159.686328 100.374306) (width 0.2) (layer "B.Cu") (net 177))
  (segment (start 158.2 98.275) (end 158.2 98.425) (width 0.2) (layer "B.Cu") (net 177))
  (segment (start 157.825 98.65) (end 157.435 98.65) (width 0.2) (layer "B.Cu") (net 177))
  (segment (start 157.5 99.385) (end 157.5 99.64) (width 0.2) (layer "B.Cu") (net 177))
  (segment (start 157.5 99.64) (end 157.925 100.065) (width 0.2) (layer "B.Cu") (net 177))
  (segment (start 157.615694 100.374306) (end 157.925 100.065) (width 0.2) (layer "B.Cu") (net 177))
  (segment (start 157.186328 100.374306) (end 157.615694 100.374306) (width 0.2) (layer "B.Cu") (net 177))
  (segment (start 158.95 100.065) (end 158.965 100.065) (width 0.2) (layer "B.Cu") (net 177))
  (segment (start 153.463477 96.797157) (end 151.586328 94.920008) (width 0.2) (layer "F.Cu") (net 178))
  (segment (start 155.009179 96.797157) (end 153.463477 96.797157) (width 0.2) (layer "F.Cu") (net 178))
  (segment (start 150.486328 94.859306) (end 151.586328 94.859306) (width 0.2) (layer "F.Cu") (net 178))
  (segment (start 149.386328 94.859306) (end 150.486328 94.859306) (width 0.2) (layer "F.Cu") (net 178))
  (segment (start 148.186328 94.610008) (end 148.435626 94.859306) (width 0.2) (layer "F.Cu") (net 178))
  (segment (start 148.435626 94.859306) (end 149.386328 94.859306) (width 0.2) (layer "F.Cu") (net 178))
  (segment (start 155.686328 99.474306) (end 155.686328 100.374306) (width 0.15) (layer "F.Cu") (net 179))
  (segment (start 161.186328 99.474306) (end 161.186328 100.374306) (width 0.15) (layer "F.Cu") (net 179))
  (via (at 155.686328 100.374306) (size 0.5) (drill 0.2) (layers "F.Cu" "B.Cu") (net 179))
  (via (at 161.186328 100.374306) (size 0.5) (drill 0.2) (layers "F.Cu" "B.Cu") (net 179))
  (segment (start 154.585 100.025) (end 155.337022 100.025) (width 0.2) (layer "B.Cu") (net 179))
  (segment (start 155.337022 100.025) (end 155.686328 100.374306) (width 0.2) (layer "B.Cu") (net 179))
  (segment (start 155.207022 101.995) (end 158.529681 101.995) (width 0.2) (layer "B.Cu") (net 179))
  (segment (start 154.486328 101.274306) (end 155.207022 101.995) (width 0.2) (layer "B.Cu") (net 179))
  (segment (start 162.9 100.715) (end 161.9 100.715) (width 0.2) (layer "B.Cu") (net 179))
  (segment (start 160.6945 101.9205) (end 161.9 100.715) (width 0.2) (layer "B.Cu") (net 179))
  (segment (start 158.714681 101.81) (end 159.51 101.81) (width 0.2) (layer "B.Cu") (net 179))
  (segment (start 158.529681 101.995) (end 158.714681 101.81) (width 0.2) (layer "B.Cu") (net 179))
  (segment (start 161.186328 100.374306) (end 161.559306 100.374306) (width 0.2) (layer "B.Cu") (net 179))
  (segment (start 159.6205 101.9205) (end 160.6945 101.9205) (width 0.2) (layer "B.Cu") (net 179))
  (segment (start 159.51 101.81) (end 159.6205 101.9205) (width 0.2) (layer "B.Cu") (net 179))
  (segment (start 154.486328 100.123672) (end 154.585 100.025) (width 0.2) (layer "B.Cu") (net 179))
  (segment (start 161.559306 100.374306) (end 161.9 100.715) (width 0.2) (layer "B.Cu") (net 179))
  (segment (start 154.486328 101.274306) (end 154.486328 100.123672) (width 0.2) (layer "B.Cu") (net 179))
  (segment (start 252.55 126.89) (end 252.55 125.875) (width 0.127) (layer "F.Cu") (net 181))
  (segment (start 252.55 125.875) (end 252.9 125.525) (width 0.127) (layer "F.Cu") (net 181))
  (via (at 252.9 125.525) (size 0.5) (drill 0.2) (layers "F.Cu" "B.Cu") (net 181))
  (segment (start 252.9 125.525) (end 252.9 124.77) (width 0.127) (layer "B.Cu") (net 181))
  (segment (start 252.9 124.77) (end 252.905 124.765) (width 0.127) (layer "B.Cu") (net 181))
  (segment (start 155.009179 93.797157) (end 154.009179 93.797157) (width 0.1) (layer "F.Cu") (net 183))
  (segment (start 177.136328 83.560008) (end 176.636328 83.060008) (width 0.127) (layer "F.Cu") (net 183))
  (via blind (at 176.636328 83.060008) (size 0.5) (drill 0.2) (layers "F.Cu" "In2.Cu") (net 183))
  (via (at 153.921318 93.774306) (size 0.5) (drill 0.2) (layers "F.Cu" "B.Cu") (net 183))
  (segment (start 164.7 80.8) (end 161.636328 83.863672) (width 0.1) (layer "In2.Cu") (net 183))
  (segment (start 176.636328 83.060008) (end 176.260008 83.060008) (width 0.1) (layer "In2.Cu") (net 183))
  (segment (start 174.67029 81.5) (end 174.2 81.5) (width 0.1) (layer "In2.Cu") (net 183))
  (segment (start 175.12 82.194) (end 175.12 81.94971) (width 0.1) (layer "In2.Cu") (net 183))
  (segment (start 176.260008 83.060008) (end 175.840008 82.640008) (width 0.1) (layer "In2.Cu") (net 183))
  (segment (start 175.840008 82.640008) (end 175.566008 82.640008) (width 0.1) (layer "In2.Cu") (net 183))
  (segment (start 155.091618 92.604006) (end 153.921318 93.774306) (width 0.1) (layer "In2.Cu") (net 183))
  (segment (start 175.12 81.94971) (end 174.67029 81.5) (width 0.1) (layer "In2.Cu") (net 183))
  (segment (start 174.2 81.5) (end 173.8 81.1) (width 0.1) (layer "In2.Cu") (net 183))
  (segment (start 161.636328 83.863672) (end 161.636328 90.331738) (width 0.1) (layer "In2.Cu") (net 183))
  (segment (start 171.7 81.1) (end 171.4 80.8) (width 0.1) (layer "In2.Cu") (net 183))
  (segment (start 159.36406 92.604006) (end 155.091618 92.604006) (width 0.1) (layer "In2.Cu") (net 183))
  (segment (start 175.566008 82.640008) (end 175.12 82.194) (width 0.1) (layer "In2.Cu") (net 183))
  (segment (start 171.4 80.8) (end 164.7 80.8) (width 0.1) (layer "In2.Cu") (net 183))
  (segment (start 161.636328 90.331738) (end 159.36406 92.604006) (width 0.1) (layer "In2.Cu") (net 183))
  (segment (start 173.8 81.1) (end 171.7 81.1) (width 0.1) (layer "In2.Cu") (net 183))
  (segment (start 119.986328 59.660008) (end 119.986328 61.060008) (width 0.4) (layer "F.Cu") (net 184))
  (segment (start 121.686328 59.660008) (end 121.686328 61.060008) (width 0.4) (layer "F.Cu") (net 184))
  (segment (start 120.836328 59.660008) (end 120.836328 61.060008) (width 0.4) (layer "F.Cu") (net 184))
  (segment (start 120.836328 55.060008) (end 120.836328 56.460008) (width 0.4) (layer "F.Cu") (net 184))
  (segment (start 121.686328 55.060008) (end 121.686328 56.460008) (width 0.4) (layer "F.Cu") (net 184))
  (via (at 119.876328 58.450008) (size 0.5) (drill 0.2) (layers "F.Cu" "B.Cu") (net 184))
  (via (at 123.106328 84.332859) (size 0.5) (drill 0.2) (layers "F.Cu" "B.Cu") (net 184))
  (via (at 124.106328 84.332859) (size 0.5) (drill 0.2) (layers "F.Cu" "B.Cu") (net 184))
  (via (at 124.106328 82.332859) (size 0.5) (drill 0.2) (layers "F.Cu" "B.Cu") (net 184))
  (via (at 123.106328 82.332859) (size 0.5) (drill 0.2) (layers "F.Cu" "B.Cu") (net 184))
  (via (at 122.606328 83.332859) (size 0.5) (drill 0.2) (layers "F.Cu" "B.Cu") (net 184))
  (via (at 123.606328 83.332859) (size 0.5) (drill 0.2) (layers "F.Cu" "B.Cu") (net 184))
  (via (at 122.606328 85.332859) (size 0.5) (drill 0.2) (layers "F.Cu" "B.Cu") (net 184))
  (via (at 123.606328 85.332859) (size 0.5) (drill 0.2) (layers "F.Cu" "B.Cu") (net 184))
  (via (at 121.686328 56.460008) (size 0.5) (drill 0.2) (layers "F.Cu" "B.Cu") (net 184))
  (via (at 120.836328 56.460008) (size 0.5) (drill 0.2) (layers "F.Cu" "B.Cu") (net 184))
  (via (at 120.726328 58.450008) (size 0.5) (drill 0.2) (layers "F.Cu" "B.Cu") (net 184))
  (via (at 121.576328 58.450008) (size 0.5) (drill 0.2) (layers "F.Cu" "B.Cu") (net 184))
  (segment (start 123.236328 62.460008) (end 123.236328 63.518208) (width 0.4) (layer "F.Cu") (net 185))
  (segment (start 123.336328 62.360008) (end 123.336328 59.710008) (width 0.4) (layer "F.Cu") (net 185))
  (segment (start 117.821328 65.160008) (end 117.821328 64.160008) (width 0.4) (layer "F.Cu") (net 185))
  (segment (start 123.561328 66.185008) (end 122.971328 66.185008) (width 0.4) (layer "F.Cu") (net 185))
  (segment (start 123.917728 67.740008) (end 123.917728 66.541408) (width 0.2) (layer "F.Cu") (net 185))
  (segment (start 123.561328 63.843208) (end 123.561328 66.185008) (width 0.4) (layer "F.Cu") (net 185))
  (segment (start 117.821328 64.160008) (end 117.821328 63.160008) (width 0.4) (layer "F.Cu") (net 185))
  (segment (start 118.361328 66.185008) (end 117.821328 65.645008) (width 0.4) (layer "F.Cu") (net 185))
  (segment (start 123.917728 66.541408) (end 123.561328 66.185008) (width 0.2) (layer "F.Cu") (net 185))
  (segment (start 119.361328 66.185008) (end 120.076328 66.185008) (width 0.4) (layer "F.Cu") (net 185))
  (segment (start 117.821328 65.645008) (end 117.821328 65.160008) (width 0.4) (layer "F.Cu") (net 185))
  (segment (start 123.236328 63.518208) (end 123.561328 63.843208) (width 0.4) (layer "F.Cu") (net 185))
  (segment (start 119.361328 66.185008) (end 118.361328 66.185008) (width 0.4) (layer "F.Cu") (net 185))
  (segment (start 123.917728 67.740008) (end 122.505128 67.740008) (width 0.2) (layer "F.Cu") (net 185))
  (via (at 123.561328 66.185008) (size 0.5) (drill 0.2) (layers "F.Cu" "B.Cu") (net 185))
  (via (at 119.361328 66.185008) (size 0.5) (drill 0.2) (layers "F.Cu" "B.Cu") (net 185))
  (segment (start 123.561328 66.185008) (end 119.361328 66.185008) (width 0.4) (layer "B.Cu") (net 185))
  (via (at 182.05 56.4) (size 0.5) (drill 0.2) (layers "F.Cu" "B.Cu") (net 186))
  (via (at 181.5 56.7) (size 0.5) (drill 0.2) (layers "F.Cu" "B.Cu") (net 186))
  (via (at 182.05 58.3) (size 0.5) (drill 0.2) (layers "F.Cu" "B.Cu") (net 186))
  (via (at 182.05 57) (size 0.5) (drill 0.2) (layers "F.Cu" "B.Cu") (net 186))
  (via (at 182.05 57.65) (size 0.5) (drill 0.2) (layers "F.Cu" "B.Cu") (net 186))
  (via (at 181.5 57.95) (size 0.5) (drill 0.2) (layers "F.Cu" "B.Cu") (net 186))
  (via (at 181.5 57.3) (size 0.5) (drill 0.2) (layers "F.Cu" "B.Cu") (net 186))
  (segment (start 177.04 61.765) (end 177.04 62.57) (width 0.2) (layer "F.Cu") (net 187))
  (segment (start 176.086328 55.060008) (end 176.086328 56.480008) (width 0.2) (layer "F.Cu") (net 187))
  (segment (start 177.04 62.57) (end 178.04 62.57) (width 0.2) (layer "F.Cu") (net 187))
  (via (at 177.04 61.765) (size 0.5) (drill 0.2) (layers "F.Cu" "B.Cu") (net 187))
  (via (at 176.086328 56.480008) (size 0.5) (drill 0.2) (layers "F.Cu" "B.Cu") (net 187))
  (segment (start 176.086328 57.013672) (end 175.6 57.5) (width 0.16) (layer "In2.Cu") (net 187))
  (segment (start 172.9 58.9) (end 172.9 59.1) (width 0.16) (layer "In2.Cu") (net 187))
  (segment (start 175.6 57.5) (end 174.3 57.5) (width 0.16) (layer "In2.Cu") (net 187))
  (segment (start 174.3 57.5) (end 172.9 58.9) (width 0.16) (layer "In2.Cu") (net 187))
  (segment (start 173.175 59.375) (end 173.370814 59.375) (width 0.16) (layer "In2.Cu") (net 187))
  (segment (start 172.429186 59.925) (end 173.370814 59.925) (width 0.16) (layer "In2.Cu") (net 187))
  (segment (start 173.4 61.8) (end 177.005 61.8) (width 0.16) (layer "In2.Cu") (net 187))
  (segment (start 172.9 60.75) (end 172.9 60.826232) (width 0.16) (layer "In2.Cu") (net 187))
  (segment (start 176.086328 56.480008) (end 176.086328 57.013672) (width 0.16) (layer "In2.Cu") (net 187))
  (segment (start 172.9 61.3) (end 173.4 61.8) (width 0.16) (layer "In2.Cu") (net 187))
  (segment (start 177.005 61.8) (end 177.04 61.765) (width 0.16) (layer "In2.Cu") (net 187))
  (segment (start 172.9 60.826232) (end 172.9 61.3) (width 0.16) (layer "In2.Cu") (net 187))
  (segment (start 172.429186 60.475) (end 172.625 60.475) (width 0.16) (layer "In2.Cu") (net 187))
  (arc (start 173.645814 59.65) (mid 173.565268 59.844454) (end 173.370814 59.925) (width 0.16) (layer "In2.Cu") (net 187))
  (arc (start 172.625 60.475) (mid 172.819454 60.555546) (end 172.9 60.75) (width 0.16) (layer "In2.Cu") (net 187))
  (arc (start 172.429186 59.925) (mid 172.234732 60.005546) (end 172.154186 60.2) (width 0.16) (layer "In2.Cu") (net 187))
  (arc (start 172.154186 60.2) (mid 172.234732 60.394454) (end 172.429186 60.475) (width 0.16) (layer "In2.Cu") (net 187))
  (arc (start 172.9 59.1) (mid 172.980546 59.294454) (end 173.175 59.375) (width 0.16) (layer "In2.Cu") (net 187))
  (arc (start 173.370814 59.375) (mid 173.565268 59.455546) (end 173.645814 59.65) (width 0.16) (layer "In2.Cu") (net 187))
  (segment (start 143.786328 59.660008) (end 143.786328 60.960008) (width 0.2) (layer "F.Cu") (net 188))
  (segment (start 182.136328 81.560008) (end 181.636328 81.060008) (width 0.127) (layer "F.Cu") (net 188))
  (via blind (at 143.786328 60.960008) (size 0.5) (drill 0.2) (layers "F.Cu" "In2.Cu") (net 188))
  (via blind (at 181.636328 81.060008) (size 0.5) (drill 0.2) (layers "F.Cu" "In2.Cu") (net 188))
  (segment (start 172.149 79.949) (end 172.149 80.349) (width 0.1) (layer "In2.Cu") (net 188))
  (segment (start 165.325 75.051661) (end 165.325 75.025) (width 0.16) (layer "In2.Cu") (net 188))
  (segment (start 180.083828 81.924558) (end 180.547886 81.4605) (width 0.1) (layer "In2.Cu") (net 188))
  (segment (start 172.149 80.349) (end 172.37 80.57) (width 0.1) (layer "In2.Cu") (net 188))
  (segment (start 170.9 75.5) (end 170.9 76.566) (width 0.1) (layer "In2.Cu") (net 188))
  (segment (start 166.225 75.025) (end 166.225 74.548339) (width 0.16) (layer "In2.Cu") (net 188))
  (segment (start 166.675 75.025) (end 166.675 75.051661) (width 0.16) (layer "In2.Cu") (net 188))
  (segment (start 171.764 79.564) (end 172.149 79.949) (width 0.1) (layer "In2.Cu") (net 188))
  (segment (start 171 79.1) (end 171.464 79.564) (width 0.1) (layer "In2.Cu") (net 188))
  (segment (start 170.9 76.566) (end 171 76.666) (width 0.1) (layer "In2.Cu") (net 188))
  (segment (start 171 76.666) (end 171 79.1) (width 0.1) (layer "In2.Cu") (net 188))
  (segment (start 171.464 79.564) (end 171.764 79.564) (width 0.1) (layer "In2.Cu") (net 188))
  (segment (start 150.46 74.8) (end 165.1 74.8) (width 0.16) (layer "In2.Cu") (net 188))
  (segment (start 181.235836 81.4605) (end 181.636328 81.060008) (width 0.1) (layer "In2.Cu") (net 188))
  (segment (start 165.775 74.548339) (end 165.775 75.051661) (width 0.16) (layer "In2.Cu") (net 188))
  (segment (start 179.800298 82.498) (end 180.083828 82.21447) (width 0.1) (layer "In2.Cu") (net 188))
  (segment (start 170.9 75.5) (end 170.9 75.3) (width 0.16) (layer "In2.Cu") (net 188))
  (segment (start 175.421 81.277) (end 175.572 81.277) (width 0.1) (layer "In2.Cu") (net 188))
  (segment (start 170.4 74.8) (end 166.9 74.8) (width 0.16) (layer "In2.Cu") (net 188))
  (segment (start 172.37 80.57) (end 174.714 80.57) (width 0.1) (layer "In2.Cu") (net 188))
  (segment (start 143.786328 68.126328) (end 143.786328 60.960008) (width 0.16) (layer "In2.Cu") (net 188))
  (segment (start 176.142 81.847) (end 176.142 82.209) (width 0.1) (layer "In2.Cu") (net 188))
  (segment (start 180.083828 82.21447) (end 180.083828 81.924558) (width 0.1) (layer "In2.Cu") (net 188))
  (segment (start 174.714 80.57) (end 175.421 81.277) (width 0.1) (layer "In2.Cu") (net 188))
  (segment (start 176.142 82.209) (end 176.431 82.498) (width 0.1) (layer "In2.Cu") (net 188))
  (segment (start 180.547886 81.4605) (end 181.235836 81.4605) (width 0.1) (layer "In2.Cu") (net 188))
  (segment (start 166.225 75.051661) (end 166.225 75.025) (width 0.16) (layer "In2.Cu") (net 188))
  (segment (start 170.9 75.3) (end 170.4 74.8) (width 0.16) (layer "In2.Cu") (net 188))
  (segment (start 176.431 82.498) (end 179.800298 82.498) (width 0.1) (layer "In2.Cu") (net 188))
  (segment (start 175.572 81.277) (end 176.142 81.847) (width 0.1) (layer "In2.Cu") (net 188))
  (segment (start 150.46 74.8) (end 143.786328 68.126328) (width 0.16) (layer "In2.Cu") (net 188))
  (arc (start 165.325 75.025) (mid 165.259099 74.865901) (end 165.1 74.8) (width 0.16) (layer "In2.Cu") (net 188))
  (arc (start 165.775 75.051661) (mid 165.709099 75.21076) (end 165.55 75.276661) (width 0.16) (layer "In2.Cu") (net 188))
  (arc (start 166.45 75.276661) (mid 166.290901 75.21076) (end 166.225 75.051661) (width 0.16) (layer "In2.Cu") (net 188))
  (arc (start 166.675 75.051661) (mid 166.609099 75.21076) (end 166.45 75.276661) (width 0.16) (layer "In2.Cu") (net 188))
  (arc (start 166.9 74.8) (mid 166.740901 74.865901) (end 166.675 75.025) (width 0.16) (layer "In2.Cu") (net 188))
  (arc (start 166 74.323339) (mid 165.840901 74.38924) (end 165.775 74.548339) (width 0.16) (layer "In2.Cu") (net 188))
  (arc (start 165.55 75.276661) (mid 165.390901 75.21076) (end 165.325 75.051661) (width 0.16) (layer "In2.Cu") (net 188))
  (arc (start 166.225 74.548339) (mid 166.159099 74.38924) (end 166 74.323339) (width 0.16) (layer "In2.Cu") (net 188))
  (segment (start 177.624247 79.047927) (end 177.624247 78.996) (width 0.127) (layer "F.Cu") (net 189))
  (segment (start 178.136328 79.560008) (end 177.624247 79.047927) (width 0.127) (layer "F.Cu") (net 189))
  (segment (start 149.736328 59.660008) (end 149.736328 60.960008) (width 0.2) (layer "F.Cu") (net 189))
  (via blind (at 177.624247 78.996) (size 0.5) (drill 0.2) (layers "F.Cu" "In2.Cu") (net 189))
  (via blind (at 149.736328 60.960008) (size 0.5) (drill 0.2) (layers "F.Cu" "In2.Cu") (net 189))
  (segment (start 174.76415 69.368598) (end 174.76415 69.368599) (width 0.16) (layer "In2.Cu") (net 189))
  (segment (start 176.84909 74.225) (end 176.875 74.225) (width 0.16) (layer "In2.Cu") (net 189))
  (segment (start 171.525 68.17909) (end 171.525 68.78091) (width 0.16) (layer "In2.Cu") (net 189))
  (segment (start 173.949689 69.794148) (end 173.949689 69.794149) (width 0.16) (layer "In2.Cu") (net 189))
  (segment (start 172.075 68.78091) (end 172.075 68.17909) (width 0.16) (layer "In2.Cu") (net 189))
  (segment (start 175.505328 70.960879) (end 175.930879 70.535328) (width 0.16) (layer "In2.Cu") (net 189))
  (segment (start 174.727508 70.18306) (end 174.727508 70.183059) (width 0.16) (layer "In2.Cu") (net 189))
  (segment (start 177.15 78.521753) (end 177.15 75.57) (width 0.1) (layer "In2.Cu") (net 189))
  (segment (start 173.949688 69.405239) (end 173.96801 69.386918) (width 0.16) (layer "In2.Cu") (net 189))
  (segment (start 176.875 74.775) (end 176.84909 74.775) (width 0.16) (layer "In2.Cu") (net 189))
  (segment (start 173.175 68.205) (end 173.175 68.17909) (width 0.16) (layer "In2.Cu") (net 189))
  (segment (start 176.31979 70.924238) (end 176.31979 70.924239) (width 0.16) (layer "In2.Cu") (net 189))
  (segment (start 173.968009 68.998009) (end 173.96801 68.99801) (width 0.16) (layer "In2.Cu") (net 189))
  (segment (start 174.727509 70.571968) (end 174.727509 70.571969) (width 0.16) (layer "In2.Cu") (net 189))
  (segment (start 172.625 68.17909) (end 172.625 68.205) (width 0.16) (layer "In2.Cu") (net 189))
  (segment (start 177.15 72.18) (end 177.07929 72.10929) (width 0.16) (layer "In2.Cu") (net 189))
  (segment (start 176.690381 72.109289) (end 176.69038 72.109289) (width 0.16) (layer "In2.Cu") (net 189))
  (segment (start 175.505328 70.96088) (end 175.505328 70.960879) (width 0.16) (layer "In2.Cu") (net 189))
  (segment (start 177.15 72.85) (end 177.15 72.18) (width 0.16) (layer "In2.Cu") (net 189))
  (segment (start 176.84909 73.125) (end 176.875 73.125) (width 0.16) (layer "In2.Cu") (net 189))
  (segment (start 173.96801 68.99801) (end 173.45 68.48) (width 0.16) (layer "In2.Cu") (net 189))
  (segment (start 155.055 68.48) (end 170.7 68.48) (width 0.16) (layer "In2.Cu") (net 189))
  (segment (start 173.949688 69.40524) (end 173.949688 69.405239) (width 0.16) (layer "In2.Cu") (net 189))
  (segment (start 177.624247 78.996) (end 177.15 78.521753) (width 0.1) (layer "In2.Cu") (net 189))
  (segment (start 176.495926 71.525926) (end 176.495924 71.525924) (width 0.16) (layer "In2.Cu") (net 189))
  (segment (start 176.28315 71.738702) (end 176.28315 71.738701) (width 0.16) (layer "In2.Cu") (net 189))
  (segment (start 176.495924 71.525924) (end 176.708699 71.313148) (width 0.16) (layer "In2.Cu") (net 189))
  (segment (start 175.930879 70.14642) (end 175.930879 70.146419) (width 0.16) (layer "In2.Cu") (net 189))
  (segment (start 155.055 68.48) (end 149.736328 63.161328) (width 0.16) (layer "In2.Cu") (net 189))
  (segment (start 175.54197 70.146418) (end 175.54197 70.146419) (width 0.16) (layer "In2.Cu") (net 189))
  (segment (start 170.975 68.78091) (end 170.975 68.755) (width 0.16) (layer "In2.Cu") (net 189))
  (segment (start 176.28315 72.12761) (end 176.283151 72.127611) (width 0.16) (layer "In2.Cu") (net 189))
  (segment (start 177.15 75.57) (end 177.15 75.05) (width 0.16) (layer "In2.Cu") (net 189))
  (segment (start 176.31979 70.924239) (end 175.894237 71.349788) (width 0.16) (layer "In2.Cu") (net 189))
  (segment (start 172.625 68.205) (end 172.625 68.78091) (width 0.16) (layer "In2.Cu") (net 189))
  (segment (start 149.736328 63.161328) (end 149.736328 60.960008) (width 0.16) (layer "In2.Cu") (net 189))
  (segment (start 174.727508 70.183059) (end 175.153059 69.757508) (width 0.16) (layer "In2.Cu") (net 189))
  (segment (start 176.28315 71.738701) (end 176.495926 71.525926) (width 0.16) (layer "In2.Cu") (net 189))
  (segment (start 175.153059 69.3686) (end 175.153059 69.368599) (width 0.16) (layer "In2.Cu") (net 189))
  (segment (start 174.76415 69.368599) (end 174.338597 69.794148) (width 0.16) (layer "In2.Cu") (net 189))
  (segment (start 176.84909 73.675) (end 177.45091 73.675) (width 0.16) (layer "In2.Cu") (net 189))
  (segment (start 175.54197 70.146419) (end 175.116417 70.571968) (width 0.16) (layer "In2.Cu") (net 189))
  (segment (start 175.505329 71.349788) (end 175.505329 71.349789) (width 0.16) (layer "In2.Cu") (net 189))
  (segment (start 176.69038 72.109289) (end 176.672059 72.127611) (width 0.16) (layer "In2.Cu") (net 189))
  (segment (start 176.708699 70.92424) (end 176.708699 70.924239) (width 0.16) (layer "In2.Cu") (net 189))
  (segment (start 176.875 74.225) (end 177.45091 74.225) (width 0.16) (layer "In2.Cu") (net 189))
  (arc (start 176.672059 72.127611) (mid 176.477604 72.208156) (end 176.28315 72.12761) (width 0.16) (layer "In2.Cu") (net 189))
  (arc (start 172.075 68.17909) (mid 171.994454 67.984636) (end 171.8 67.90409) (width 0.16) (layer "In2.Cu") (net 189))
  (arc (start 176.57409 73.4) (mid 176.654636 73.205546) (end 176.84909 73.125) (width 0.16) (layer "In2.Cu") (net 189))
  (arc (start 174.727509 70.571969) (mid 174.646963 70.377515) (end 174.727508 70.18306) (width 0.16) (layer "In2.Cu") (net 189))
  (arc (start 175.505329 71.349789) (mid 175.424783 71.155335) (end 175.505328 70.96088) (width 0.16) (layer "In2.Cu") (net 189))
  (arc (start 172.35 69.05591) (mid 172.155546 68.975364) (end 172.075 68.78091) (width 0.16) (layer "In2.Cu") (net 189))
  (arc (start 176.283151 72.127611) (mid 176.202605 71.933157) (end 176.28315 71.738702) (width 0.16) (layer "In2.Cu") (net 189))
  (arc (start 172.625 68.78091) (mid 172.544454 68.975364) (end 172.35 69.05591) (width 0.16) (layer "In2.Cu") (net 189))
  (arc (start 175.153059 69.757508) (mid 175.233604 69.563054) (end 175.153059 69.3686) (width 0.16) (layer "In2.Cu") (net 189))
  (arc (start 177.15 75.05) (mid 177.069454 74.855546) (end 176.875 74.775) (width 0.16) (layer "In2.Cu") (net 189))
  (arc (start 171.8 67.90409) (mid 171.605546 67.984636) (end 171.525 68.17909) (width 0.16) (layer "In2.Cu") (net 189))
  (arc (start 175.930879 70.146419) (mid 175.736425 70.065873) (end 175.54197 70.146418) (width 0.16) (layer "In2.Cu") (net 189))
  (arc (start 170.975 68.755) (mid 170.894454 68.560546) (end 170.7 68.48) (width 0.16) (layer "In2.Cu") (net 189))
  (arc (start 173.96801 69.386918) (mid 174.048555 69.192463) (end 173.968009 68.998009) (width 0.16) (layer "In2.Cu") (net 189))
  (arc (start 176.84909 74.775) (mid 176.654636 74.694454) (end 176.57409 74.5) (width 0.16) (layer "In2.Cu") (net 189))
  (arc (start 177.72591 73.95) (mid 177.645364 73.755546) (end 177.45091 73.675) (width 0.16) (layer "In2.Cu") (net 189))
  (arc (start 171.25 69.05591) (mid 171.055546 68.975364) (end 170.975 68.78091) (width 0.16) (layer "In2.Cu") (net 189))
  (arc (start 174.338597 69.794148) (mid 174.144144 69.874694) (end 173.949689 69.794148) (width 0.16) (layer "In2.Cu") (net 189))
  (arc (start 176.57409 74.5) (mid 176.654636 74.305546) (end 176.84909 74.225) (width 0.16) (layer "In2.Cu") (net 189))
  (arc (start 173.45 68.48) (mid 173.255546 68.399454) (end 173.175 68.205) (width 0.16) (layer "In2.Cu") (net 189))
  (arc (start 175.153059 69.368599) (mid 174.958605 69.288053) (end 174.76415 69.368598) (width 0.16) (layer "In2.Cu") (net 189))
  (arc (start 173.949689 69.794149) (mid 173.869143 69.599695) (end 173.949688 69.40524) (width 0.16) (layer "In2.Cu") (net 189))
  (arc (start 176.708699 70.924239) (mid 176.514245 70.843693) (end 176.31979 70.924238) (width 0.16) (layer "In2.Cu") (net 189))
  (arc (start 177.07929 72.10929) (mid 176.884836 72.028744) (end 176.690381 72.109289) (width 0.16) (layer "In2.Cu") (net 189))
  (arc (start 176.84909 73.675) (mid 176.654636 73.594454) (end 176.57409 73.4) (width 0.16) (layer "In2.Cu") (net 189))
  (arc (start 177.45091 74.225) (mid 177.645364 74.144454) (end 177.72591 73.95) (width 0.16) (layer "In2.Cu") (net 189))
  (arc (start 172.9 67.90409) (mid 172.705546 67.984636) (end 172.625 68.17909) (width 0.16) (layer "In2.Cu") (net 189))
  (arc (start 175.894237 71.349788) (mid 175.699784 71.430334) (end 175.505329 71.349788) (width 0.16) (layer "In2.Cu") (net 189))
  (arc (start 175.116417 70.571968) (mid 174.921964 70.652514) (end 174.727509 70.571968) (width 0.16) (layer "In2.Cu") (net 189))
  (arc (start 175.930879 70.535328) (mid 176.011424 70.340874) (end 175.930879 70.14642) (width 0.16) (layer "In2.Cu") (net 189))
  (arc (start 171.525 68.78091) (mid 171.444454 68.975364) (end 171.25 69.05591) (width 0.16) (layer "In2.Cu") (net 189))
  (arc (start 176.708699 71.313148) (mid 176.789244 71.118694) (end 176.708699 70.92424) (width 0.16) (layer "In2.Cu") (net 189))
  (arc (start 173.175 68.17909) (mid 173.094454 67.984636) (end 172.9 67.90409) (width 0.16) (layer "In2.Cu") (net 189))
  (arc (start 176.875 73.125) (mid 177.069454 73.044454) (end 177.15 72.85) (width 0.16) (layer "In2.Cu") (net 189))
  (segment (start 140.386328 59.660008) (end 140.386328 60.960008) (width 0.2) (layer "F.Cu") (net 190))
  (segment (start 179.789828 81.213508) (end 180.136328 81.560008) (width 0.127) (layer "F.Cu") (net 190))
  (segment (start 179.789828 81.079634) (end 179.789828 81.213508) (width 0.127) (layer "F.Cu") (net 190))
  (via blind (at 140.386328 60.960008) (size 0.5) (drill 0.2) (layers "F.Cu" "In5.Cu") (net 190))
  (via blind (at 179.789828 81.07) (size 0.5) (drill 0.2) (layers "F.Cu" "In5.Cu") (net 190))
  (segment (start 142.486654 64.063141) (end 142.863143 63.686657) (width 0.146) (layer "In5.Cu") (net 190))
  (segment (start 141.850253 63.42674) (end 142.226742 63.050256) (width 0.146) (layer "In5.Cu") (net 190))
  (segment (start 148.966511 70.413998) (end 149.214 70.166513) (width 0.146) (layer "In5.Cu") (net 190))
  (segment (start 142.863143 63.686657) (end 142.863143 63.686656) (width 0.146) (layer "In5.Cu") (net 190))
  (segment (start 142.226742 63.050256) (end 142.226742 63.050255) (width 0.146) (layer "In5.Cu") (net 190))
  (segment (start 148.259399 68.964424) (end 148.2594 68.964425) (width 0.146) (layer "In5.Cu") (net 190))
  (segment (start 143.441259 65.017745) (end 143.441257 65.017744) (width 0.146) (layer "In5.Cu") (net 190))
  (segment (start 149.921112 71.616087) (end 149.991823 71.686798) (width 0.146) (layer "In5.Cu") (net 190))
  (segment (start 148.011912 69.706887) (end 148.082623 69.777598) (width 0.146) (layer "In5.Cu") (net 190))
  (segment (start 148.188688 68.893713) (end 148.259399 68.964424) (width 0.146) (layer "In5.Cu") (net 190))
  (segment (start 148.825088 69.530113) (end 148.895799 69.600824) (width 0.146) (layer "In5.Cu") (net 190))
  (segment (start 143.499544 64.323058) (end 143.499544 64.323057) (width 0.146) (layer "In5.Cu") (net 190))
  (segment (start 150.363057 71.563056) (end 150.486801 71.439313) (width 0.146) (layer "In5.Cu") (net 190))
  (segment (start 148.719023 70.413998) (end 148.719024 70.413999) (width 0.146) (layer "In5.Cu") (net 190))
  (segment (start 150.097888 70.802913) (end 150.168599 70.873624) (width 0.146) (layer "In5.Cu") (net 190))
  (segment (start 143.759456 65.335943) (end 144.135945 64.959458) (width 0.146) (layer "In5.Cu") (net 190))
  (segment (start 149.355423 71.050398) (end 149.355424 71.050399) (width 0.146) (layer "In5.Cu") (net 190))
  (segment (start 149.921112 71.368599) (end 150.168599 71.121112) (width 0.146) (layer "In5.Cu") (net 190))
  (segment (start 141.90854 62.732053) (end 141.532056 63.108542) (width 0.146) (layer "In5.Cu") (net 190))
  (segment (start 140.895655 62.472141) (end 140.895653 62.47214) (width 0.146) (layer "In5.Cu") (net 190))
  (segment (start 148.011912 69.459399) (end 148.259399 69.211912) (width 0.146) (layer "In5.Cu") (net 190))
  (segment (start 169.9 78) (end 169.6 77.7) (width 0.09) (layer "In5.Cu") (net 190))
  (segment (start 148.648312 70.343287) (end 148.719023 70.413998) (width 0.146) (layer "In5.Cu") (net 190))
  (segment (start 150.168599 70.873624) (end 150.1686 70.873625) (width 0.146) (layer "In5.Cu") (net 190))
  (segment (start 140.386328 60.960008) (end 140.386328 61.586328) (width 0.146) (layer "In5.Cu") (net 190))
  (segment (start 142.804858 64.381344) (end 142.804856 64.381343) (width 0.146) (layer "In5.Cu") (net 190))
  (segment (start 170.56 78) (end 169.9 78) (width 0.09) (layer "In5.Cu") (net 190))
  (segment (start 148.895799 69.600824) (end 148.8958 69.600825) (width 0.146) (layer "In5.Cu") (net 190))
  (segment (start 148.648312 70.095799) (end 148.895799 69.848312) (width 0.146) (layer "In5.Cu") (net 190))
  (segment (start 169.6 77.7) (end 169.14 77.7) (width 0.09) (layer "In5.Cu") (net 190))
  (segment (start 175.97 79.28) (end 175.165008 78.475008) (width 0.09) (layer "In5.Cu") (net 190))
  (segment (start 141.532056 63.108542) (end 141.532054 63.108541) (width 0.146) (layer "In5.Cu") (net 190))
  (segment (start 150.805 72.005) (end 151 72.2) (width 0.146) (layer "In5.Cu") (net 190))
  (segment (start 179.789828 80.754964) (end 178.314864 79.28) (width 0.09) (layer "In5.Cu") (net 190))
  (segment (start 140.95394 61.777454) (end 140.95394 61.777453) (width 0.146) (layer "In5.Cu") (net 190))
  (segment (start 148.330111 69.777598) (end 148.5776 69.530113) (width 0.146) (layer "In5.Cu") (net 190))
  (segment (start 149.991823 71.686798) (end 149.991824 71.686799) (width 0.146) (layer "In5.Cu") (net 190))
  (segment (start 149.602911 71.050398) (end 149.8504 70.802913) (width 0.146) (layer "In5.Cu") (net 190))
  (segment (start 149.284712 70.732199) (end 149.532199 70.484712) (width 0.146) (layer "In5.Cu") (net 190))
  (segment (start 141.590341 62.413855) (end 141.590341 62.413854) (width 0.146) (layer "In5.Cu") (net 190))
  (segment (start 160.14 72.2) (end 165.64 77.7) (width 0.146) (layer "In5.Cu") (net 190))
  (segment (start 144.135945 64.959458) (end 144.135945 64.959457) (width 0.146) (layer "In5.Cu") (net 190))
  (segment (start 165.64 77.7) (end 169.14 77.7) (width 0.146) (layer "In5.Cu") (net 190))
  (segment (start 149.532199 70.237224) (end 149.5322 70.237225) (width 0.146) (layer "In5.Cu") (net 190))
  (segment (start 178.314864 79.28) (end 175.97 79.28) (width 0.09) (layer "In5.Cu") (net 190))
  (segment (start 175.165008 78.475008) (end 171.035008 78.475008) (width 0.09) (layer "In5.Cu") (net 190))
  (segment (start 142.544941 63.368454) (end 142.168457 63.744943) (width 0.146) (layer "In5.Cu") (net 190))
  (segment (start 144.425 65.306801) (end 144.424999 65.306801) (width 0.146) (layer "In5.Cu") (net 190))
  (segment (start 140.386328 61.586328) (end 140.606597 61.806598) (width 0.146) (layer "In5.Cu") (net 190))
  (segment (start 144.454144 65.277656) (end 144.425 65.306801) (width 0.146) (layer "In5.Cu") (net 190))
  (segment (start 149.284712 70.979687) (end 149.355423 71.050398) (width 0.146) (layer "In5.Cu") (net 190))
  (segment (start 141.213852 62.790339) (end 141.590341 62.413855) (width 0.146) (layer "In5.Cu") (net 190))
  (segment (start 140.924795 61.806598) (end 140.95394 61.777454) (width 0.146) (layer "In5.Cu") (net 190))
  (segment (start 143.817743 64.641256) (end 143.441259 65.017745) (width 0.146) (layer "In5.Cu") (net 190))
  (segment (start 142.168457 63.744943) (end 142.168455 63.744942) (width 0.146) (layer "In5.Cu") (net 190))
  (segment (start 150.805 71.757512) (end 150.804999 71.757513) (width 0.146) (layer "In5.Cu") (net 190))
  (segment (start 151 72.2) (end 160.14 72.2) (width 0.146) (layer "In5.Cu") (net 190))
  (segment (start 143.123055 64.699542) (end 143.499544 64.323058) (width 0.146) (layer "In5.Cu") (net 190))
  (segment (start 148.082623 69.777598) (end 148.082624 69.777599) (width 0.146) (layer "In5.Cu") (net 190))
  (segment (start 143.181342 64.004855) (end 142.804858 64.381344) (width 0.146) (layer "In5.Cu") (net 190))
  (segment (start 150.239311 71.686798) (end 150.363057 71.563056) (width 0.146) (layer "In5.Cu") (net 190))
  (segment (start 179.789828 81.079634) (end 179.789828 80.754964) (width 0.09) (layer "In5.Cu") (net 190))
  (segment (start 149.461488 70.166513) (end 149.532199 70.237224) (width 0.146) (layer "In5.Cu") (net 190))
  (segment (start 144.425 65.625) (end 147.693712 68.893713) (width 0.146) (layer "In5.Cu") (net 190))
  (segment (start 141.272139 62.095652) (end 140.895655 62.472141) (width 0.146) (layer "In5.Cu") (net 190))
  (segment (start 171.035008 78.475008) (end 170.56 78) (width 0.09) (layer "In5.Cu") (net 190))
  (segment (start 150.734289 71.439313) (end 150.805 71.510024) (width 0.146) (layer "In5.Cu") (net 190))
  (arc (start 149.355424 71.050399) (mid 149.479168 71.101655) (end 149.602911 71.050398) (width 0.146) (layer "In5.Cu") (net 190))
  (arc (start 149.991824 71.686799) (mid 150.115568 71.738055) (end 150.239311 71.686798) (width 0.146) (layer "In5.Cu") (net 190))
  (arc (start 140.895653 62.47214) (mid 140.829753 62.631241) (end 140.895654 62.790339) (width 0.146) (layer "In5.Cu") (net 190))
  (arc (start 149.214 70.166513) (mid 149.337744 70.115257) (end 149.461488 70.166513) (width 0.146) (layer "In5.Cu") (net 190))
  (arc (start 142.226742 63.050255) (mid 142.385842 62.984354) (end 142.544941 63.050256) (width 0.146) (layer "In5.Cu") (net 190))
  (arc (start 148.011912 69.459399) (mid 147.960656 69.583143) (end 148.011912 69.706887) (width 0.146) (layer "In5.Cu") (net 190))
  (arc (start 141.590341 62.413854) (mid 141.749441 62.347953) (end 141.90854 62.413855) (width 0.146) (layer "In5.Cu") (net 190))
  (arc (start 148.2594 68.964425) (mid 148.310656 69.088169) (end 148.259399 69.211912) (width 0.146) (layer "In5.Cu") (net 190))
  (arc (start 142.804857 64.699542) (mid 142.963956 64.765443) (end 143.123055 64.699542) (width 0.146) (layer "In5.Cu") (net 190))
  (arc (start 140.606597 61.806598) (mid 140.765696 61.872499) (end 140.924795 61.806598) (width 0.146) (layer "In5.Cu") (net 190))
  (arc (start 149.284712 70.732199) (mid 149.233456 70.855943) (end 149.284712 70.979687) (width 0.146) (layer "In5.Cu") (net 190))
  (arc (start 142.168455 63.744942) (mid 142.102555 63.904043) (end 142.168456 64.063141) (width 0.146) (layer "In5.Cu") (net 190))
  (arc (start 142.863143 63.686656) (mid 143.022243 63.620755) (end 143.181342 63.686657) (width 0.146) (layer "In5.Cu") (net 190))
  (arc (start 141.532054 63.108541) (mid 141.466154 63.267642) (end 141.532055 63.42674) (width 0.146) (layer "In5.Cu") (net 190))
  (arc (start 148.082624 69.777599) (mid 148.206368 69.828855) (end 148.330111 69.777598) (width 0.146) (layer "In5.Cu") (net 190))
  (arc (start 148.8958 69.600825) (mid 148.947056 69.724569) (end 148.895799 69.848312) (width 0.146) (layer "In5.Cu") (net 190))
  (arc (start 143.441257 65.017744) (mid 143.375357 65.176845) (end 143.441258 65.335943) (width 0.146) (layer "In5.Cu") (net 190))
  (arc (start 143.499544 64.323057) (mid 143.658644 64.257156) (end 143.817743 64.323058) (width 0.146) (layer "In5.Cu") (net 190))
  (arc (start 140.895654 62.790339) (mid 141.054753 62.85624) (end 141.213852 62.790339) (width 0.146) (layer "In5.Cu") (net 190))
  (arc (start 141.532055 63.42674) (mid 141.691154 63.492641) (end 141.850253 63.42674) (width 0.146) (layer "In5.Cu") (net 190))
  (arc (start 150.1686 70.873625) (mid 150.219856 70.997369) (end 150.168599 71.121112) (width 0.146) (layer "In5.Cu") (net 190))
  (arc (start 147.9412 68.893713) (mid 148.064944 68.842457) (end 148.188688 68.893713) (width 0.146) (layer "In5.Cu") (net 190))
  (arc (start 141.90854 62.413855) (mid 141.974441 62.572954) (end 141.90854 62.732053) (width 0.146) (layer "In5.Cu") (net 190))
  (arc (start 150.804999 71.757513) (mid 150.753743 71.881257) (end 150.805 72.005) (width 0.146) (layer "In5.Cu") (net 190))
  (arc (start 142.544941 63.050256) (mid 142.610842 63.209355) (end 142.544941 63.368454) (width 0.146) (layer "In5.Cu") (net 190))
  (arc (start 149.8504 70.802913) (mid 149.974144 70.751657) (end 150.097888 70.802913) (width 0.146) (layer "In5.Cu") (net 190))
  (arc (start 147.693712 68.893713) (mid 147.817456 68.944969) (end 147.9412 68.893713) (width 0.146) (layer "In5.Cu") (net 190))
  (arc (start 149.921112 71.368599) (mid 149.869856 71.492343) (end 149.921112 71.616087) (width 0.146) (layer "In5.Cu") (net 190))
  (arc (start 143.441258 65.335943) (mid 143.600357 65.401844) (end 143.759456 65.335943) (width 0.146) (layer "In5.Cu") (net 190))
  (arc (start 142.804856 64.381343) (mid 142.738956 64.540444) (end 142.804857 64.699542) (width 0.146) (layer "In5.Cu") (net 190))
  (arc (start 143.817743 64.323058) (mid 143.883644 64.482157) (end 143.817743 64.641256) (width 0.146) (layer "In5.Cu") (net 190))
  (arc (start 141.272139 61.777454) (mid 141.33804 61.936553) (end 141.272139 62.095652) (width 0.146) (layer "In5.Cu") (net 190))
  (arc (start 140.95394 61.777453) (mid 141.11304 61.711552) (end 141.272139 61.777454) (width 0.146) (layer "In5.Cu") (net 190))
  (arc (start 150.486801 71.439313) (mid 150.610545 71.388057) (end 150.734289 71.439313) (width 0.146) (layer "In5.Cu") (net 190))
  (arc (start 143.181342 63.686657) (mid 143.247243 63.845756) (end 143.181342 64.004855) (width 0.146) (layer "In5.Cu") (net 190))
  (arc (start 148.5776 69.530113) (mid 148.701344 69.478857) (end 148.825088 69.530113) (width 0.146) (layer "In5.Cu") (net 190))
  (arc (start 149.5322 70.237225) (mid 149.583456 70.360969) (end 149.532199 70.484712) (width 0.146) (layer "In5.Cu") (net 190))
  (arc (start 144.454144 64.959458) (mid 144.520045 65.118557) (end 144.454144 65.277656) (width 0.146) (layer "In5.Cu") (net 190))
  (arc (start 148.719024 70.413999) (mid 148.842768 70.465255) (end 148.966511 70.413998) (width 0.146) (layer "In5.Cu") (net 190))
  (arc (start 148.648312 70.095799) (mid 148.597056 70.219543) (end 148.648312 70.343287) (width 0.146) (layer "In5.Cu") (net 190))
  (arc (start 144.135945 64.959457) (mid 144.295045 64.893556) (end 144.454144 64.959458) (width 0.146) (layer "In5.Cu") (net 190))
  (arc (start 144.424999 65.306801) (mid 144.359098 65.465901) (end 144.425 65.625) (width 0.146) (layer "In5.Cu") (net 190))
  (arc (start 142.168456 64.063141) (mid 142.327555 64.129042) (end 142.486654 64.063141) (width 0.146) (layer "In5.Cu") (net 190))
  (arc (start 150.805 71.510024) (mid 150.856256 71.633768) (end 150.805 71.757512) (width 0.146) (layer "In5.Cu") (net 190))
  (segment (start 132.736328 59.660008) (end 132.736328 60.960008) (width 0.2) (layer "F.Cu") (net 191))
  (segment (start 182.136328 83.560008) (end 181.636328 83.060008) (width 0.127) (layer "F.Cu") (net 191))
  (via (at 132.736328 60.960008) (size 0.5) (drill 0.2) (layers "F.Cu" "B.Cu") (net 191))
  (via (at 181.636328 83.060008) (size 0.5) (drill 0.2) (layers "F.Cu" "B.Cu") (net 191))
  (segment (start 138.3 66.6) (end 157.7 66.6) (width 0.16) (layer "In9.Cu") (net 191))
  (segment (start 180.1 71.3) (end 178 69.2) (width 0.16) (layer "In9.Cu") (net 191))
  (segment (start 167.45 69.2) (end 164.85 66.6) (width 0.16) (layer "In9.Cu") (net 191))
  (segment (start 160.725 66.176298) (end 160.725 67.023702) (width 0.16) (layer "In9.Cu") (net 191))
  (segment (start 161.275 67.023702) (end 161.275 66.176298) (width 0.16) (layer "In9.Cu") (net 191))
  (segment (start 164.575 66.325) (end 164.575 66.176298) (width 0.16) (layer "In9.Cu") (net 191))
  (segment (start 181.606328 81.646328) (end 181.636328 81.646328) (width 0.1) (layer "In9.Cu") (net 191))
  (segment (start 159.075 67.023702) (end 159.075 66.176298) (width 0.16) (layer "In9.Cu") (net 191))
  (segment (start 162.375 67.023702) (end 162.375 66.176298) (width 0.16) (layer "In9.Cu") (net 191))
  (segment (start 180.18 76.02) (end 180.18 77.76) (width 0.1) (layer "In9.Cu") (net 191))
  (segment (start 157.975 67.023702) (end 157.975 66.875) (width 0.16) (layer "In9.Cu") (net 191))
  (segment (start 180.64 80.68) (end 181.606328 81.646328) (width 0.1) (layer "In9.Cu") (net 191))
  (segment (start 161.825 66.176298) (end 161.825 67.023702) (width 0.16) (layer "In9.Cu") (net 191))
  (segment (start 160.175 67.023702) (end 160.175 66.176298) (width 0.16) (layer "In9.Cu") (net 191))
  (segment (start 158.525 66.176298) (end 158.525 67.023702) (width 0.16) (layer "In9.Cu") (net 191))
  (segment (start 180.1 75.94) (end 180.18 76.02) (width 0.1) (layer "In9.Cu") (net 191))
  (segment (start 159.625 66.176298) (end 159.625 67.023702) (width 0.16) (layer "In9.Cu") (net 191))
  (segment (start 164.025 66.325) (end 164.025 67.023702) (width 0.16) (layer "In9.Cu") (net 191))
  (segment (start 162.925 66.176298) (end 162.925 67.023702) (width 0.16) (layer "In9.Cu") (net 191))
  (segment (start 180.1 75.53) (end 180.1 71.3) (width 0.16) (layer "In9.Cu") (net 191))
  (segment (start 163.475 67.023702) (end 163.475 66.176298) (width 0.16) (layer "In9.Cu") (net 191))
  (segment (start 138.3 66.6) (end 132.736328 61.036328) (width 0.16) (layer "In9.Cu") (net 191))
  (segment (start 178 69.2) (end 167.45 69.2) (width 0.16) (layer "In9.Cu") (net 191))
  (segment (start 181.636328 81.646328) (end 181.636328 83.060008) (width 0.1) (layer "In9.Cu") (net 191))
  (segment (start 132.736328 61.036328) (end 132.736328 60.960008) (width 0.16) (layer "In9.Cu") (net 191))
  (segment (start 164.025 66.176298) (end 164.025 66.325) (width 0.16) (layer "In9.Cu") (net 191))
  (segment (start 180.64 78.22) (end 180.64 80.68) (width 0.1) (layer "In9.Cu") (net 191))
  (segment (start 180.1 75.53) (end 180.1 75.94) (width 0.1) (layer "In9.Cu") (net 191))
  (segment (start 180.18 77.76) (end 180.64 78.22) (width 0.1) (layer "In9.Cu") (net 191))
  (arc (start 160.175 66.176298) (mid 160.094454 65.981844) (end 159.9 65.901298) (width 0.16) (layer "In9.Cu") (net 191))
  (arc (start 158.525 67.023702) (mid 158.444454 67.218156) (end 158.25 67.298702) (width 0.16) (layer "In9.Cu") (net 191))
  (arc (start 161.825 67.023702) (mid 161.744454 67.218156) (end 161.55 67.298702) (width 0.16) (layer "In9.Cu") (net 191))
  (arc (start 159.075 66.176298) (mid 158.994454 65.981844) (end 158.8 65.901298) (width 0.16) (layer "In9.Cu") (net 191))
  (arc (start 164.85 66.6) (mid 164.655546 66.519454) (end 164.575 66.325) (width 0.16) (layer "In9.Cu") (net 191))
  (arc (start 160.45 67.298702) (mid 160.255546 67.218156) (end 160.175 67.023702) (width 0.16) (layer "In9.Cu") (net 191))
  (arc (start 163.2 65.901298) (mid 163.005546 65.981844) (end 162.925 66.176298) (width 0.16) (layer "In9.Cu") (net 191))
  (arc (start 158.25 67.298702) (mid 158.055546 67.218156) (end 157.975 67.023702) (width 0.16) (layer "In9.Cu") (net 191))
  (arc (start 162.375 66.176298) (mid 162.294454 65.981844) (end 162.1 65.901298) (width 0.16) (layer "In9.Cu") (net 191))
  (arc (start 164.575 66.176298) (mid 164.494454 65.981844) (end 164.3 65.901298) (width 0.16) (layer "In9.Cu") (net 191))
  (arc (start 161 65.901298) (mid 160.805546 65.981844) (end 160.725 66.176298) (width 0.16) (layer "In9.Cu") (net 191))
  (arc (start 159.35 67.298702) (mid 159.155546 67.218156) (end 159.075 67.023702) (width 0.16) (layer "In9.Cu") (net 191))
  (arc (start 162.925 67.023702) (mid 162.844454 67.218156) (end 162.65 67.298702) (width 0.16) (layer "In9.Cu") (net 191))
  (arc (start 157.975 66.875) (mid 157.894454 66.680546) (end 157.7 66.6) (width 0.16) (layer "In9.Cu") (net 191))
  (arc (start 164.025 67.023702) (mid 163.944454 67.218156) (end 163.75 67.298702) (width 0.16) (layer "In9.Cu") (net 191))
  (arc (start 163.475 66.176298) (mid 163.394454 65.981844) (end 163.2 65.901298) (width 0.16) (layer "In9.Cu") (net 191))
  (arc (start 159.625 67.023702) (mid 159.544454 67.218156) (end 159.35 67.298702) (width 0.16) (layer "In9.Cu") (net 191))
  (arc (start 163.75 67.298702) (mid 163.555546 67.218156) (end 163.475 67.023702) (width 0.16) (layer "In9.Cu") (net 191))
  (arc (start 158.8 65.901298) (mid 158.605546 65.981844) (end 158.525 66.176298) (width 0.16) (layer "In9.Cu") (net 191))
  (arc (start 162.1 65.901298) (mid 161.905546 65.981844) (end 161.825 66.176298) (width 0.16) (layer "In9.Cu") (net 191))
  (arc (start 161.275 66.176298) (mid 161.194454 65.981844) (end 161 65.901298) (width 0.16) (layer "In9.Cu") (net 191))
  (arc (start 160.725 67.023702) (mid 160.644454 67.218156) (end 160.45 67.298702) (width 0.16) (layer "In9.Cu") (net 191))
  (arc (start 161.55 67.298702) (mid 161.355546 67.218156) (end 161.275 67.023702) (width 0.16) (layer "In9.Cu") (net 191))
  (arc (start 159.9 65.901298) (mid 159.705546 65.981844) (end 159.625 66.176298) (width 0.16) (layer "In9.Cu") (net 191))
  (arc (start 162.65 67.298702) (mid 162.455546 67.218156) (end 162.375 67.023702) (width 0.16) (layer "In9.Cu") (net 191))
  (arc (start 164.3 65.901298) (mid 164.105546 65.981844) (end 164.025 66.176298) (width 0.16) (layer "In9.Cu") (net 191))
  (segment (start 180.655 82.9455) (end 180.655 82.995) (width 0.127) (layer "F.Cu") (net 192))
  (segment (start 180.655 82.995) (end 181.136328 83.476328) (width 0.127) (layer "F.Cu") (net 192))
  (segment (start 181.136328 83.476328) (end 181.136328 83.560008) (width 0.127) (layer "F.Cu") (net 192))
  (segment (start 131.036328 60.960008) (end 131.036328 59.660008) (width 0.16) (layer "F.Cu") (net 192))
  (via (at 131.036328 60.960008) (size 0.5) (drill 0.2) (layers "F.Cu" "B.Cu") (net 192))
  (via (at 180.655 82.9455) (size 0.5) (drill 0.2) (layers "F.Cu" "B.Cu") (net 192))
  (segment (start 179.08 75.54) (end 179.08 72.25) (width 0.16) (layer "In9.Cu") (net 192))
  (segment (start 157.655 68.82198) (end 157.655 68.27802) (width 0.16) (layer "In9.Cu") (net 192))
  (segment (start 155.405 68.27802) (end 155.405 68.82198) (width 0.16) (layer "In9.Cu") (net 192))
  (segment (start 151.805 68.27802) (end 151.805 68.82198) (width 0.16) (layer "In9.Cu") (net 192))
  (segment (start 155.855 68.82198) (end 155.855 68.27802) (width 0.16) (layer "In9.Cu") (net 192))
  (segment (start 180.1 78.83) (end 179.3 78.03) (width 0.1) (layer "In9.Cu") (net 192))
  (segment (start 131.036328 63.136328) (end 131.036328 60.960008) (width 0.16) (layer "In9.Cu") (net 192))
  (segment (start 150.68 68.55) (end 150.5 68.55) (width 0.16) (layer "In9.Cu") (net 192))
  (segment (start 180.655 82.9455) (end 180.1 82.3905) (width 0.1) (layer "In9.Cu") (net 192))
  (segment (start 150.5 68.55) (end 150.3 68.75) (width 0.16) (layer "In9.Cu") (net 192))
  (segment (start 177.53 70.7) (end 164.65 70.7) (width 0.16) (layer "In9.Cu") (net 192))
  (segment (start 150.3 68.75) (end 136.65 68.75) (width 0.16) (layer "In9.Cu") (net 192))
  (segment (start 179.08 72.25) (end 177.53 70.7) (width 0.16) (layer "In9.Cu") (net 192))
  (segment (start 150.905 68.27802) (end 150.905 68.325) (width 0.16) (layer "In9.Cu") (net 192))
  (segment (start 154.955 68.82198) (end 154.955 68.27802) (width 0.16) (layer "In9.Cu") (net 192))
  (segment (start 154.055 68.82198) (end 154.055 68.27802) (width 0.16) (layer "In9.Cu") (net 192))
  (segment (start 179.3 76.06) (end 179.08 75.84) (width 0.1) (layer "In9.Cu") (net 192))
  (segment (start 162.5 68.55) (end 158.35567 68.55) (width 0.16) (layer "In9.Cu") (net 192))
  (segment (start 136.65 68.75) (end 131.036328 63.136328) (width 0.16) (layer "In9.Cu") (net 192))
  (segment (start 157.205 68.27802) (end 157.205 68.82198) (width 0.16) (layer "In9.Cu") (net 192))
  (segment (start 156.305 68.27802) (end 156.305 68.82198) (width 0.16) (layer "In9.Cu") (net 192))
  (segment (start 154.505 68.27802) (end 154.505 68.82198) (width 0.16) (layer "In9.Cu") (net 192))
  (segment (start 151.355 68.82198) (end 151.355 68.27802) (width 0.16) (layer "In9.Cu") (net 192))
  (segment (start 156.755 68.82198) (end 156.755 68.27802) (width 0.16) (layer "In9.Cu") (net 192))
  (segment (start 164.65 70.7) (end 162.5 68.55) (width 0.16) (layer "In9.Cu") (net 192))
  (segment (start 179.3 78.03) (end 179.3 76.06) (width 0.1) (layer "In9.Cu") (net 192))
  (segment (start 153.155 68.82198) (end 153.155 68.27802) (width 0.16) (layer "In9.Cu") (net 192))
  (segment (start 180.1 82.3905) (end 180.1 78.83) (width 0.1) (layer "In9.Cu") (net 192))
  (segment (start 152.255 68.82198) (end 152.255 68.27802) (width 0.16) (layer "In9.Cu") (net 192))
  (segment (start 158.105 68.82198) (end 158.105002 68.80065) (width 0.16) (layer "In9.Cu") (net 192))
  (segment (start 153.605 68.27802) (end 153.605 68.82198) (width 0.16) (layer "In9.Cu") (net 192))
  (segment (start 179.08 75.84) (end 179.08 75.54) (width 0.1) (layer "In9.Cu") (net 192))
  (segment (start 152.705 68.27802) (end 152.705 68.82198) (width 0.16) (layer "In9.Cu") (net 192))
  (arc (start 153.155 68.27802) (mid 153.089099 68.118921) (end 152.93 68.05302) (width 0.16) (layer "In9.Cu") (net 192))
  (arc (start 155.855 68.27802) (mid 155.789099 68.118921) (end 155.63 68.05302) (width 0.16) (layer "In9.Cu") (net 192))
  (arc (start 152.03 68.05302) (mid 151.870901 68.118921) (end 151.805 68.27802) (width 0.16) (layer "In9.Cu") (net 192))
  (arc (start 154.505 68.82198) (mid 154.439099 68.981079) (end 154.28 69.04698) (width 0.16) (layer "In9.Cu") (net 192))
  (arc (start 154.28 69.04698) (mid 154.120901 68.981079) (end 154.055 68.82198) (width 0.16) (layer "In9.Cu") (net 192))
  (arc (start 154.955 68.27802) (mid 154.889099 68.118921) (end 154.73 68.05302) (width 0.16) (layer "In9.Cu") (net 192))
  (arc (start 150.905 68.325) (mid 150.839099 68.484099) (end 150.68 68.55) (width 0.16) (layer "In9.Cu") (net 192))
  (arc (start 153.38 69.04698) (mid 153.220901 68.981079) (end 153.155 68.82198) (width 0.16) (layer "In9.Cu") (net 192))
  (arc (start 151.805 68.82198) (mid 151.739099 68.981079) (end 151.58 69.04698) (width 0.16) (layer "In9.Cu") (net 192))
  (arc (start 156.53 68.05302) (mid 156.370901 68.118921) (end 156.305 68.27802) (width 0.16) (layer "In9.Cu") (net 192))
  (arc (start 156.755 68.27802) (mid 156.689099 68.118921) (end 156.53 68.05302) (width 0.16) (layer "In9.Cu") (net 192))
  (arc (start 154.055 68.27802) (mid 153.989099 68.118921) (end 153.83 68.05302) (width 0.16) (layer "In9.Cu") (net 192))
  (arc (start 156.08 69.04698) (mid 155.920901 68.981079) (end 155.855 68.82198) (width 0.16) (layer "In9.Cu") (net 192))
  (arc (start 153.83 68.05302) (mid 153.670901 68.118921) (end 153.605 68.27802) (width 0.16) (layer "In9.Cu") (net 192))
  (arc (start 152.705 68.82198) (mid 152.639099 68.981079) (end 152.48 69.04698) (width 0.16) (layer "In9.Cu") (net 192))
  (arc (start 152.48 69.04698) (mid 152.320901 68.981079) (end 152.255 68.82198) (width 0.16) (layer "In9.Cu") (net 192))
  (arc (start 157.43 68.05302) (mid 157.270901 68.118921) (end 157.205 68.27802) (width 0.16) (layer "In9.Cu") (net 192))
  (arc (start 158.105 68.82198) (mid 158.039099 68.981079) (end 157.88 69.04698) (width 0.16) (layer "In9.Cu") (net 192))
  (arc (start 155.18 69.04698) (mid 155.020901 68.981079) (end 154.955 68.82198) (width 0.16) (layer "In9.Cu") (net 192))
  (arc (start 157.655 68.27802) (mid 157.589099 68.118921) (end 157.43 68.05302) (width 0.16) (layer "In9.Cu") (net 192))
  (arc (start 155.63 68.05302) (mid 155.470901 68.118921) (end 155.405 68.27802) (width 0.16) (layer "In9.Cu") (net 192))
  (arc (start 151.58 69.04698) (mid 151.420901 68.981079) (end 151.355 68.82198) (width 0.16) (layer "In9.Cu") (net 192))
  (arc (start 152.93 68.05302) (mid 152.770901 68.118921) (end 152.705 68.27802) (width 0.16) (layer "In9.Cu") (net 192))
  (arc (start 154.73 68.05302) (mid 154.570901 68.118921) (end 154.505 68.27802) (width 0.16) (layer "In9.Cu") (net 192))
  (arc (start 156.305 68.82198) (mid 156.239099 68.981079) (end 156.08 69.04698) (width 0.16) (layer "In9.Cu") (net 192))
  (arc (start 157.88 69.04698) (mid 157.720901 68.981079) (end 157.655 68.82198) (width 0.16) (layer "In9.Cu") (net 192))
  (arc (start 156.98 69.04698) (mid 156.820901 68.981079) (end 156.755 68.82198) (width 0.16) (layer "In9.Cu") (net 192))
  (arc (start 155.405 68.82198) (mid 155.339099 68.981079) (end 155.18 69.04698) (width 0.16) (layer "In9.Cu") (net 192))
  (arc (start 153.605 68.82198) (mid 153.539099 68.981079) (end 153.38 69.04698) (width 0.16) (layer "In9.Cu") (net 192))
  (arc (start 152.255 68.27802) (mid 152.189099 68.118921) (end 152.03 68.05302) (width 0.16) (layer "In9.Cu") (net 192))
  (arc (start 158.35567 68.55) (mid 158.178427 68.623413) (end 158.105002 68.80065) (width 0.16) (layer "In9.Cu") (net 192))
  (arc (start 151.355 68.27802) (mid 151.289099 68.118921) (end 151.13 68.05302) (width 0.16) (layer "In9.Cu") (net 192))
  (arc (start 151.13 68.05302) (mid 150.970901 68.118921) (end 150.905 68.27802) (width 0.16) (layer "In9.Cu") (net 192))
  (arc (start 157.205 68.82198) (mid 157.139099 68.981079) (end 156.98 69.04698) (width 0.16) (layer "In9.Cu") (net 192))
  (segment (start 176.636328 82.060008) (end 176.636328 82.0405) (width 0.127) (layer "F.Cu") (net 193))
  (segment (start 134.436328 59.660008) (end 134.436328 60.960008) (width 0.2) (layer "F.Cu") (net 193))
  (segment (start 177.136328 82.560008) (end 176.636328 82.060008) (width 0.127) (layer "F.Cu") (net 193))
  (via blind (at 176.636328 82.0405) (size 0.5) (drill 0.2) (layers "F.Cu" "In5.Cu") (net 193))
  (via blind (at 134.436328 60.960008) (size 0.5) (drill 0.2) (layers "F.Cu" "In5.Cu") (net 193))
  (segment (start 157.525 77.1) (end 145.3 77.1) (width 0.146) (layer "In5.Cu") (net 193))
  (segment (start 175.295008 82.475008) (end 175.0495 82.2295) (width 0.09) (layer "In5.Cu") (net 193))
  (segment (start 176.20182 82.475008) (end 175.295008 82.475008) (width 0.09) (layer "In5.Cu") (net 193))
  (segment (start 175.0495 82.2295) (end 169.6295 82.2295) (width 0.09) (layer "In5.Cu") (net 193))
  (segment (start 163.69 82.306) (end 163.69 82.3) (width 0.146) (layer "In5.Cu") (net 193))
  (segment (start 145.3 77.1) (end 134.436328 66.236328) (width 0.146) (layer "In5.Cu") (net 193))
  (segment (start 169.17 82) (end 168.36 82) (width 0.146) (layer "In5.Cu") (net 193))
  (segment (start 162.425 82) (end 163.39 82) (width 0.146) (layer "In5.Cu") (net 193))
  (segment (start 169.4 82) (end 169.17 82) (width 0.09) (layer "In5.Cu") (net 193))
  (segment (start 134.436328 66.236328) (end 134.436328 60.960008) (width 0.146) (layer "In5.Cu") (net 193))
  (segment (start 169.6295 82.2295) (end 169.4 82) (width 0.09) (layer "In5.Cu") (net 193))
  (segment (start 167.16 82) (end 167.11 82) (width 0.146) (layer "In5.Cu") (net 193))
  (segment (start 162.425 82) (end 157.525 77.1) (width 0.146) (layer "In5.Cu") (net 193))
  (segment (start 165.24 82.6) (end 165.19 82.6) (width 0.146) (layer "In5.Cu") (net 193))
  (segment (start 176.636328 82.0405) (end 176.20182 82.475008) (width 0.09) (layer "In5.Cu") (net 193))
  (segment (start 164.29 82.3) (end 164.29 82.306) (width 0.146) (layer "In5.Cu") (net 193))
  (segment (start 167.11 82) (end 167.04 82) (width 0.146) (layer "In5.Cu") (net 193))
  (arc (start 168.06 82.3) (mid 167.972132 82.512132) (end 167.76 82.6) (width 0.146) (layer "In5.Cu") (net 193))
  (arc (start 166.14 82.3) (mid 166.052132 82.087868) (end 165.84 82) (width 0.146) (layer "In5.Cu") (net 193))
  (arc (start 163.99 82.606) (mid 163.777868 82.518132) (end 163.69 82.306) (width 0.146) (layer "In5.Cu") (net 193))
  (arc (start 163.69 82.3) (mid 163.602132 82.087868) (end 163.39 82) (width 0.146) (layer "In5.Cu") (net 193))
  (arc (start 166.74 82.3) (mid 166.652132 82.512132) (end 166.44 82.6) (width 0.146) (layer "In5.Cu") (net 193))
  (arc (start 168.36 82) (mid 168.147868 82.087868) (end 168.06 82.3) (width 0.146) (layer "In5.Cu") (net 193))
  (arc (start 167.76 82.6) (mid 167.547868 82.512132) (end 167.46 82.3) (width 0.146) (layer "In5.Cu") (net 193))
  (arc (start 164.59 82) (mid 164.377868 82.087868) (end 164.29 82.3) (width 0.146) (layer "In5.Cu") (net 193))
  (arc (start 167.46 82.3) (mid 167.372132 82.087868) (end 167.16 82) (width 0.146) (layer "In5.Cu") (net 193))
  (arc (start 165.54 82.3) (mid 165.452132 82.512132) (end 165.24 82.6) (width 0.146) (layer "In5.Cu") (net 193))
  (arc (start 165.84 82) (mid 165.627868 82.087868) (end 165.54 82.3) (width 0.146) (layer "In5.Cu") (net 193))
  (arc (start 164.29 82.306) (mid 164.202132 82.518132) (end 163.99 82.606) (width 0.146) (layer "In5.Cu") (net 193))
  (arc (start 166.44 82.6) (mid 166.227868 82.512132) (end 166.14 82.3) (width 0.146) (layer "In5.Cu") (net 193))
  (arc (start 165.19 82.6) (mid 164.977868 82.512132) (end 164.89 82.3) (width 0.146) (layer "In5.Cu") (net 193))
  (arc (start 167.04 82) (mid 166.827868 82.087868) (end 166.74 82.3) (width 0.146) (layer "In5.Cu") (net 193))
  (arc (start 164.89 82.3) (mid 164.802132 82.087868) (end 164.59 82) (width 0.146) (layer "In5.Cu") (net 193))
  (segment (start 180.735809 78.159489) (end 181.136328 78.560008) (width 0.127) (layer "F.Cu") (net 194))
  (segment (start 159.086328 59.660008) (end 159.086328 60.960008) (width 0.2) (layer "F.Cu") (net 194))
  (segment (start 180.735809 78.021) (end 180.735809 78.159489) (width 0.127) (layer "F.Cu") (net 194))
  (via blind (at 159.086328 60.960008) (size 0.5) (drill 0.2) (layers "F.Cu" "In5.Cu") (net 194))
  (via blind (at 180.735809 78.021) (size 0.5) (drill 0.2) (layers "F.Cu" "In5.Cu") (net 194))
  (segment (start 174.275 66.975) (end 174.275 66.904014) (width 0.146) (layer "In5.Cu") (net 194))
  (segment (start 173.375 67.495986) (end 173.375 66.904014) (width 0.146) (layer "In5.Cu") (net 194))
  (segment (start 171.575 67.495986) (end 171.575 66.904014) (width 0.146) (layer "In5.Cu") (net 194))
  (segment (start 170.225 66.904014) (end 170.225 67.495986) (width 0.146) (layer "In5.Cu") (net 194))
  (segment (start 172.475 67.495986) (end 172.475 66.904014) (width 0.146) (layer "In5.Cu") (net 194))
  (segment (start 168.875 67.495986) (end 168.875 66.904014) (width 0.146) (layer "In5.Cu") (net 194))
  (segment (start 169.325 66.904014) (end 169.325 67.495986) (width 0.146) (layer "In5.Cu") (net 194))
  (segment (start 172.025 66.904014) (end 172.025 67.495986) (width 0.146) (layer "In5.Cu") (net 194))
  (segment (start 171.125 66.904014) (end 171.125 67.495986) (width 0.146) (layer "In5.Cu") (net 194))
  (segment (start 170.675 67.495986) (end 170.675 66.904014) (width 0.146) (layer "In5.Cu") (net 194))
  (segment (start 174.8 67.2) (end 174.5 67.2) (width 0.146) (layer "In5.Cu") (net 194))
  (segment (start 172.925 66.904014) (end 172.925 67.495986) (width 0.146) (layer "In5.Cu") (net 194))
  (segment (start 159.086328 61.786328) (end 159.086328 60.960008) (width 0.146) (layer "In5.Cu") (net 194))
  (segment (start 167.8 67.2) (end 164.5 63.9) (width 0.146) (layer "In5.Cu") (net 194))
  (segment (start 168.425 66.904014) (end 168.425 66.975) (width 0.146) (layer "In5.Cu") (net 194))
  (segment (start 181.28 77.53) (end 181.28 75.56) (width 0.09) (layer "In5.Cu") (net 194))
  (segment (start 181.28 75.56) (end 181.28 73.68) (width 0.146) (layer "In5.Cu") (net 194))
  (segment (start 169.775 67.495986) (end 169.775 66.904014) (width 0.146) (layer "In5.Cu") (net 194))
  (segment (start 181.28 73.68) (end 174.8 67.2) (width 0.146) (layer "In5.Cu") (net 194))
  (segment (start 161.2 63.9) (end 159.086328 61.786328) (width 0.146) (layer "In5.Cu") (net 194))
  (segment (start 173.825 66.975) (end 173.825 67.495986) (width 0.146) (layer "In5.Cu") (net 194))
  (segment (start 168.2 67.2) (end 167.8 67.2) (width 0.146) (layer "In5.Cu") (net 194))
  (segment (start 173.825 66.904014) (end 173.825 66.975) (width 0.146) (layer "In5.Cu") (net 194))
  (segment (start 180.735809 78.021) (end 180.789 78.021) (width 0.09) (layer "In5.Cu") (net 194))
  (segment (start 180.789 78.021) (end 181.28 77.53) (width 0.09) (layer "In5.Cu") (net 194))
  (segment (start 164.5 63.9) (end 161.2 63.9) (width 0.146) (layer "In5.Cu") (net 194))
  (arc (start 171.575 66.904014) (mid 171.509099 66.744915) (end 171.35 66.679014) (width 0.146) (layer "In5.Cu") (net 194))
  (arc (start 172.025 67.495986) (mid 171.959099 67.655085) (end 171.8 67.720986) (width 0.146) (layer "In5.Cu") (net 194))
  (arc (start 174.275 66.904014) (mid 174.209099 66.744915) (end 174.05 66.679014) (width 0.146) (layer "In5.Cu") (net 194))
  (arc (start 169.325 67.495986) (mid 169.259099 67.655085) (end 169.1 67.720986) (width 0.146) (layer "In5.Cu") (net 194))
  (arc (start 173.15 66.679014) (mid 172.990901 66.744915) (end 172.925 66.904014) (width 0.146) (layer "In5.Cu") (net 194))
  (arc (start 171.125 67.495986) (mid 171.059099 67.655085) (end 170.9 67.720986) (width 0.146) (layer "In5.Cu") (net 194))
  (arc (start 170 67.720986) (mid 169.840901 67.655085) (end 169.775 67.495986) (width 0.146) (layer "In5.Cu") (net 194))
  (arc (start 174.05 66.679014) (mid 173.890901 66.744915) (end 173.825 66.904014) (width 0.146) (layer "In5.Cu") (net 194))
  (arc (start 173.825 67.495986) (mid 173.759099 67.655085) (end 173.6 67.720986) (width 0.146) (layer "In5.Cu") (net 194))
  (arc (start 168.65 66.679014) (mid 168.490901 66.744915) (end 168.425 66.904014) (width 0.146) (layer "In5.Cu") (net 194))
  (arc (start 170.225 67.495986) (mid 170.159099 67.655085) (end 170 67.720986) (width 0.146) (layer "In5.Cu") (net 194))
  (arc (start 171.8 67.720986) (mid 171.640901 67.655085) (end 171.575 67.495986) (width 0.146) (layer "In5.Cu") (net 194))
  (arc (start 172.7 67.720986) (mid 172.540901 67.655085) (end 172.475 67.495986) (width 0.146) (layer "In5.Cu") (net 194))
  (arc (start 173.6 67.720986) (mid 173.440901 67.655085) (end 173.375 67.495986) (width 0.146) (layer "In5.Cu") (net 194))
  (arc (start 170.675 66.904014) (mid 170.609099 66.744915) (end 170.45 66.679014) (width 0.146) (layer "In5.Cu") (net 194))
  (arc (start 173.375 66.904014) (mid 173.309099 66.744915) (end 173.15 66.679014) (width 0.146) (layer "In5.Cu") (net 194))
  (arc (start 172.25 66.679014) (mid 172.090901 66.744915) (end 172.025 66.904014) (width 0.146) (layer "In5.Cu") (net 194))
  (arc (start 168.875 66.904014) (mid 168.809099 66.744915) (end 168.65 66.679014) (width 0.146) (layer "In5.Cu") (net 194))
  (arc (start 172.925 67.495986) (mid 172.859099 67.655085) (end 172.7 67.720986) (width 0.146) (layer "In5.Cu") (net 194))
  (arc (start 170.45 66.679014) (mid 170.290901 66.744915) (end 170.225 66.904014) (width 0.146) (layer "In5.Cu") (net 194))
  (arc (start 169.775 66.904014) (mid 169.709099 66.744915) (end 169.55 66.679014) (width 0.146) (layer "In5.Cu") (net 194))
  (arc (start 168.425 66.975) (mid 168.359099 67.134099) (end 168.2 67.2) (width 0.146) (layer "In5.Cu") (net 194))
  (arc (start 174.5 67.2) (mid 174.340901 67.134099) (end 174.275 66.975) (width 0.146) (layer "In5.Cu") (net 194))
  (arc (start 169.55 66.679014) (mid 169.390901 66.744915) (end 169.325 66.904014) (width 0.146) (layer "In5.Cu") (net 194))
  (arc (start 170.9 67.720986) (mid 170.740901 67.655085) (end 170.675 67.495986) (width 0.146) (layer "In5.Cu") (net 194))
  (arc (start 172.475 66.904014) (mid 172.409099 66.744915) (end 172.25 66.679014) (width 0.146) (layer "In5.Cu") (net 194))
  (arc (start 171.35 66.679014) (mid 171.190901 66.744915) (end 171.125 66.904014) (width 0.146) (layer "In5.Cu") (net 194))
  (arc (start 169.1 67.720986) (mid 168.940901 67.655085) (end 168.875 67.495986) (width 0.146) (layer "In5.Cu") (net 194))
  (segment (start 162.486328 59.660008) (end 162.486328 58.310008) (width 0.2) (layer "F.Cu") (net 195))
  (segment (start 114.336328 63.160008) (end 116.851328 63.160008) (width 0.15) (layer "F.Cu") (net 195))
  (segment (start 112.821328 63.160008) (end 114.336328 63.160008) (width 0.15) (layer "F.Cu") (net 195))
  (via (at 162.486328 58.310008) (size 0.5) (drill 0.2) (layers "F.Cu" "B.Cu") (net 195))
  (via (at 114.336328 63.160008) (size 0.5) (drill 0.2) (layers "F.Cu" "B.Cu") (net 195))
  (segment (start 163.1 54.775) (end 160.860008 52.535008) (width 0.15) (layer "B.Cu") (net 195))
  (segment (start 115.836328 54.660008) (end 115.836328 61.660008) (width 0.15) (layer "B.Cu") (net 195))
  (segment (start 117.961328 52.535008) (end 115.836328 54.660008) (width 0.15) (layer "B.Cu") (net 195))
  (segment (start 162.486328 58.310008) (end 163.1 57.696336) (width 0.15) (layer "B.Cu") (net 195))
  (segment (start 163.1 57.696336) (end 163.1 54.775) (width 0.15) (layer "B.Cu") (net 195))
  (segment (start 115.836328 61.660008) (end 114.336328 63.160008) (width 0.15) (layer "B.Cu") (net 195))
  (segment (start 160.860008 52.535008) (end 117.961328 52.535008) (width 0.15) (layer "B.Cu") (net 195))
  (segment (start 177.77632 85.2) (end 177.7 85.2) (width 0.127) (layer "F.Cu") (net 196))
  (segment (start 125.086328 59.660008) (end 125.086328 60.960008) (width 0.2) (layer "F.Cu") (net 196))
  (segment (start 178.136328 85.560008) (end 177.77632 85.2) (width 0.127) (layer "F.Cu") (net 196))
  (via (at 177.7 85.2) (size 0.5) (drill 0.2) (layers "F.Cu" "B.Cu") (net 196))
  (via (at 125.086328 60.960008) (size 0.5) (drill 0.2) (layers "F.Cu" "B.Cu") (net 196))
  (segment (start 175.086328 75.913672) (end 175.086328 75.546328) (width 0.1) (layer "In9.Cu") (net 196))
  (segment (start 163.725 77.054153) (end 163.725 76.925) (width 0.16) (layer "In9.Cu") (net 196))
  (segment (start 133.75 76.6) (end 163.4 76.6) (width 0.16) (layer "In9.Cu") (net 196))
  (segment (start 175.27 81.09971) (end 175.27 77.72) (width 0.1) (layer "In9.Cu") (net 196))
  (segment (start 174.85 77.3) (end 174.85 76.15) (width 0.1) (layer "In9.Cu") (net 196))
  (segment (start 125.086328 67.936328) (end 125.086328 60.960008) (width 0.16) (layer "In9.Cu") (net 196))
  (segment (start 164.9 76.6) (end 164.7 76.6) (width 0.16) (layer "In9.Cu") (net 196))
  (segment (start 133.75 76.6) (end 125.086328 67.936328) (width 0.16) (layer "In9.Cu") (net 196))
  (segment (start 175.27 77.72) (end 174.85 77.3) (width 0.1) (layer "In9.Cu") (net 196))
  (segment (start 164.375 76.925) (end 164.375 77.054153) (width 0.16) (layer "In9.Cu") (net 196))
  (segment (start 176.7 84.2) (end 176.7 82.52971) (width 0.1) (layer "In9.Cu") (net 196))
  (segment (start 166.45 75.05) (end 164.9 76.6) (width 0.16) (layer "In9.Cu") (net 196))
  (segment (start 175.086328 75.546328) (end 174.59 75.05) (width 0.16) (layer "In9.Cu") (net 196))
  (segment (start 174.59 75.05) (end 166.45 75.05) (width 0.16) (layer "In9.Cu") (net 196))
  (segment (start 176.7 82.52971) (end 175.27 81.09971) (width 0.1) (layer "In9.Cu") (net 196))
  (segment (start 174.85 76.15) (end 175.086328 75.913672) (width 0.1) (layer "In9.Cu") (net 196))
  (segment (start 177.7 85.2) (end 176.7 84.2) (width 0.1) (layer "In9.Cu") (net 196))
  (arc (start 164.7 76.6) (mid 164.47019 76.69519) (end 164.375 76.925) (width 0.16) (layer "In9.Cu") (net 196))
  (arc (start 163.725 76.925) (mid 163.62981 76.69519) (end 163.4 76.6) (width 0.16) (layer "In9.Cu") (net 196))
  (arc (start 164.05 77.379153) (mid 163.82019 77.283963) (end 163.725 77.054153) (width 0.16) (layer "In9.Cu") (net 196))
  (arc (start 164.375 77.054153) (mid 164.27981 77.283963) (end 164.05 77.379153) (width 0.16) (layer "In9.Cu") (net 196))
  (segment (start 178.663979 85.087659) (end 179.136328 85.560008) (width 0.127) (layer "F.Cu") (net 197))
  (segment (start 178.5055 85.087659) (end 178.663979 85.087659) (width 0.127) (layer "F.Cu") (net 197))
  (segment (start 126.786328 59.660008) (end 126.786328 60.960008) (width 0.2) (layer "F.Cu") (net 197))
  (via (at 126.786328 60.960008) (size 0.5) (drill 0.2) (layers "F.Cu" "B.Cu") (net 197))
  (via (at 178.5055 85.087659) (size 0.5) (drill 0.2) (layers "F.Cu" "B.Cu") (net 197))
  (segment (start 176.05 75.53) (end 176.05 76.5) (width 0.1) (layer "In9.Cu") (net 197))
  (segment (start 162.525 74.325) (end 162.525 74.32483) (width 0.16) (layer "In9.Cu") (net 197))
  (segment (start 134.83 74.6) (end 160.05 74.6) (width 0.16) (layer "In9.Cu") (net 197))
  (segment (start 161.425 74.87517) (end 161.425 74.32483) (width 0.16) (layer "In9.Cu") (net 197))
  (segment (start 160.875 74.32483) (end 160.875 74.87517) (width 0.16) (layer "In9.Cu") (net 197))
  (segment (start 176.05 74.45) (end 175.5 73.9) (width 0.16) (layer "In9.Cu") (net 197))
  (segment (start 163.3 74.6) (end 162.8 74.6) (width 0.16) (layer "In9.Cu") (net 197))
  (segment (start 176.05 76.5) (end 176.03 76.52) (width 0.1) (layer "In9.Cu") (net 197))
  (segment (start 176.03 76.52) (end 176.03 80.73) (width 0.1) (layer "In9.Cu") (net 197))
  (segment (start 176.03 80.73) (end 178.056328 82.756328) (width 0.1) (layer "In9.Cu") (net 197))
  (segment (start 126.786328 66.556328) (end 126.786328 60.960008) (width 0.16) (layer "In9.Cu") (net 197))
  (segment (start 160.325 74.87517) (end 160.325 74.875) (width 0.16) (layer "In9.Cu") (net 197))
  (segment (start 134.83 74.6) (end 126.786328 66.556328) (width 0.16) (layer "In9.Cu") (net 197))
  (segment (start 164 73.9) (end 163.3 74.6) (width 0.16) (layer "In9.Cu") (net 197))
  (segment (start 178.056328 82.756328) (end 178.056328 84.638487) (width 0.1) (layer "In9.Cu") (net 197))
  (segment (start 176.05 75.53) (end 176.05 74.45) (width 0.16) (layer "In9.Cu") (net 197))
  (segment (start 178.056328 84.638487) (end 178.5055 85.087659) (width 0.1) (layer "In9.Cu") (net 197))
  (segment (start 161.975 74.32483) (end 161.975 74.325) (width 0.16) (layer "In9.Cu") (net 197))
  (segment (start 175.5 73.9) (end 164 73.9) (width 0.16) (layer "In9.Cu") (net 197))
  (segment (start 161.975 74.325) (end 161.975 74.87517) (width 0.16) (layer "In9.Cu") (net 197))
  (arc (start 162.8 74.6) (mid 162.605546 74.519454) (end 162.525 74.325) (width 0.16) (layer "In9.Cu") (net 197))
  (arc (start 161.15 74.04983) (mid 160.955546 74.130376) (end 160.875 74.32483) (width 0.16) (layer "In9.Cu") (net 197))
  (arc (start 162.525 74.32483) (mid 162.444454 74.130376) (end 162.25 74.04983) (width 0.16) (layer "In9.Cu") (net 197))
  (arc (start 161.7 75.15017) (mid 161.505546 75.069624) (end 161.425 74.87517) (width 0.16) (layer "In9.Cu") (net 197))
  (arc (start 161.425 74.32483) (mid 161.344454 74.130376) (end 161.15 74.04983) (width 0.16) (layer "In9.Cu") (net 197))
  (arc (start 160.6 75.15017) (mid 160.405546 75.069624) (end 160.325 74.87517) (width 0.16) (layer "In9.Cu") (net 197))
  (arc (start 160.325 74.875) (mid 160.244454 74.680546) (end 160.05 74.6) (width 0.16) (layer "In9.Cu") (net 197))
  (arc (start 161.975 74.87517) (mid 161.894454 75.069624) (end 161.7 75.15017) (width 0.16) (layer "In9.Cu") (net 197))
  (arc (start 160.875 74.87517) (mid 160.794454 75.069624) (end 160.6 75.15017) (width 0.16) (layer "In9.Cu") (net 197))
  (arc (start 162.25 74.04983) (mid 162.055546 74.130376) (end 161.975 74.32483) (width 0.16) (layer "In9.Cu") (net 197))
  (segment (start 163.336328 59.660008) (end 163.336328 60.960008) (width 0.2) (layer "F.Cu") (net 198))
  (segment (start 185.636328 84.060008) (end 185.636328 84.0405) (width 0.127) (layer "F.Cu") (net 198))
  (segment (start 186.136328 84.560008) (end 185.636328 84.060008) (width 0.127) (layer "F.Cu") (net 198))
  (via (at 163.336328 60.960008) (size 0.5) (drill 0.2) (layers "F.Cu" "B.Cu") (net 198))
  (via blind (at 185.636328 84.0405) (size 0.5) (drill 0.2) (layers "F.Cu" "In5.Cu") (net 198))
  (segment (start 181.417244 67.926153) (end 181.417246 67.926154) (width 0.146) (layer "In5.Cu") (net 198))
  (segment (start 182.124354 67.855445) (end 182.124354 67.855446) (width 0.146) (layer "In5.Cu") (net 198))
  (segment (start 179.08 65.63) (end 176.625 63.175) (width 0.146) (layer "In5.Cu") (net 198))
  (segment (start 182.690046 69.198955) (end 182.690048 69.198956) (width 0.146) (layer "In5.Cu") (net 198))
  (segment (start 180.780843 67.289752) (end 180.780845 67.289753) (width 0.146) (layer "In5.Cu") (net 198))
  (segment (start 183.397156 69.128246) (end 183.397156 69.128247) (width 0.146) (layer "In5.Cu") (net 198))
  (segment (start 167.025 62.325) (end 166.2 61.5) (width 0.146) (layer "In5.Cu") (net 198))
  (segment (start 184.15 82.79) (end 183.196 81.836) (width 0.09) (layer "In5.Cu") (net 198))
  (segment (start 182.760755 68.491847) (end 182.371844 68.880753) (width 0.146) (layer "In5.Cu") (net 198))
  (segment (start 179.51 65.63) (end 179.08 65.63) (width 0.146) (layer "In5.Cu") (net 198))
  (segment (start 180.497998 66.617999) (end 179.51 65.63) (width 0.146) (layer "In5.Cu") (net 198))
  (segment (start 183.68 69.481801) (end 183.715355 69.446445) (width 0.146) (layer "In5.Cu") (net 198))
  (segment (start 163.87632 61.5) (end 163.336328 60.960008) (width 0.146) (layer "In5.Cu") (net 198))
  (segment (start 180.851552 66.582644) (end 180.816196 66.617999) (width 0.146) (layer "In5.Cu") (net 198))
  (segment (start 180.780845 67.289753) (end 181.169751 66.900842) (width 0.146) (layer "In5.Cu") (net 198))
  (segment (start 184.4005 83.6255) (end 184.15 83.375) (width 0.09) (layer "In5.Cu") (net 198))
  (segment (start 171.417896 62.325) (end 167.025 62.325) (width 0.146) (layer "In5.Cu") (net 198))
  (segment (start 183.397156 69.128247) (end 183.008245 69.517154) (width 0.146) (layer "In5.Cu") (net 198))
  (segment (start 183.196 81.836) (end 183.196 76.659) (width 0.09) (layer "In5.Cu") (net 198))
  (segment (start 182.053645 68.562554) (end 182.053647 68.562555) (width 0.146) (layer "In5.Cu") (net 198))
  (segment (start 182.053647 68.562555) (end 182.442553 68.173644) (width 0.146) (layer "In5.Cu") (net 198))
  (segment (start 183.679999 69.481801) (end 183.68 69.481801) (width 0.146) (layer "In5.Cu") (net 198))
  (segment (start 181.487953 67.219044) (end 181.487953 67.219045) (width 0.146) (layer "In5.Cu") (net 198))
  (segment (start 183.77 76.085) (end 183.77 75.56) (width 0.09) (layer "In5.Cu") (net 198))
  (segment (start 182.124354 67.855446) (end 181.735443 68.244352) (width 0.146) (layer "In5.Cu") (net 198))
  (segment (start 183.77 69.89) (end 183.68 69.8) (width 0.146) (layer "In5.Cu") (net 198))
  (segment (start 166.2 61.5) (end 163.87632 61.5) (width 0.146) (layer "In5.Cu") (net 198))
  (segment (start 172.267896 63.175) (end 171.417896 62.325) (width 0.146) (layer "In5.Cu") (net 198))
  (segment (start 181.417246 67.926154) (end 181.806152 67.537243) (width 0.146) (layer "In5.Cu") (net 198))
  (segment (start 185.636328 84.0405) (end 185.221328 83.6255) (width 0.09) (layer "In5.Cu") (net 198))
  (segment (start 182.760755 68.491846) (end 182.760755 68.491847) (width 0.146) (layer "In5.Cu") (net 198))
  (segment (start 180.851552 66.582643) (end 180.851552 66.582644) (width 0.146) (layer "In5.Cu") (net 198))
  (segment (start 181.487953 67.219045) (end 181.099042 67.607951) (width 0.146) (layer "In5.Cu") (net 198))
  (segment (start 182.690048 69.198956) (end 183.078954 68.810045) (width 0.146) (layer "In5.Cu") (net 198))
  (segment (start 183.196 76.659) (end 183.77 76.085) (width 0.09) (layer "In5.Cu") (net 198))
  (segment (start 183.77 75.56) (end 183.77 69.89) (width 0.146) (layer "In5.Cu") (net 198))
  (segment (start 176.625 63.175) (end 172.267896 63.175) (width 0.146) (layer "In5.Cu") (net 198))
  (segment (start 185.221328 83.6255) (end 184.4005 83.6255) (width 0.09) (layer "In5.Cu") (net 198))
  (segment (start 184.15 83.375) (end 184.15 82.79) (width 0.09) (layer "In5.Cu") (net 198))
  (arc (start 182.371844 68.880753) (mid 182.212745 68.946654) (end 182.053646 68.880753) (width 0.146) (layer "In5.Cu") (net 198))
  (arc (start 181.806152 67.219045) (mid 181.647053 67.153143) (end 181.487953 67.219044) (width 0.146) (layer "In5.Cu") (net 198))
  (arc (start 183.078954 68.810045) (mid 183.144855 68.650946) (end 183.078954 68.491847) (width 0.146) (layer "In5.Cu") (net 198))
  (arc (start 183.715355 69.446445) (mid 183.781256 69.287346) (end 183.715355 69.128247) (width 0.146) (layer "In5.Cu") (net 198))
  (arc (start 181.169751 66.900842) (mid 181.235652 66.741743) (end 181.169751 66.582644) (width 0.146) (layer "In5.Cu") (net 198))
  (arc (start 181.806152 67.537243) (mid 181.872053 67.378144) (end 181.806152 67.219045) (width 0.146) (layer "In5.Cu") (net 198))
  (arc (start 182.442553 68.173644) (mid 182.508454 68.014545) (end 182.442553 67.855446) (width 0.146) (layer "In5.Cu") (net 198))
  (arc (start 180.816196 66.617999) (mid 180.657097 66.6839) (end 180.497998 66.617999) (width 0.146) (layer "In5.Cu") (net 198))
  (arc (start 181.099042 67.607951) (mid 180.939943 67.673852) (end 180.780844 67.607951) (width 0.146) (layer "In5.Cu") (net 198))
  (arc (start 180.780844 67.607951) (mid 180.714943 67.448853) (end 180.780843 67.289752) (width 0.146) (layer "In5.Cu") (net 198))
  (arc (start 183.008245 69.517154) (mid 182.849146 69.583055) (end 182.690047 69.517154) (width 0.146) (layer "In5.Cu") (net 198))
  (arc (start 181.735443 68.244352) (mid 181.576344 68.310253) (end 181.417245 68.244352) (width 0.146) (layer "In5.Cu") (net 198))
  (arc (start 181.417245 68.244352) (mid 181.351344 68.085254) (end 181.417244 67.926153) (width 0.146) (layer "In5.Cu") (net 198))
  (arc (start 182.442553 67.855446) (mid 182.283454 67.789544) (end 182.124354 67.855445) (width 0.146) (layer "In5.Cu") (net 198))
  (arc (start 183.078954 68.491847) (mid 182.919855 68.425945) (end 182.760755 68.491846) (width 0.146) (layer "In5.Cu") (net 198))
  (arc (start 183.68 69.8) (mid 183.614098 69.640901) (end 183.679999 69.481801) (width 0.146) (layer "In5.Cu") (net 198))
  (arc (start 181.169751 66.582644) (mid 181.010652 66.516742) (end 180.851552 66.582643) (width 0.146) (layer "In5.Cu") (net 198))
  (arc (start 182.690047 69.517154) (mid 182.624146 69.358056) (end 182.690046 69.198955) (width 0.146) (layer "In5.Cu") (net 198))
  (arc (start 183.715355 69.128247) (mid 183.556256 69.062345) (end 183.397156 69.128246) (width 0.146) (layer "In5.Cu") (net 198))
  (arc (start 182.053646 68.880753) (mid 181.987745 68.721655) (end 182.053645 68.562554) (width 0.146) (layer "In5.Cu") (net 198))
  (segment (start 184.136328 78.560008) (end 184.636328 78.060008) (width 0.127) (layer "F.Cu") (net 199))
  (segment (start 176.086328 59.660008) (end 176.086328 60.960008) (width 0.2) (layer "F.Cu") (net 199))
  (via blind (at 184.636328 78.060008) (size 0.5) (drill 0.2) (layers "F.Cu" "In2.Cu") (net 199))
  (via blind (at 176.086328 60.960008) (size 0.5) (drill 0.2) (layers "F.Cu" "In2.Cu") (net 199))
  (segment (start 184.175 74.025) (end 184.475 74.025) (width 0.16) (layer "In2.Cu") (net 199))
  (segment (start 182.50226 66.661877) (end 182.502259 66.661878) (width 0.16) (layer "In2.Cu") (net 199))
  (segment (start 181.865864 66.025481) (end 181.936573 65.954771) (width 0.16) (layer "In2.Cu") (net 199))
  (segment (start 178.542462 62.984923) (end 178.754593 62.772791) (width 0.16) (layer "In2.Cu") (net 199))
  (segment (start 184.625 70.575) (end 184.625 70.725) (width 0.16) (layer "In2.Cu") (net 199))
  (segment (start 184.025 69.225) (end 184.025 69.375) (width 0.16) (layer "In2.Cu") (net 199))
  (segment (start 184.175 73.125) (end 184.475 73.125) (width 0.16) (layer "In2.Cu") (net 199))
  (segment (start 181.229468 65.389085) (end 181.300177 65.318375) (width 0.16) (layer "In2.Cu") (net 199))
  (segment (start 184.33 75.55) (end 184.325 75.545) (width 0.1) (layer "In2.Cu") (net 199))
  (segment (start 179.956676 64.116293) (end 180.027385 64.045583) (width 0.16) (layer "In2.Cu") (net 199))
  (segment (start 184.625 73.275) (end 184.625 73.425) (width 0.16) (layer "In2.Cu") (net 199))
  (segment (start 184.025 71.025) (end 184.025 71.175) (width 0.16) (layer "In2.Cu") (net 199))
  (segment (start 184.625 68.775) (end 184.625 68.925) (width 0.16) (layer "In2.Cu") (net 199))
  (segment (start 184.625 72.375) (end 184.625 72.525) (width 0.16) (layer "In2.Cu") (net 199))
  (segment (start 182.254771 66.272971) (end 182.184061 66.34368) (width 0.16) (layer "In2.Cu") (net 199))
  (segment (start 184.025 70.125) (end 184.025 70.275) (width 0.16) (layer "In2.Cu") (net 199))
  (segment (start 179.072791 63.090991) (end 178.860659 63.303122) (width 0.16) (layer "In2.Cu") (net 199))
  (segment (start 184.175 72.225) (end 184.475 72.225) (width 0.16) (layer "In2.Cu") (net 199))
  (segment (start 184.636328 76.086328) (end 184.33 75.78) (width 0.1) (layer "In2.Cu") (net 199))
  (segment (start 179.709187 63.727387) (end 179.638477 63.798096) (width 0.16) (layer "In2.Cu") (net 199))
  (segment (start 179.072791 62.772791) (end 179.072792 62.772792) (width 0.16) (layer "In2.Cu") (net 199))
  (segment (start 183.138655 67.298272) (end 183.138654 67.298273) (width 0.16) (layer "In2.Cu") (net 199))
  (segment (start 180.981979 64.681979) (end 180.98198 64.68198) (width 0.16) (layer "In2.Cu") (net 199))
  (segment (start 183.138654 67.298273) (end 183.598271 66.838652) (width 0.16) (layer "In2.Cu") (net 199))
  (segment (start 184.475 72.675) (end 184.175 72.675) (width 0.16) (layer "In2.Cu") (net 199))
  (segment (start 179.709187 63.409187) (end 179.709188 63.409188) (width 0.16) (layer "In2.Cu") (net 199))
  (segment (start 184.163956 67.863956) (end 184.325 68.025) (width 0.16) (layer "In2.Cu") (net 199))
  (segment (start 180.981979 65.000179) (end 180.911269 65.070888) (width 0.16) (layer "In2.Cu") (net 199))
  (segment (start 184.33 75.78) (end 184.33 75.55) (width 0.1) (layer "In2.Cu") (net 199))
  (segment (start 180.593072 64.752689) (end 180.663781 64.681979) (width 0.16) (layer "In2.Cu") (net 199))
  (segment (start 181.618375 65.318375) (end 181.618376 65.318376) (width 0.16) (layer "In2.Cu") (net 199))
  (segment (start 184.025 72.825) (end 184.025 72.975) (width 0.16) (layer "In2.Cu") (net 199))
  (segment (start 184.625 69.675) (end 184.625 69.825) (width 0.16) (layer "In2.Cu") (net 199))
  (segment (start 180.345583 64.363783) (end 180.274873 64.434492) (width 0.16) (layer "In2.Cu") (net 199))
  (segment (start 184.475 70.875) (end 184.175 70.875) (width 0.16) (layer "In2.Cu") (net 199))
  (segment (start 184.025 71.925) (end 184.025 72.075) (width 0.16) (layer "In2.Cu") (net 199))
  (segment (start 180.345583 64.045583) (end 180.345584 64.045584) (width 0.16) (layer "In2.Cu") (net 199))
  (segment (start 177.799999 61.818199) (end 177.587867 62.03033) (width 0.16) (layer "In2.Cu") (net 199))
  (segment (start 184.175 69.525) (end 184.475 69.525) (width 0.16) (layer "In2.Cu") (net 199))
  (segment (start 176.126336 60.92) (end 177.22 60.92) (width 0.16) (layer "In2.Cu") (net 199))
  (segment (start 184.475 73.575) (end 184.175 73.575) (width 0.16) (layer "In2.Cu") (net 199))
  (segment (start 184.475 69.075) (end 184.175 69.075) (width 0.16) (layer "In2.Cu") (net 199))
  (segment (start 184.175 70.425) (end 184.475 70.425) (width 0.16) (layer "In2.Cu") (net 199))
  (segment (start 177.906066 62.348527) (end 178.118197 62.136395) (width 0.16) (layer "In2.Cu") (net 199))
  (segment (start 184.325 68.025) (end 184.325 68.475) (width 0.16) (layer "In2.Cu") (net 199))
  (segment (start 184.625 71.475) (end 184.625 71.625) (width 0.16) (layer "In2.Cu") (net 199))
  (segment (start 184.475 71.775) (end 184.175 71.775) (width 0.16) (layer "In2.Cu") (net 199))
  (segment (start 182.254771 65.954771) (end 182.254772 65.954772) (width 0.16) (layer "In2.Cu") (net 199))
  (segment (start 183.280074 66.520456) (end 182.820456 66.980075) (width 0.16) (layer "In2.Cu") (net 199))
  (segment (start 184.325 74.625) (end 184.325 75.545) (width 0.16) (layer "In2.Cu") (net 199))
  (segment (start 178.436395 62.136395) (end 178.436396 62.136396) (width 0.16) (layer "In2.Cu") (net 199))
  (segment (start 183.91647 67.156853) (end 183.916471 67.156852) (width 0.16) (layer "In2.Cu") (net 199))
  (segment (start 182.502259 66.661878) (end 182.961876 66.202257) (width 0.16) (layer "In2.Cu") (net 199))
  (segment (start 178.436395 62.454595) (end 178.224263 62.666726) (width 0.16) (layer "In2.Cu") (net 199))
  (segment (start 184.475 69.975) (end 184.175 69.975) (width 0.16) (layer "In2.Cu") (net 199))
  (segment (start 177.22 60.92) (end 177.8 61.5) (width 0.16) (layer "In2.Cu") (net 199))
  (segment (start 183.775049 67.934666) (end 183.845758 67.863956) (width 0.16) (layer "In2.Cu") (net 199))
  (segment (start 184.025 73.725) (end 184.025 73.875) (width 0.16) (layer "In2.Cu") (net 199))
  (segment (start 176.086328 60.960008) (end 176.126336 60.92) (width 0.16) (layer "In2.Cu") (net 199))
  (segment (start 183.916471 67.156852) (end 183.45685 67.616469) (width 0.16) (layer "In2.Cu") (net 199))
  (segment (start 179.178858 63.621319) (end 179.390989 63.409187) (width 0.16) (layer "In2.Cu") (net 199))
  (segment (start 184.175 71.325) (end 184.475 71.325) (width 0.16) (layer "In2.Cu") (net 199))
  (segment (start 181.618375 65.636575) (end 181.547665 65.707284) (width 0.16) (layer "In2.Cu") (net 199))
  (segment (start 184.636328 78.060008) (end 184.636328 76.086328) (width 0.1) (layer "In2.Cu") (net 199))
  (segment (start 184.625 74.175) (end 184.625 74.325) (width 0.16) (layer "In2.Cu") (net 199))
  (segment (start 183.280075 66.520458) (end 183.280074 66.520456) (width 0.16) (layer "In2.Cu") (net 199))
  (arc (start 184.025 72.975) (mid 184.068934 73.081066) (end 184.175 73.125) (width 0.16) (layer "In2.Cu") (net 199))
  (arc (start 184.625 73.425) (mid 184.581066 73.531066) (end 184.475 73.575) (width 0.16) (layer "In2.Cu") (net 199))
  (arc (start 182.184061 66.661878) (mid 182.343161 66.727779) (end 182.50226 66.661877) (width 0.16) (layer "In2.Cu") (net 199))
  (arc (start 181.618376 65.318376) (mid 181.684277 65.477476) (end 181.618375 65.636575) (width 0.16) (layer "In2.Cu") (net 199))
  (arc (start 184.475 73.125) (mid 184.581066 73.168934) (end 184.625 73.275) (width 0.16) (layer "In2.Cu") (net 199))
  (arc (start 183.598271 66.838652) (mid 183.757372 66.772753) (end 183.916471 66.838654) (width 0.16) (layer "In2.Cu") (net 199))
  (arc (start 180.274873 64.75269) (mid 180.433973 64.818591) (end 180.593072 64.752689) (width 0.16) (layer "In2.Cu") (net 199))
  (arc (start 184.475 70.425) (mid 184.581066 70.468934) (end 184.625 70.575) (width 0.16) (layer "In2.Cu") (net 199))
  (arc (start 184.025 71.175) (mid 184.068934 71.281066) (end 184.175 71.325) (width 0.16) (layer "In2.Cu") (net 199))
  (arc (start 182.820456 67.298273) (mid 182.979556 67.364174) (end 183.138655 67.298272) (width 0.16) (layer "In2.Cu") (net 199))
  (arc (start 184.625 70.725) (mid 184.581066 70.831066) (end 184.475 70.875) (width 0.16) (layer "In2.Cu") (net 199))
  (arc (start 184.475 74.025) (mid 184.581066 74.068934) (end 184.625 74.175) (width 0.16) (layer "In2.Cu") (net 199))
  (arc (start 184.025 69.375) (mid 184.068934 69.481066) (end 184.175 69.525) (width 0.16) (layer "In2.Cu") (net 199))
  (arc (start 181.547665 65.707284) (mid 181.481764 65.866383) (end 181.547665 66.025482) (width 0.16) (layer "In2.Cu") (net 199))
  (arc (start 181.300177 65.318375) (mid 181.459276 65.252474) (end 181.618375 65.318375) (width 0.16) (layer "In2.Cu") (net 199))
  (arc (start 184.175 69.975) (mid 184.068934 70.018934) (end 184.025 70.125) (width 0.16) (layer "In2.Cu") (net 199))
  (arc (start 184.625 71.625) (mid 184.581066 71.731066) (end 184.475 71.775) (width 0.16) (layer "In2.Cu") (net 199))
  (arc (start 179.638477 63.798096) (mid 179.572576 63.957195) (end 179.638477 64.116294) (width 0.16) (layer "In2.Cu") (net 199))
  (arc (start 184.025 70.275) (mid 184.068934 70.381066) (end 184.175 70.425) (width 0.16) (layer "In2.Cu") (net 199))
  (arc (start 184.625 68.925) (mid 184.581066 69.031066) (end 184.475 69.075) (width 0.16) (layer "In2.Cu") (net 199))
  (arc (start 180.345584 64.045584) (mid 180.411485 64.204684) (end 180.345583 64.363783) (width 0.16) (layer "In2.Cu") (net 199))
  (arc (start 179.638477 64.116294) (mid 179.797577 64.182195) (end 179.956676 64.116293) (width 0.16) (layer "In2.Cu") (net 199))
  (arc (start 182.254772 65.954772) (mid 182.320673 66.113872) (end 182.254771 66.272971) (width 0.16) (layer "In2.Cu") (net 199))
  (arc (start 181.936573 65.954771) (mid 182.095672 65.88887) (end 182.254771 65.954771) (width 0.16) (layer "In2.Cu") (net 199))
  (arc (start 180.98198 64.68198) (mid 181.047881 64.84108) (end 180.981979 65.000179) (width 0.16) (layer "In2.Cu") (net 199))
  (arc (start 180.027385 64.045583) (mid 180.186484 63.979682) (end 180.345583 64.045583) (width 0.16) (layer "In2.Cu") (net 199))
  (arc (start 178.224263 62.666726) (mid 178.158362 62.825825) (end 178.224263 62.984924) (width 0.16) (layer "In2.Cu") (net 199))
  (arc (start 184.475 68.625) (mid 184.581066 68.668934) (end 184.625 68.775) (width 0.16) (layer "In2.Cu") (net 199))
  (arc (start 177.587867 62.03033) (mid 177.521966 62.189429) (end 177.587867 62.348528) (width 0.16) (layer "In2.Cu") (net 199))
  (arc (start 184.325 68.475) (mid 184.368934 68.581066) (end 184.475 68.625) (width 0.16) (layer "In2.Cu") (net 199))
  (arc (start 184.475 72.225) (mid 184.581066 72.268934) (end 184.625 72.375) (width 0.16) (layer "In2.Cu") (net 199))
  (arc (start 178.754593 62.772791) (mid 178.913692 62.70689) (end 179.072791 62.772791) (width 0.16) (layer "In2.Cu") (net 199))
  (arc (start 184.625 69.825) (mid 184.581066 69.931066) (end 184.475 69.975) (width 0.16) (layer "In2.Cu") (net 199))
  (arc (start 182.820456 66.980075) (mid 182.754555 67.139174) (end 182.820456 67.298273) (width 0.16) (layer "In2.Cu") (net 199))
  (arc (start 178.118197 62.136395) (mid 178.277296 62.070494) (end 178.436395 62.136395) (width 0.16) (layer "In2.Cu") (net 199))
  (arc (start 180.274873 64.434492) (mid 180.208972 64.593591) (end 180.274873 64.75269) (width 0.16) (layer "In2.Cu") (net 199))
  (arc (start 182.961876 66.202257) (mid 183.120977 66.136358) (end 183.280076 66.202259) (width 0.16) (layer "In2.Cu") (net 199))
  (arc (start 184.025 72.075) (mid 184.068934 72.181066) (end 184.175 72.225) (width 0.16) (layer "In2.Cu") (net 199))
  (arc (start 183.45685 67.934667) (mid 183.61595 68.000568) (end 183.775049 67.934666) (width 0.16) (layer "In2.Cu") (net 199))
  (arc (start 177.8 61.5) (mid 177.865901 61.6591) (end 177.799999 61.818199) (width 0.16) (layer "In2.Cu") (net 199))
  (arc (start 178.860659 63.62132) (mid 179.019759 63.687221) (end 179.178858 63.621319) (width 0.16) (layer "In2.Cu") (net 199))
  (arc (start 179.709188 63.409188) (mid 179.775089 63.568288) (end 179.709187 63.727387) (width 0.16) (layer "In2.Cu") (net 199))
  (arc (start 184.175 73.575) (mid 184.068934 73.618934) (end 184.025 73.725) (width 0.16) (layer "In2.Cu") (net 199))
  (arc (start 184.025 73.875) (mid 184.068934 73.981066) (end 184.175 74.025) (width 0.16) (layer "In2.Cu") (net 199))
  (arc (start 178.436396 62.136396) (mid 178.502297 62.295496) (end 178.436395 62.454595) (width 0.16) (layer "In2.Cu") (net 199))
  (arc (start 184.625 74.325) (mid 184.581066 74.431066) (end 184.475 74.475) (width 0.16) (layer "In2.Cu") (net 199))
  (arc (start 179.390989 63.409187) (mid 179.550088 63.343286) (end 179.709187 63.409187) (width 0.16) (layer "In2.Cu") (net 199))
  (arc (start 184.475 71.325) (mid 184.581066 71.368934) (end 184.625 71.475) (width 0.16) (layer "In2.Cu") (net 199))
  (arc (start 181.547665 66.025482) (mid 181.706765 66.091383) (end 181.865864 66.025481) (width 0.16) (layer "In2.Cu") (net 199))
  (arc (start 182.184061 66.34368) (mid 182.11816 66.502779) (end 182.184061 66.661878) (width 0.16) (layer "In2.Cu") (net 199))
  (arc (start 180.911269 65.389086) (mid 181.070369 65.454987) (end 181.229468 65.389085) (width 0.16) (layer "In2.Cu") (net 199))
  (arc (start 179.072792 62.772792) (mid 179.138693 62.931892) (end 179.072791 63.090991) (width 0.16) (layer "In2.Cu") (net 199))
  (arc (start 178.860659 63.303122) (mid 178.794758 63.462221) (end 178.860659 63.62132) (width 0.16) (layer "In2.Cu") (net 199))
  (arc (start 184.175 69.075) (mid 184.068934 69.118934) (end 184.025 69.225) (width 0.16) (layer "In2.Cu") (net 199))
  (arc (start 180.663781 64.681979) (mid 180.82288 64.616078) (end 180.981979 64.681979) (width 0.16) (layer "In2.Cu") (net 199))
  (arc (start 184.475 74.475) (mid 184.368934 74.518934) (end 184.325 74.625) (width 0.16) (layer "In2.Cu") (net 199))
  (arc (start 180.911269 65.070888) (mid 180.845368 65.229987) (end 180.911269 65.389086) (width 0.16) (layer "In2.Cu") (net 199))
  (arc (start 184.175 72.675) (mid 184.068934 72.718934) (end 184.025 72.825) (width 0.16) (layer "In2.Cu") (net 199))
  (arc (start 183.845758 67.863956) (mid 184.004857 67.798055) (end 184.163956 67.863956) (width 0.16) (layer "In2.Cu") (net 199))
  (arc (start 184.175 70.875) (mid 184.068934 70.918934) (end 184.025 71.025) (width 0.16) (layer "In2.Cu") (net 199))
  (arc (start 184.475 69.525) (mid 184.581066 69.568934) (end 184.625 69.675) (width 0.16) (layer "In2.Cu") (net 199))
  (arc (start 178.224263 62.984924) (mid 178.383363 63.050825) (end 178.542462 62.984923) (width 0.16) (layer "In2.Cu") (net 199))
  (arc (start 184.175 71.775) (mid 184.068934 71.818934) (end 184.025 71.925) (width 0.16) (layer "In2.Cu") (net 199))
  (arc (start 177.587867 62.348528) (mid 177.746967 62.414429) (end 177.906066 62.348527) (width 0.16) (layer "In2.Cu") (net 199))
  (arc (start 184.625 72.525) (mid 184.581066 72.631066) (end 184.475 72.675) (width 0.16) (layer "In2.Cu") (net 199))
  (arc (start 183.916471 66.838654) (mid 183.982371 66.997753) (end 183.91647 67.156853) (width 0.16) (layer "In2.Cu") (net 199))
  (arc (start 183.280076 66.202259) (mid 183.345976 66.361358) (end 183.280075 66.520458) (width 0.16) (layer "In2.Cu") (net 199))
  (arc (start 183.45685 67.616469) (mid 183.390949 67.775568) (end 183.45685 67.934667) (width 0.16) (layer "In2.Cu") (net 199))
  (segment (start 165.886328 59.660008) (end 165.886328 60.960008) (width 0.2) (layer "F.Cu") (net 200))
  (segment (start 183.636328 80.060008) (end 183.636328 80.0405) (width 0.127) (layer "F.Cu") (net 200))
  (segment (start 184.136328 80.560008) (end 183.636328 80.060008) (width 0.127) (layer "F.Cu") (net 200))
  (via (at 165.886328 60.960008) (size 0.5) (drill 0.2) (layers "F.Cu" "B.Cu") (net 200))
  (via (at 183.636328 80.0405) (size 0.5) (drill 0.2) (layers "F.Cu" "B.Cu") (net 200))
  (segment (start 182.3 73.1) (end 182.392076 73.1) (width 0.16) (layer "In9.Cu") (net 200))
  (segment (start 182.175 76.975) (end 182.175 78.579172) (width 0.1) (layer "In9.Cu") (net 200))
  (segment (start 172.4 66.85) (end 178.7 66.85) (width 0.16) (layer "In9.Cu") (net 200))
  (segment (start 178.7 66.85) (end 182.1 70.25) (width 0.16) (layer "In9.Cu") (net 200))
  (segment (start 182.1 70.25) (end 182.1 72.9) (width 0.16) (layer "In9.Cu") (net 200))
  (segment (start 182.175 78.579172) (end 183.636328 80.0405) (width 0.1) (layer "In9.Cu") (net 200))
  (segment (start 165.886328 61.486328) (end 167.425 63.025) (width 0.16) (layer "In9.Cu") (net 200))
  (segment (start 182.1 74.9) (end 182.1 75.6) (width 0.16) (layer "In9.Cu") (net 200))
  (segment (start 182.1 75.6) (end 182.1 76.9) (width 0.1) (layer "In9.Cu") (net 200))
  (segment (start 182.1 76.9) (end 182.175 76.975) (width 0.1) (layer "In9.Cu") (net 200))
  (segment (start 182.392076 73.5) (end 182.3 73.5) (width 0.16) (layer "In9.Cu") (net 200))
  (segment (start 167.425 63.025) (end 168.575 63.025) (width 0.16) (layer "In9.Cu") (net 200))
  (segment (start 181.707924 74.3) (end 182.392076 74.3) (width 0.16) (layer "In9.Cu") (net 200))
  (segment (start 181.707924 73.9) (end 182.392076 73.9) (width 0.16) (layer "In9.Cu") (net 200))
  (segment (start 165.886328 60.960008) (end 165.886328 61.486328) (width 0.16) (layer "In9.Cu") (net 200))
  (segment (start 181.707924 74.7) (end 181.9 74.7) (width 0.16) (layer "In9.Cu") (net 200))
  (segment (start 182.3 73.5) (end 181.707924 73.5) (width 0.16) (layer "In9.Cu") (net 200))
  (segment (start 168.575 63.025) (end 172.4 66.85) (width 0.16) (layer "In9.Cu") (net 200))
  (arc (start 181.507924 73.7) (mid 181.566503 73.841421) (end 181.707924 73.9) (width 0.16) (layer "In9.Cu") (net 200))
  (arc (start 182.1 72.9) (mid 182.158579 73.041421) (end 182.3 73.1) (width 0.16) (layer "In9.Cu") (net 200))
  (arc (start 182.592076 73.3) (mid 182.533497 73.441421) (end 182.392076 73.5) (width 0.16) (layer "In9.Cu") (net 200))
  (arc (start 181.707924 74.3) (mid 181.566503 74.358579) (end 181.507924 74.5) (width 0.16) (layer "In9.Cu") (net 200))
  (arc (start 181.9 74.7) (mid 182.041421 74.758579) (end 182.1 74.9) (width 0.16) (layer "In9.Cu") (net 200))
  (arc (start 182.392076 73.9) (mid 182.533497 73.958579) (end 182.592076 74.1) (width 0.16) (layer "In9.Cu") (net 200))
  (arc (start 182.592076 74.1) (mid 182.533497 74.241421) (end 182.392076 74.3) (width 0.16) (layer "In9.Cu") (net 200))
  (arc (start 181.707924 73.5) (mid 181.566503 73.558579) (end 181.507924 73.7) (width 0.16) (layer "In9.Cu") (net 200))
  (arc (start 182.392076 73.1) (mid 182.533497 73.158579) (end 182.592076 73.3) (width 0.16) (layer "In9.Cu") (net 200))
  (arc (start 181.507924 74.5) (mid 181.566503 74.641421) (end 181.707924 74.7) (width 0.16) (layer "In9.Cu") (net 200))
  (segment (start 187.636328 84.060008) (end 187.655836 84.060008) (width 0.127) (layer "F.Cu") (net 201))
  (segment (start 187.136328 84.560008) (end 187.636328 84.060008) (width 0.127) (layer "F.Cu") (net 201))
  (segment (start 165.036328 59.660008) (end 165.036328 60.960008) (width 0.2) (layer "F.Cu") (net 201))
  (via (at 165.036328 60.960008) (size 0.5) (drill 0.2) (layers "F.Cu" "B.Cu") (net 201))
  (via blind (at 187.655836 84.060008) (size 0.5) (drill 0.2) (layers "F.Cu" "In5.Cu") (net 201))
  (segment (start 171.628008 61.453008) (end 167.303008 61.453008) (width 0.146) (layer "In5.Cu") (net 201))
  (segment (start 185.75 83.55) (end 184.718 82.518) (width 0.09) (layer "In5.Cu") (net 201))
  (segment (start 166.25 60.4) (end 165.596336 60.4) (width 0.146) (layer "In5.Cu") (net 201))
  (segment (start 184.47 75.985) (end 184.47 75.56) (width 0.09) (layer "In5.Cu") (net 201))
  (segment (start 172.6 62.425) (end 171.628008 61.453008) (width 0.146) (layer "In5.Cu") (net 201))
  (segment (start 179.368986 63.461154) (end 179.227201 63.602938) (width 0.146) (layer "In5.Cu") (net 201))
  (segment (start 184.501 82.518) (end 184.2 82.217) (width 0.09) (layer "In5.Cu") (net 201))
  (segment (start 179.368986 63.461153) (end 179.368986 63.461154) (width 0.146) (layer "In5.Cu") (net 201))
  (segment (start 184.6 76.83) (end 184.6 76.115) (width 0.09) (layer "In5.Cu") (net 201))
  (segment (start 187.145828 83.55) (end 185.75 83.55) (width 0.09) (layer "In5.Cu") (net 201))
  (segment (start 184.2 77.23) (end 184.6 76.83) (width 0.09) (layer "In5.Cu") (net 201))
  (segment (start 184.47 69.27) (end 180.5 65.3) (width 0.146) (layer "In5.Cu") (net 201))
  (segment (start 177.625 62.425) (end 178.802937 63.602938) (width 0.146) (layer "In5.Cu") (net 201))
  (segment (start 180.217519 64.309685) (end 180.217519 64.309686) (width 0.146) (layer "In5.Cu") (net 201))
  (segment (start 180.499999 64.875735) (end 180.5 64.875735) (width 0.146) (layer "In5.Cu") (net 201))
  (segment (start 187.655836 84.060008) (end 187.145828 83.55) (width 0.09) (layer "In5.Cu") (net 201))
  (segment (start 184.718 82.518) (end 184.501 82.518) (width 0.09) (layer "In5.Cu") (net 201))
  (segment (start 179.085421 64.593253) (end 179.793251 63.885418) (width 0.146) (layer "In5.Cu") (net 201))
  (segment (start 179.085419 64.593252) (end 179.085421 64.593253) (width 0.146) (layer "In5.Cu") (net 201))
  (segment (start 184.2 82.217) (end 184.2 77.23) (width 0.09) (layer "In5.Cu") (net 201))
  (segment (start 167.303008 61.453008) (end 166.25 60.4) (width 0.146) (layer "In5.Cu") (net 201))
  (segment (start 184.47 75.56) (end 184.47 69.27) (width 0.146) (layer "In5.Cu") (net 201))
  (segment (start 177.625 62.425) (end 172.6 62.425) (width 0.146) (layer "In5.Cu") (net 201))
  (segment (start 184.6 76.115) (end 184.47 75.985) (width 0.09) (layer "In5.Cu") (net 201))
  (segment (start 180.217519 64.309686) (end 179.509684 65.017517) (width 0.146) (layer "In5.Cu") (net 201))
  (segment (start 180.5 64.875735) (end 180.641784 64.73395) (width 0.146) (layer "In5.Cu") (net 201))
  (segment (start 165.596336 60.4) (end 165.036328 60.960008) (width 0.146) (layer "In5.Cu") (net 201))
  (arc (start 179.793251 63.461154) (mid 179.581119 63.373285) (end 179.368986 63.461153) (width 0.146) (layer "In5.Cu") (net 201))
  (arc (start 180.641784 64.73395) (mid 180.729652 64.521818) (end 180.641784 64.309686) (width 0.146) (layer "In5.Cu") (net 201))
  (arc (start 179.08542 65.017517) (mid 178.997552 64.805386) (end 179.085419 64.593252) (width 0.146) (layer "In5.Cu") (net 201))
  (arc (start 180.641784 64.309686) (mid 180.429652 64.221817) (end 180.217519 64.309685) (width 0.146) (layer "In5.Cu") (net 201))
  (arc (start 179.227201 63.602938) (mid 179.015069 63.690806) (end 178.802937 63.602938) (width 0.146) (layer "In5.Cu") (net 201))
  (arc (start 179.509684 65.017517) (mid 179.297552 65.105385) (end 179.08542 65.017517) (width 0.146) (layer "In5.Cu") (net 201))
  (arc (start 180.5 65.3) (mid 180.412131 65.087868) (end 180.499999 64.875735) (width 0.146) (layer "In5.Cu") (net 201))
  (arc (start 179.793251 63.885418) (mid 179.881119 63.673286) (end 179.793251 63.461154) (width 0.146) (layer "In5.Cu") (net 201))
  (segment (start 178.636328 78.060008) (end 178.636328 78.0405) (width 0.127) (layer "F.Cu") (net 202))
  (segment (start 179.136328 78.560008) (end 178.636328 78.060008) (width 0.127) (layer "F.Cu") (net 202))
  (segment (start 154.836328 59.660008) (end 154.836328 60.960008) (width 0.2) (layer "F.Cu") (net 202))
  (via blind (at 178.636328 78.0405) (size 0.5) (drill 0.2) (layers "F.Cu" "In5.Cu") (net 202))
  (via blind (at 154.836328 60.960008) (size 0.5) (drill 0.2) (layers "F.Cu" "In5.Cu") (net 202))
  (segment (start 173.875 72.825) (end 173.875 72.375) (width 0.146) (layer "In5.Cu") (net 202))
  (segment (start 175.4 72.6) (end 175 72.6) (width 0.146) (layer "In5.Cu") (net 202))
  (segment (start 174.325 72.375) (end 174.325 72.825) (width 0.146) (layer "In5.Cu") (net 202))
  (segment (start 178.636328 78.0405) (end 178.057 77.461172) (width 0.09) (layer "In5.Cu") (net 202))
  (segment (start 178.057 76.757) (end 177.49 76.19) (width 0.09) (layer "In5.Cu") (net 202))
  (segment (start 173.425 72.375) (end 173.425 72.825) (width 0.146) (layer "In5.Cu") (net 202))
  (segment (start 178.057 77.461172) (end 178.057 76.757) (width 0.09) (layer "In5.Cu") (net 202))
  (segment (start 171.6 72.6) (end 172.75 72.6) (width 0.146) (layer "In5.Cu") (net 202))
  (segment (start 170.475 72.844893) (end 170.475 72.355107) (width 0.146) (layer "In5.Cu") (net 202))
  (segment (start 169.8 72.6) (end 168.2 72.6) (width 0.146) (layer "In5.Cu") (net 202))
  (segment (start 170.925 72.375) (end 170.925 72.844893) (width 0.146) (layer "In5.Cu") (net 202))
  (segment (start 177.49 75.56) (end 177.49 74.69) (width 0.146) (layer "In5.Cu") (net 202))
  (segment (start 158.8 67.6) (end 154.836328 63.636328) (width 0.146) (layer "In5.Cu") (net 202))
  (segment (start 163.2 67.6) (end 158.8 67.6) (width 0.146) (layer "In5.Cu") (net 202))
  (segment (start 177.49 74.69) (end 175.4 72.6) (width 0.146) (layer "In5.Cu") (net 202))
  (segment (start 170.925 72.355107) (end 170.925 72.375) (width 0.146) (layer "In5.Cu") (net 202))
  (segment (start 170.025 72.355107) (end 170.025 72.375) (width 0.146) (layer "In5.Cu") (net 202))
  (segment (start 171.375 72.375) (end 171.375 72.355107) (width 0.146) (layer "In5.Cu") (net 202))
  (segment (start 168.2 72.6) (end 163.2 67.6) (width 0.146) (layer "In5.Cu") (net 202))
  (segment (start 177.49 76.19) (end 177.49 75.56) (width 0.09) (layer "In5.Cu") (net 202))
  (segment (start 154.836328 63.636328) (end 154.836328 60.960008) (width 0.146) (layer "In5.Cu") (net 202))
  (arc (start 174.1 73.05) (mid 173.940901 72.984099) (end 173.875 72.825) (width 0.146) (layer "In5.Cu") (net 202))
  (arc (start 172.975 72.825) (mid 172.909099 72.665901) (end 172.75 72.6) (width 0.146) (layer "In5.Cu") (net 202))
  (arc (start 170.925 72.844893) (mid 170.859099 73.003992) (end 170.7 73.069893) (width 0.146) (layer "In5.Cu") (net 202))
  (arc (start 171.6 72.6) (mid 171.440901 72.534099) (end 171.375 72.375) (width 0.146) (layer "In5.Cu") (net 202))
  (arc (start 170.475 72.355107) (mid 170.409099 72.196008) (end 170.25 72.130107) (width 0.146) (layer "In5.Cu") (net 202))
  (arc (start 174.325 72.825) (mid 174.259099 72.984099) (end 174.1 73.05) (width 0.146) (layer "In5.Cu") (net 202))
  (arc (start 170.025 72.375) (mid 169.959099 72.534099) (end 169.8 72.6) (width 0.146) (layer "In5.Cu") (net 202))
  (arc (start 171.15 72.130107) (mid 170.990901 72.196008) (end 170.925 72.355107) (width 0.146) (layer "In5.Cu") (net 202))
  (arc (start 173.875 72.375) (mid 173.809099 72.215901) (end 173.65 72.15) (width 0.146) (layer "In5.Cu") (net 202))
  (arc (start 173.425 72.825) (mid 173.359099 72.984099) (end 173.2 73.05) (width 0.146) (layer "In5.Cu") (net 202))
  (arc (start 173.2 73.05) (mid 173.040901 72.984099) (end 172.975 72.825) (width 0.146) (layer "In5.Cu") (net 202))
  (arc (start 174.775 72.375) (mid 174.709099 72.215901) (end 174.55 72.15) (width 0.146) (layer "In5.Cu") (net 202))
  (arc (start 170.7 73.069893) (mid 170.540901 73.003992) (end 170.475 72.844893) (width 0.146) (layer "In5.Cu") (net 202))
  (arc (start 171.375 72.355107) (mid 171.309099 72.196008) (end 171.15 72.130107) (width 0.146) (layer "In5.Cu") (net 202))
  (arc (start 175 72.6) (mid 174.840901 72.534099) (end 174.775 72.375) (width 0.146) (layer "In5.Cu") (net 202))
  (arc (start 173.65 72.15) (mid 173.490901 72.215901) (end 173.425 72.375) (width 0.146) (layer "In5.Cu") (net 202))
  (arc (start 170.25 72.130107) (mid 170.090901 72.196008) (end 170.025 72.355107) (width 0.146) (layer "In5.Cu") (net 202))
  (arc (start 174.55 72.15) (mid 174.390901 72.215901) (end 174.325 72.375) (width 0.146) (layer "In5.Cu") (net 202))
  (segment (start 151.436328 59.660008) (end 151.436328 60.960008) (width 0.2) (layer "F.Cu") (net 203))
  (segment (start 180.636328 79.060008) (end 181.136328 79.560008) (width 0.127) (layer "F.Cu") (net 203))
  (via blind (at 151.436328 60.960008) (size 0.5) (drill 0.2) (layers "F.Cu" "In2.Cu") (net 203))
  (via blind (at 180.636328 79.060008) (size 0.5) (drill 0.2) (layers "F.Cu" "In2.Cu") (net 203))
  (segment (start 176.75269 68.610058) (end 176.75269 68.610059) (width 0.16) (layer "In2.Cu") (net 203))
  (segment (start 177.476788 70.608329) (end 177.476789 70.608329) (width 0.16) (layer "In2.Cu") (net 203))
  (segment (start 178.817012 73.455) (end 179.442988 73.455) (width 0.16) (layer "In2.Cu") (net 203))
  (segment (start 177.476788 70.219419) (end 177.919419 69.776788) (width 0.16) (layer "In2.Cu") (net 203))
  (segment (start 175.921148 69.052689) (end 175.921149 69.052689) (width 0.16) (layer "In2.Cu") (net 203))
  (segment (start 179.13 75.53) (end 179.13 74.83) (width 0.16) (layer "In2.Cu") (net 203))
  (segment (start 175.19705 67.054419) (end 175.170188 67.08128) (width 0.16) (layer "In2.Cu") (net 203))
  (segment (start 176.75269 68.610059) (end 176.310057 69.052688) (width 0.16) (layer "In2.Cu") (net 203))
  (segment (start 178.30833 70.165698) (end 178.30833 70.165699) (width 0.16) (layer "In2.Cu") (net 203))
  (segment (start 179.44 78.53) (end 179.13 78.22) (width 0.1) (layer "In2.Cu") (net 203))
  (segment (start 177.53051 69.387879) (end 177.087877 69.830508) (width 0.16) (layer "In2.Cu") (net 203))
  (segment (start 175.143328 67.885959) (end 175.585959 67.443328) (width 0.16) (layer "In2.Cu") (net 203))
  (segment (start 177.1416 68.610059) (end 177.141599 68.610059) (width 0.16) (layer "In2.Cu") (net 203))
  (segment (start 155.8 66.5) (end 151.436328 62.136328) (width 0.16) (layer "In2.Cu") (net 203))
  (segment (start 179.13 71.43) (end 179.05929 71.35929) (width 0.16) (layer "In2.Cu") (net 203))
  (segment (start 178.67038 71.359289) (end 178.643519 71.386151) (width 0.16) (layer "In2.Cu") (net 203))
  (segment (start 176.36378 67.832239) (end 176.363779 67.832239) (width 0.16) (layer "In2.Cu") (net 203))
  (segment (start 178.817012 72.905) (end 179.442988 72.905) (width 0.16) (layer "In2.Cu") (net 203))
  (segment (start 174.2 66.5) (end 155.8 66.5) (width 0.16) (layer "In2.Cu") (net 203))
  (segment (start 175.921148 68.66378) (end 175.921148 68.663779) (width 0.16) (layer "In2.Cu") (net 203))
  (segment (start 175.143328 67.88596) (end 175.143328 67.885959) (width 0.16) (layer "In2.Cu") (net 203))
  (segment (start 177.476788 70.21942) (end 177.476788 70.219419) (width 0.16) (layer "In2.Cu") (net 203))
  (segment (start 176.698968 69.441599) (end 177.141599 68.998968) (width 0.16) (layer "In2.Cu") (net 203))
  (segment (start 174.781279 67.08128) (end 174.2 66.5) (width 0.16) (layer "In2.Cu") (net 203))
  (segment (start 178.254611 71.386151) (end 178.254609 71.38615) (width 0.16) (layer "In2.Cu") (net 203))
  (segment (start 179.442988 72.355) (end 179.405 72.355) (width 0.16) (layer "In2.Cu") (net 203))
  (segment (start 176.698968 69.4416) (end 176.698968 69.441599) (width 0.16) (layer "In2.Cu") (net 203))
  (segment (start 180.10632 78.53) (end 179.44 78.53) (width 0.1) (layer "In2.Cu") (net 203))
  (segment (start 175.143328 68.274869) (end 175.143329 68.274869) (width 0.16) (layer "In2.Cu") (net 203))
  (segment (start 180.636328 79.060008) (end 180.10632 78.53) (width 0.1) (layer "In2.Cu") (net 203))
  (segment (start 178.254608 70.997241) (end 178.25461 70.997242) (width 0.16) (layer "In2.Cu") (net 203))
  (segment (start 175.97487 67.832238) (end 175.97487 67.832239) (width 0.16) (layer "In2.Cu") (net 203))
  (segment (start 175.921148 68.663779) (end 176.363779 68.221148) (width 0.16) (layer "In2.Cu") (net 203))
  (segment (start 177.53051 69.387878) (end 177.53051 69.387879) (width 0.16) (layer "In2.Cu") (net 203))
  (segment (start 175.58596 67.054419) (end 175.585959 67.054419) (width 0.16) (layer "In2.Cu") (net 203))
  (segment (start 178.25461 70.997242) (end 178.697239 70.554608) (width 0.16) (layer "In2.Cu") (net 203))
  (segment (start 178.30833 70.165699) (end 177.865697 70.608328) (width 0.16) (layer "In2.Cu") (net 203))
  (segment (start 177.91942 69.387879) (end 177.919419 69.387879) (width 0.16) (layer "In2.Cu") (net 203))
  (segment (start 178.670381 71.359289) (end 178.67038 71.359289) (width 0.16) (layer "In2.Cu") (net 203))
  (segment (start 174.78128 67.08128) (end 174.781279 67.08128) (width 0.16) (layer "In2.Cu") (net 203))
  (segment (start 151.436328 62.136328) (end 151.436328 60.960008) (width 0.16) (layer "In2.Cu") (net 203))
  (segment (start 178.855 74.555) (end 178.817012 74.555) (width 0.16) (layer "In2.Cu") (net 203))
  (segment (start 179.13 72.08) (end 179.13 71.43) (width 0.16) (layer "In2.Cu") (net 203))
  (segment (start 178.855 74.005) (end 179.442988 74.005) (width 0.16) (layer "In2.Cu") (net 203))
  (segment (start 178.817012 74.005) (end 178.855 74.005) (width 0.16) (layer "In2.Cu") (net 203))
  (segment (start 176.698968 69.830509) (end 176.698969 69.830509) (width 0.16) (layer "In2.Cu") (net 203))
  (segment (start 178.69724 70.165699) (end 178.697239 70.165699) (width 0.16) (layer "In2.Cu") (net 203))
  (segment (start 175.19705 67.054418) (end 175.19705 67.054419) (width 0.16) (layer "In2.Cu") (net 203))
  (segment (start 179.13 78.22) (end 179.13 75.53) (width 0.1) (layer "In2.Cu") (net 203))
  (segment (start 175.97487 67.832239) (end 175.532237 68.274868) (width 0.16) (layer "In2.Cu") (net 203))
  (arc (start 175.585959 67.443328) (mid 175.666505 67.248874) (end 175.58596 67.054419) (width 0.16) (layer "In2.Cu") (net 203))
  (arc (start 175.532237 68.274868) (mid 175.337783 68.355414) (end 175.143328 68.274869) (width 0.16) (layer "In2.Cu") (net 203))
  (arc (start 179.13 74.83) (mid 179.049454 74.635546) (end 178.855 74.555) (width 0.16) (layer "In2.Cu") (net 203))
  (arc (start 177.919419 69.776788) (mid 177.999965 69.582334) (end 177.91942 69.387879) (width 0.16) (layer "In2.Cu") (net 203))
  (arc (start 178.542012 73.18) (mid 178.622558 72.985546) (end 178.817012 72.905) (width 0.16) (layer "In2.Cu") (net 203))
  (arc (start 178.697239 70.554608) (mid 178.777785 70.360154) (end 178.69724 70.165699) (width 0.16) (layer "In2.Cu") (net 203))
  (arc (start 177.476789 70.608329) (mid 177.396243 70.413875) (end 177.476788 70.21942) (width 0.16) (layer "In2.Cu") (net 203))
  (arc (start 179.442988 72.905) (mid 179.637442 72.824454) (end 179.717988 72.63) (width 0.16) (layer "In2.Cu") (net 203))
  (arc (start 176.363779 67.832239) (mid 176.169325 67.751693) (end 175.97487 67.832238) (width 0.16) (layer "In2.Cu") (net 203))
  (arc (start 177.919419 69.387879) (mid 177.724965 69.307333) (end 177.53051 69.387878) (width 0.16) (layer "In2.Cu") (net 203))
  (arc (start 179.442988 74.005) (mid 179.637442 73.924454) (end 179.717988 73.73) (width 0.16) (layer "In2.Cu") (net 203))
  (arc (start 179.717988 72.63) (mid 179.637442 72.435546) (end 179.442988 72.355) (width 0.16) (layer "In2.Cu") (net 203))
  (arc (start 176.698969 69.830509) (mid 176.618423 69.636055) (end 176.698968 69.4416) (width 0.16) (layer "In2.Cu") (net 203))
  (arc (start 178.697239 70.165699) (mid 178.502785 70.085153) (end 178.30833 70.165698) (width 0.16) (layer "In2.Cu") (net 203))
  (arc (start 177.141599 68.998968) (mid 177.222145 68.804514) (end 177.1416 68.610059) (width 0.16) (layer "In2.Cu") (net 203))
  (arc (start 175.143329 68.274869) (mid 175.062783 68.080415) (end 175.143328 67.88596) (width 0.16) (layer "In2.Cu") (net 203))
  (arc (start 179.405 72.355) (mid 179.210546 72.274454) (end 179.13 72.08) (width 0.16) (layer "In2.Cu") (net 203))
  (arc (start 179.717988 73.73) (mid 179.637442 73.535546) (end 179.442988 73.455) (width 0.16) (layer "In2.Cu") (net 203))
  (arc (start 175.921149 69.052689) (mid 175.840603 68.858235) (end 175.921148 68.66378) (width 0.16) (layer "In2.Cu") (net 203))
  (arc (start 176.310057 69.052688) (mid 176.115603 69.133234) (end 175.921148 69.052689) (width 0.16) (layer "In2.Cu") (net 203))
  (arc (start 177.087877 69.830508) (mid 176.893423 69.911054) (end 176.698968 69.830509) (width 0.16) (layer "In2.Cu") (net 203))
  (arc (start 177.865697 70.608328) (mid 177.671243 70.688874) (end 177.476788 70.608329) (width 0.16) (layer "In2.Cu") (net 203))
  (arc (start 176.363779 68.221148) (mid 176.444325 68.026694) (end 176.36378 67.832239) (width 0.16) (layer "In2.Cu") (net 203))
  (arc (start 178.817012 73.455) (mid 178.622558 73.374454) (end 178.542012 73.18) (width 0.16) (layer "In2.Cu") (net 203))
  (arc (start 178.643519 71.386151) (mid 178.449064 71.466695) (end 178.254611 71.386151) (width 0.16) (layer "In2.Cu") (net 203))
  (arc (start 178.542012 74.28) (mid 178.622558 74.085546) (end 178.817012 74.005) (width 0.16) (layer "In2.Cu") (net 203))
  (arc (start 177.141599 68.610059) (mid 176.947145 68.529513) (end 176.75269 68.610058) (width 0.16) (layer "In2.Cu") (net 203))
  (arc (start 175.170188 67.08128) (mid 174.975734 67.161825) (end 174.78128 67.08128) (width 0.16) (layer "In2.Cu") (net 203))
  (arc (start 175.585959 67.054419) (mid 175.391505 66.973873) (end 175.19705 67.054418) (width 0.16) (layer "In2.Cu") (net 203))
  (arc (start 178.254609 71.38615) (mid 178.174063 71.191696) (end 178.254608 70.997241) (width 0.16) (layer "In2.Cu") (net 203))
  (arc (start 178.817012 74.555) (mid 178.622558 74.474454) (end 178.542012 74.28) (width 0.16) (layer "In2.Cu") (net 203))
  (arc (start 179.05929 71.35929) (mid 178.864836 71.278744) (end 178.670381 71.359289) (width 0.16) (layer "In2.Cu") (net 203))
  (segment (start 180.704799 81.061) (end 180.704799 81.128479) (width 0.127) (layer "F.Cu") (net 204))
  (segment (start 180.704799 81.128479) (end 181.136328 81.560008) (width 0.127) (layer "F.Cu") (net 204))
  (segment (start 142.086328 59.660008) (end 142.086328 60.960008) (width 0.2) (layer "F.Cu") (net 204))
  (via blind (at 142.086328 60.960008) (size 0.5) (drill 0.2) (layers "F.Cu" "In5.Cu") (net 204))
  (via blind (at 180.704799 81.061) (size 0.5) (drill 0.2) (layers "F.Cu" "In5.Cu") (net 204))
  (segment (start 157.08 71.2) (end 157.03 71.2) (width 0.146) (layer "In5.Cu") (net 204))
  (segment (start 180.704799 81.061) (end 180.704799 80.69587) (width 0.09) (layer "In5.Cu") (net 204))
  (segment (start 156.83 71) (end 156.83 70.6) (width 0.146) (layer "In5.Cu") (net 204))
  (segment (start 152.6 70.8) (end 151.735 69.935) (width 0.146) (layer "In5.Cu") (net 204))
  (segment (start 151.204667 69.404667) (end 151.380948 69.228385) (width 0.146) (layer "In5.Cu") (net 204))
  (segment (start 159.53 71) (end 159.53 70.6) (width 0.146) (layer "In5.Cu") (net 204))
  (segment (start 159.78 71.2) (end 159.73 71.2) (width 0.146) (layer "In5.Cu") (net 204))
  (segment (start 149.615158 68.520281) (end 149.615159 68.520282) (width 0.146) (layer "In5.Cu") (net 204))
  (segment (start 159.98 70.6) (end 159.98 71) (width 0.146) (layer "In5.Cu") (net 204))
  (segment (start 153.68 70.6) (end 153.68 71) (width 0.146) (layer "In5.Cu") (net 204))
  (segment (start 155.03 71) (end 155.03 70.6) (width 0.146) (layer "In5.Cu") (net 204))
  (segment (start 155.93 71) (end 155.93 70.6) (width 0.146) (layer "In5.Cu") (net 204))
  (segment (start 157.98 71.2) (end 157.93 71.2) (width 0.146) (layer "In5.Cu") (net 204))
  (segment (start 160.23 70.4) (end 160.18 70.4) (width 0.146) (layer "In5.Cu") (net 204))
  (segment (start 156.38 70.6) (end 156.38 71) (width 0.146) (layer "In5.Cu") (net 204))
  (segment (start 158.88 71.2) (end 158.83 71.2) (width 0.146) (layer "In5.Cu") (net 204))
  (segment (start 157.73 71) (end 157.73 70.6) (width 0.146) (layer "In5.Cu") (net 204))
  (segment (start 149.614167 67.814166) (end 149.614167 67.814167) (width 0.146) (layer "In5.Cu") (net 204))
  (segment (start 157.28 70.6) (end 157.28 71) (width 0.146) (layer "In5.Cu") (net 204))
  (segment (start 155.73 70.4) (end 155.68 70.4) (width 0.146) (layer "In5.Cu") (net 204))
  (segment (start 153.93 70.4) (end 153.88 70.4) (width 0.146) (layer "In5.Cu") (net 204))
  (segment (start 151.380947 68.875824) (end 151.380948 68.875825) (width 0.146) (layer "In5.Cu") (net 204))
  (segment (start 150.320284 68.167722) (end 149.967719 68.520282) (width 0.146) (layer "In5.Cu") (net 204))
  (segment (start 161.071 70.8) (end 160.63 70.8) (width 0.146) (layer "In5.Cu") (net 204))
  (segment (start 151.027394 68.874832) (end 150.674829 69.227392) (width 0.146) (layer "In5.Cu") (net 204))
  (segment (start 156.18 71.2) (end 156.13 71.2) (width 0.146) (layer "In5.Cu") (net 204))
  (segment (start 154.58 70.6) (end 154.58 71) (width 0.146) (layer "In5.Cu") (net 204))
  (segment (start 155.48 70.6) (end 155.48 71) (width 0.146) (layer "In5.Cu") (net 204))
  (segment (start 151.029877 69.935001) (end 151.029876 69.934999) (width 0.146) (layer "In5.Cu") (net 204))
  (segment (start 151.028884 69.581446) (end 151.028883 69.581444) (width 0.146) (layer "In5.Cu") (net 204))
  (segment (start 178.788929 78.78) (end 176.765055 78.78) (width 0.09) (layer "In5.Cu") (net 204))
  (segment (start 154.13 71) (end 154.13 70.6) (width 0.146) (layer "In5.Cu") (net 204))
  (segment (start 151.027394 68.874831) (end 151.027394 68.874832) (width 0.146) (layer "In5.Cu") (net 204))
  (segment (start 149.614167 67.814167) (end 142.760008 60.960008) (width 0.146) (layer "In5.Cu") (net 204))
  (segment (start 153.03 70.8) (end 152.6 70.8) (width 0.146) (layer "In5.Cu") (net 204))
  (segment (start 159.08 70.6) (end 159.08 71) (width 0.146) (layer "In5.Cu") (net 204))
  (segment (start 166.772 76.501) (end 161.071 70.8) (width 0.146) (layer "In5.Cu") (net 204))
  (segment (start 158.63 71) (end 158.63 70.6) (width 0.146) (layer "In5.Cu") (net 204))
  (segment (start 151.028883 69.581444) (end 151.205164 69.405163) (width 0.146) (layer "In5.Cu") (net 204))
  (segment (start 149.615159 68.520282) (end 149.614166 68.519289) (width 0.146) (layer "In5.Cu") (net 204))
  (segment (start 150.673838 68.168715) (end 150.672845 68.167722) (width 0.146) (layer "In5.Cu") (net 204))
  (segment (start 176.765055 78.78) (end 174.486055 76.501) (width 0.09) (layer "In5.Cu") (net 204))
  (segment (start 142.760008 60.960008) (end 142.086328 60.960008) (width 0.146) (layer "In5.Cu") (net 204))
  (segment (start 150.321277 68.873839) (end 150.673838 68.521275) (width 0.146) (layer "In5.Cu") (net 204))
  (segment (start 153.48 71.2) (end 153.43 71.2) (width 0.146) (layer "In5.Cu") (net 204))
  (segment (start 150.673837 68.168714) (end 150.673838 68.168715) (width 0.146) (layer "In5.Cu") (net 204))
  (segment (start 150.322269 69.227392) (end 150.321276 69.226399) (width 0.146) (layer "In5.Cu") (net 204))
  (segment (start 151.380948 68.875825) (end 151.379955 68.874832) (width 0.146) (layer "In5.Cu") (net 204))
  (segment (start 151.029876 69.934999) (end 151.028883 69.934006) (width 0.146) (layer "In5.Cu") (net 204))
  (segment (start 157.53 70.4) (end 157.48 70.4) (width 0.146) (layer "In5.Cu") (net 204))
  (segment (start 149.614167 68.166729) (end 149.614166 68.166727) (width 0.146) (layer "In5.Cu") (net 204))
  (segment (start 159.33 70.4) (end 159.28 70.4) (width 0.146) (layer "In5.Cu") (net 204))
  (segment (start 158.18 70.6) (end 158.18 71) (width 0.146) (layer "In5.Cu") (net 204))
  (segment (start 154.38 71.2) (end 154.33 71.2) (width 0.146) (layer "In5.Cu") (net 204))
  (segment (start 150.320284 68.167721) (end 150.320284 68.167722) (width 0.146) (layer "In5.Cu") (net 204))
  (segment (start 154.83 70.4) (end 154.78 70.4) (width 0.146) (layer "In5.Cu") (net 204))
  (segment (start 150.322268 69.227391) (end 150.322269 69.227392) (width 0.146) (layer "In5.Cu") (net 204))
  (segment (start 174.486055 76.501) (end 168.997 76.501) (width 0.09) (layer "In5.Cu") (net 204))
  (segment (start 156.63 70.4) (end 156.58 70.4) (width 0.146) (layer "In5.Cu") (net 204))
  (segment (start 151.205164 69.405163) (end 151.204667 69.404667) (width 0.146) (layer "In5.Cu") (net 204))
  (segment (start 151.028882 69.581445) (end 151.028884 69.581446) (width 0.146) (layer "In5.Cu") (net 204))
  (segment (start 151.382438 69.934999) (end 151.382438 69.935) (width 0.146) (layer "In5.Cu") (net 204))
  (segment (start 155.28 71.2) (end 155.23 71.2) (width 0.146) (layer "In5.Cu") (net 204))
  (segment (start 151.382439 69.934999) (end 151.382438 69.934999) (width 0.146) (layer "In5.Cu") (net 204))
  (segment (start 158.43 70.4) (end 158.38 70.4) (width 0.146) (layer "In5.Cu") (net 204))
  (segment (start 168.997 76.501) (end 166.772 76.501) (width 0.146) (layer "In5.Cu") (net 204))
  (segment (start 149.614165 68.166728) (end 149.614167 68.166729) (width 0.146) (layer "In5.Cu") (net 204))
  (segment (start 180.704799 80.69587) (end 178.788929 78.78) (width 0.09) (layer "In5.Cu") (net 204))
  (segment (start 150.321275 68.873838) (end 150.321277 68.873839) (width 0.146) (layer "In5.Cu") (net 204))
  (arc (start 159.28 70.4) (mid 159.138579 70.458579) (end 159.08 70.6) (width 0.146) (layer "In5.Cu") (net 204))
  (arc (start 154.13 70.6) (mid 154.071421 70.458579) (end 153.93 70.4) (width 0.146) (layer "In5.Cu") (net 204))
  (arc (start 154.33 71.2) (mid 154.188579 71.141421) (end 154.13 71) (width 0.146) (layer "In5.Cu") (net 204))
  (arc (start 155.48 71) (mid 155.421421 71.141421) (end 155.28 71.2) (width 0.146) (layer "In5.Cu") (net 204))
  (arc (start 151.379955 68.874832) (mid 151.203675 68.801814) (end 151.027394 68.874831) (width 0.146) (layer "In5.Cu") (net 204))
  (arc (start 158.83 71.2) (mid 158.688579 71.141421) (end 158.63 71) (width 0.146) (layer "In5.Cu") (net 204))
  (arc (start 154.78 70.4) (mid 154.638579 70.458579) (end 154.58 70.6) (width 0.146) (layer "In5.Cu") (net 204))
  (arc (start 156.58 70.4) (mid 156.438579 70.458579) (end 156.38 70.6) (width 0.146) (layer "In5.Cu") (net 204))
  (arc (start 160.18 70.4) (mid 160.038579 70.458579) (end 159.98 70.6) (width 0.146) (layer "In5.Cu") (net 204))
  (arc (start 157.03 71.2) (mid 156.888579 71.141421) (end 156.83 71) (width 0.146) (layer "In5.Cu") (net 204))
  (arc (start 151.382438 69.935) (mid 151.206158 70.008018) (end 151.029877 69.935001) (width 0.146) (layer "In5.Cu") (net 204))
  (arc (start 159.98 71) (mid 159.921421 71.141421) (end 159.78 71.2) (width 0.146) (layer "In5.Cu") (net 204))
  (arc (start 153.23 71) (mid 153.171421 70.858579) (end 153.03 70.8) (width 0.146) (layer "In5.Cu") (net 204))
  (arc (start 150.673838 68.521275) (mid 150.746855 68.344994) (end 150.673837 68.168714) (width 0.146) (layer "In5.Cu") (net 204))
  (arc (start 159.08 71) (mid 159.021421 71.141421) (end 158.88 71.2) (width 0.146) (layer "In5.Cu") (net 204))
  (arc (start 157.73 70.6) (mid 157.671421 70.458579) (end 157.53 70.4) (width 0.146) (layer "In5.Cu") (net 204))
  (arc (start 158.38 70.4) (mid 158.238579 70.458579) (end 158.18 70.6) (width 0.146) (layer "In5.Cu") (net 204))
  (arc (start 160.43 70.6) (mid 160.371421 70.458579) (end 160.23 70.4) (width 0.146) (layer "In5.Cu") (net 204))
  (arc (start 160.63 70.8) (mid 160.488579 70.741421) (end 160.43 70.6) (width 0.146) (layer "In5.Cu") (net 204))
  (arc (start 157.93 71.2) (mid 157.788579 71.141421) (end 157.73 71) (width 0.146) (layer "In5.Cu") (net 204))
  (arc (start 150.321276 69.226399) (mid 150.248258 69.050119) (end 150.321275 68.873838) (width 0.146) (layer "In5.Cu") (net 204))
  (arc (start 158.63 70.6) (mid 158.571421 70.458579) (end 158.43 70.4) (width 0.146) (layer "In5.Cu") (net 204))
  (arc (start 153.43 71.2) (mid 153.288579 71.141421) (end 153.23 71) (width 0.146) (layer "In5.Cu") (net 204))
  (arc (start 153.68 71) (mid 153.621421 71.141421) (end 153.48 71.2) (width 0.146) (layer "In5.Cu") (net 204))
  (arc (start 155.68 70.4) (mid 155.538579 70.458579) (end 155.48 70.6) (width 0.146) (layer "In5.Cu") (net 204))
  (arc (start 158.18 71) (mid 158.121421 71.141421) (end 157.98 71.2) (width 0.146) (layer "In5.Cu") (net 204))
  (arc (start 149.614166 68.166727) (mid 149.687184 67.990447) (end 149.614167 67.814166) (width 0.146) (layer "In5.Cu") (net 204))
  (arc (start 157.28 71) (mid 157.221421 71.141421) (end 157.08 71.2) (width 0.146) (layer "In5.Cu") (net 204))
  (arc (start 157.48 70.4) (mid 157.338579 70.458579) (end 157.28 70.6) (width 0.146) (layer "In5.Cu") (net 204))
  (arc (start 150.674829 69.227392) (mid 150.498548 69.300409) (end 150.322268 69.227391) (width 0.146) (layer "In5.Cu") (net 204))
  (arc (start 154.58 71) (mid 154.521421 71.141421) (end 154.38 71.2) (width 0.146) (layer "In5.Cu") (net 204))
  (arc (start 155.23 71.2) (mid 155.088579 71.141421) (end 155.03 71) (width 0.146) (layer "In5.Cu") (net 204))
  (arc (start 156.38 71) (mid 156.321421 71.141421) (end 156.18 71.2) (width 0.146) (layer "In5.Cu") (net 204))
  (arc (start 149.614166 68.519289) (mid 149.541148 68.343009) (end 149.614165 68.166728) (width 0.146) (layer "In5.Cu") (net 204))
  (arc (start 151.028883 69.934006) (mid 150.955865 69.757726) (end 151.028882 69.581445) (width 0.146) (layer "In5.Cu") (net 204))
  (arc (start 155.03 70.6) (mid 154.971421 70.458579) (end 154.83 70.4) (width 0.146) (layer "In5.Cu") (net 204))
  (arc (start 156.83 70.6) (mid 156.771421 70.458579) (end 156.63 70.4) (width 0.146) (layer "In5.Cu") (net 204))
  (arc (start 150.672845 68.167722) (mid 150.496565 68.094704) (end 150.320284 68.167721) (width 0.146) (layer "In5.Cu") (net 204))
  (arc (start 159.53 70.6) (mid 159.471421 70.458579) (end 159.33 70.4) (width 0.146) (layer "In5.Cu") (net 204))
  (arc (start 149.967719 68.520282) (mid 149.791438 68.593299) (end 149.615158 68.520281) (width 0.146) (layer "In5.Cu") (net 204))
  (arc (start 155.93 70.6) (mid 155.871421 70.458579) (end 155.73 70.4) (width 0.146) (layer "In5.Cu") (net 204))
  (arc (start 151.735 69.935) (mid 151.55872 69.861982) (end 151.382439 69.934999) (width 0.146) (layer "In5.Cu") (net 204))
  (arc (start 151.380948 69.228385) (mid 151.453965 69.052104) (end 151.380947 68.875824) (width 0.146) (layer "In5.Cu") (net 204))
  (arc (start 156.13 71.2) (mid 155.988579 71.141421) (end 155.93 71) (width 0.146) (layer "In5.Cu") (net 204))
  (arc (start 159.73 71.2) (mid 159.588579 71.141421) (end 159.53 71) (width 0.146) (layer "In5.Cu") (net 204))
  (arc (start 153.88 70.4) (mid 153.738579 70.458579) (end 153.68 70.6) (width 0.146) (layer "In5.Cu") (net 204))
  (segment (start 180.136328 80.560008) (end 179.636328 80.060008) (width 0.127) (layer "F.Cu") (net 205))
  (segment (start 145.486328 59.660008) (end 145.486328 60.960008) (width 0.2) (layer "F.Cu") (net 205))
  (via blind (at 145.486328 60.960008) (size 0.5) (drill 0.2) (layers "F.Cu" "In2.Cu") (net 205))
  (via blind (at 179.636328 80.060008) (size 0.5) (drill 0.2) (layers "F.Cu" "In2.Cu") (net 205))
  (segment (start 172.65 75.5) (end 172.65 76.18) (width 0.1) (layer "In2.Cu") (net 205))
  (segment (start 166.89 73.265459) (end 166.89 72.654541) (width 0.16) (layer "In2.Cu") (net 205))
  (segment (start 145.486328 66.786328) (end 145.486328 60.960008) (width 0.16) (layer "In2.Cu") (net 205))
  (segment (start 172.65 76.18) (end 173.2 76.73) (width 0.1) (layer "In2.Cu") (net 205))
  (segment (start 167.89 73.265459) (end 167.89 72.654541) (width 0.16) (layer "In2.Cu") (net 205))
  (segment (start 166.39 72.654541) (end 166.39 73.265459) (width 0.16) (layer "In2.Cu") (net 205))
  (segment (start 165.39 72.654541) (end 165.39 72.71) (width 0.16) (layer "In2.Cu") (net 205))
  (segment (start 167.39 72.654541) (end 167.39 73.265459) (width 0.16) (layer "In2.Cu") (net 205))
  (segment (start 168.39 72.654541) (end 168.39 73.265459) (width 0.16) (layer "In2.Cu") (net 205))
  (segment (start 151.66 72.96) (end 145.486328 66.786328) (width 0.16) (layer "In2.Cu") (net 205))
  (segment (start 169.39 72.71) (end 169.39 73.265459) (width 0.16) (layer "In2.Cu") (net 205))
  (segment (start 173.2 76.73) (end 173.2 79.2) (width 0.1) (layer "In2.Cu") (net 205))
  (segment (start 165.89 73.265459) (end 165.89 72.654541) (width 0.16) (layer "In2.Cu") (net 205))
  (segment (start 174.68 79.86) (end 175.39 80.57) (width 0.1) (layer "In2.Cu") (net 205))
  (segment (start 172.65 75.5) (end 172.65 74.95) (width 0.16) (layer "In2.Cu") (net 205))
  (segment (start 170.66 72.96) (end 170.14 72.96) (width 0.16) (layer "In2.Cu") (net 205))
  (segment (start 168.89 73.265459) (end 168.89 72.654541) (width 0.16) (layer "In2.Cu") (net 205))
  (segment (start 151.66 72.96) (end 165.14 72.96) (width 0.16) (layer "In2.Cu") (net 205))
  (segment (start 179.126336 80.57) (end 179.636328 80.060008) (width 0.1) (layer "In2.Cu") (net 205))
  (segment (start 169.89 72.71) (end 169.89 72.654541) (width 0.16) (layer "In2.Cu") (net 205))
  (segment (start 173.86 79.86) (end 174.68 79.86) (width 0.1) (layer "In2.Cu") (net 205))
  (segment (start 175.39 80.57) (end 179.126336 80.57) (width 0.1) (layer "In2.Cu") (net 205))
  (segment (start 169.39 72.654541) (end 169.39 72.71) (width 0.16) (layer "In2.Cu") (net 205))
  (segment (start 172.65 74.95) (end 170.66 72.96) (width 0.16) (layer "In2.Cu") (net 205))
  (segment (start 173.2 79.2) (end 173.86 79.86) (width 0.1) (layer "In2.Cu") (net 205))
  (arc (start 167.14 73.515459) (mid 166.963223 73.442236) (end 166.89 73.265459) (width 0.16) (layer "In2.Cu") (net 205))
  (arc (start 166.39 73.265459) (mid 166.316777 73.442236) (end 166.14 73.515459) (width 0.16) (layer "In2.Cu") (net 205))
  (arc (start 167.89 72.654541) (mid 167.816777 72.477764) (end 167.64 72.404541) (width 0.16) (layer "In2.Cu") (net 205))
  (arc (start 169.64 72.404541) (mid 169.463223 72.477764) (end 169.39 72.654541) (width 0.16) (layer "In2.Cu") (net 205))
  (arc (start 168.39 73.265459) (mid 168.316777 73.442236) (end 168.14 73.515459) (width 0.16) (layer "In2.Cu") (net 205))
  (arc (start 165.39 72.71) (mid 165.316777 72.886777) (end 165.14 72.96) (width 0.16) (layer "In2.Cu") (net 205))
  (arc (start 165.89 72.654541) (mid 165.816777 72.477764) (end 165.64 72.404541) (width 0.16) (layer "In2.Cu") (net 205))
  (arc (start 169.89 72.654541) (mid 169.816777 72.477764) (end 169.64 72.404541) (width 0.16) (layer "In2.Cu") (net 205))
  (arc (start 166.64 72.404541) (mid 166.463223 72.477764) (end 166.39 72.654541) (width 0.16) (layer "In2.Cu") (net 205))
  (arc (start 167.64 72.404541) (mid 167.463223 72.477764) (end 167.39 72.654541) (width 0.16) (layer "In2.Cu") (net 205))
  (arc (start 166.89 72.654541) (mid 166.816777 72.477764) (end 166.64 72.404541) (width 0.16) (layer "In2.Cu") (net 205))
  (arc (start 169.39 73.265459) (mid 169.316777 73.442236) (end 169.14 73.515459) (width 0.16) (layer "In2.Cu") (net 205))
  (arc (start 167.39 73.265459) (mid 167.316777 73.442236) (end 167.14 73.515459) (width 0.16) (layer "In2.Cu") (net 205))
  (arc (start 168.89 72.654541) (mid 168.816777 72.477764) (end 168.64 72.404541) (width 0.16) (layer "In2.Cu") (net 205))
  (arc (start 168.14 73.515459) (mid 167.963223 73.442236) (end 167.89 73.265459) (width 0.16) (layer "In2.Cu") (net 205))
  (arc (start 165.64 72.404541) (mid 165.463223 72.477764) (end 165.39 72.654541) (width 0.16) (layer "In2.Cu") (net 205))
  (arc (start 170.14 72.96) (mid 169.963223 72.886777) (end 169.89 72.71) (width 0.16) (layer "In2.Cu") (net 205))
  (arc (start 166.14 73.515459) (mid 165.963223 73.442236) (end 165.89 73.265459) (width 0.16) (layer "In2.Cu") (net 205))
  (arc (start 168.64 72.404541) (mid 168.463223 72.477764) (end 168.39 72.654541) (width 0.16) (layer "In2.Cu") (net 205))
  (arc (start 169.14 73.515459) (mid 168.963223 73.442236) (end 168.89 73.265459) (width 0.16) (layer "In2.Cu") (net 205))
  (segment (start 176.636328 81.060008) (end 176.636328 81.0405) (width 0.127) (layer "F.Cu") (net 206))
  (segment (start 136.136328 59.660008) (end 136.136328 60.960008) (width 0.2) (layer "F.Cu") (net 206))
  (segment (start 177.136328 81.560008) (end 176.636328 81.060008) (width 0.127) (layer "F.Cu") (net 206))
  (via blind (at 176.636328 81.0405) (size 0.5) (drill 0.2) (layers "F.Cu" "In5.Cu") (net 206))
  (via blind (at 136.136328 60.960008) (size 0.5) (drill 0.2) (layers "F.Cu" "In5.Cu") (net 206))
  (segment (start 162.919286 79.796825) (end 162.954643 79.832182) (width 0.146) (layer "In5.Cu") (net 206))
  (segment (start 169.25 80.8) (end 169.93 81.48) (width 0.09) (layer "In5.Cu") (net 206))
  (segment (start 162.388951 79.513978) (end 162.141466 79.761468) (width 0.146) (layer "In5.Cu") (net 206))
  (segment (start 158.568497 75.7) (end 158.745741 75.877244) (width 0.146) (layer "In5.Cu") (net 206))
  (segment (start 162.707155 80.574645) (end 162.742511 80.610001) (width 0.146) (layer "In5.Cu") (net 206))
  (segment (start 136.136328 64.936328) (end 146.9 75.7) (width 0.146) (layer "In5.Cu") (net 206))
  (segment (start 169.1 80.8) (end 169.25 80.8) (width 0.09) (layer "In5.Cu") (net 206))
  (segment (start 161.858618 79.478619) (end 162.106108 79.231134) (width 0.146) (layer "In5.Cu") (net 206))
  (segment (start 161.540417 78.665443) (end 161.540416 78.665443) (width 0.146) (layer "In5.Cu") (net 206))
  (segment (start 158.745741 76.584349) (end 158.74574 76.584351) (width 0.146) (layer "In5.Cu") (net 206))
  (segment (start 161.010084 78.630086) (end 161.010083 78.630084) (width 0.146) (layer "In5.Cu") (net 206))
  (segment (start 161.010083 78.877572) (end 161.04544 78.912929) (width 0.146) (layer "In5.Cu") (net 206))
  (segment (start 162.141466 79.761468) (end 162.141465 79.761466) (width 0.146) (layer "In5.Cu") (net 206))
  (segment (start 160.61 77.741503) (end 160.61 77.982514) (width 0.146) (layer "In5.Cu") (net 206))
  (segment (start 161.575774 79.443263) (end 161.611131 79.47862) (width 0.146) (layer "In5.Cu") (net 206))
  (segment (start 163.43 80.8) (end 169.1 80.8) (width 0.146) (layer "In5.Cu") (net 206))
  (segment (start 174.97 81.48) (end 175.4095 81.0405) (width 0.09) (layer "In5.Cu") (net 206))
  (segment (start 162.989999 80.610001) (end 162.99 80.61) (width 0.146) (layer "In5.Cu") (net 206))
  (segment (start 162.707154 80.327157) (end 162.707155 80.327157) (width 0.146) (layer "In5.Cu") (net 206))
  (segment (start 162.106108 79.231134) (end 162.106107 79.231134) (width 0.146) (layer "In5.Cu") (net 206))
  (segment (start 162.353595 79.231134) (end 162.388952 79.266491) (width 0.146) (layer "In5.Cu") (net 206))
  (segment (start 162.424309 80.04431) (end 162.671799 79.796825) (width 0.146) (layer "In5.Cu") (net 206))
  (segment (start 159.099294 76.584351) (end 159.099296 76.58435) (width 0.146) (layer "In5.Cu") (net 206))
  (segment (start 161.575775 79.195777) (end 161.575774 79.195775) (width 0.146) (layer "In5.Cu") (net 206))
  (segment (start 163.240001 80.610001) (end 163.43 80.8) (width 0.146) (layer "In5.Cu") (net 206))
  (segment (start 161.82326 78.948287) (end 161.575775 79.195777) (width 0.146) (layer "In5.Cu") (net 206))
  (segment (start 160.61 77.982514) (end 160.727238 78.099752) (width 0.146) (layer "In5.Cu") (net 206))
  (segment (start 162.954642 80.079669) (end 162.707154 80.327157) (width 0.146) (layer "In5.Cu") (net 206))
  (segment (start 160.974726 78.099752) (end 160.974725 78.099752) (width 0.146) (layer "In5.Cu") (net 206))
  (segment (start 161.787904 78.665443) (end 161.823261 78.7008) (width 0.146) (layer "In5.Cu") (net 206))
  (segment (start 175.4095 81.0405) (end 176.636328 81.0405) (width 0.09) (layer "In5.Cu") (net 206))
  (segment (start 161.257569 78.382596) (end 161.010084 78.630086) (width 0.146) (layer "In5.Cu") (net 206))
  (segment (start 136.136328 60.960008) (end 136.136328 64.936328) (width 0.146) (layer "In5.Cu") (net 206))
  (segment (start 161.222213 78.099752) (end 161.25757 78.135109) (width 0.146) (layer "In5.Cu") (net 206))
  (segment (start 160.089243 77.220747) (end 160.61 77.741503) (width 0.146) (layer "In5.Cu") (net 206))
  (segment (start 158.745741 75.877244) (end 158.745741 75.877241) (width 0.146) (layer "In5.Cu") (net 206))
  (segment (start 146.9 75.7) (end 158.568497 75.7) (width 0.146) (layer "In5.Cu") (net 206))
  (segment (start 159.686454 77.305338) (end 159.771045 77.220746) (width 0.146) (layer "In5.Cu") (net 206))
  (segment (start 162.671799 79.796825) (end 162.671798 79.796825) (width 0.146) (layer "In5.Cu") (net 206))
  (segment (start 161.292927 78.912928) (end 161.540417 78.665443) (width 0.146) (layer "In5.Cu") (net 206))
  (segment (start 162.141465 80.008954) (end 162.176822 80.044311) (width 0.146) (layer "In5.Cu") (net 206))
  (segment (start 169.93 81.48) (end 174.97 81.48) (width 0.09) (layer "In5.Cu") (net 206))
  (segment (start 159.452848 76.902549) (end 159.368256 76.98714) (width 0.146) (layer "In5.Cu") (net 206))
  (segment (start 158.745741 76.230795) (end 158.74574 76.230796) (width 0.146) (layer "In5.Cu") (net 206))
  (segment (start 159.452847 76.902549) (end 159.452848 76.902549) (width 0.146) (layer "In5.Cu") (net 206))
  (segment (start 163.237487 80.610001) (end 163.240001 80.610001) (width 0.146) (layer "In5.Cu") (net 206))
  (segment (start 160.089243 77.220746) (end 160.089243 77.220747) (width 0.146) (layer "In5.Cu") (net 206))
  (arc (start 161.010083 78.630084) (mid 160.958827 78.753828) (end 161.010083 78.877572) (width 0.146) (layer "In5.Cu") (net 206))
  (arc (start 162.954643 79.832182) (mid 163.005899 79.955926) (end 162.954642 80.079669) (width 0.146) (layer "In5.Cu") (net 206))
  (arc (start 162.99 80.61) (mid 163.113744 80.558744) (end 163.237487 80.610001) (width 0.146) (layer "In5.Cu") (net 206))
  (arc (start 161.540416 78.665443) (mid 161.66416 78.614187) (end 161.787904 78.665443) (width 0.146) (layer "In5.Cu") (net 206))
  (arc (start 161.575774 79.195775) (mid 161.524518 79.319519) (end 161.575774 79.443263) (width 0.146) (layer "In5.Cu") (net 206))
  (arc (start 159.368256 76.98714) (mid 159.302355 77.146239) (end 159.368256 77.305338) (width 0.146) (layer "In5.Cu") (net 206))
  (arc (start 162.671798 79.796825) (mid 162.795542 79.745569) (end 162.919286 79.796825) (width 0.146) (layer "In5.Cu") (net 206))
  (arc (start 159.771045 77.220746) (mid 159.930144 77.154845) (end 160.089243 77.220746) (width 0.146) (layer "In5.Cu") (net 206))
  (arc (start 162.176822 80.044311) (mid 162.300566 80.095567) (end 162.424309 80.04431) (width 0.146) (layer "In5.Cu") (net 206))
  (arc (start 162.141465 79.761466) (mid 162.090209 79.88521) (end 162.141465 80.008954) (width 0.146) (layer "In5.Cu") (net 206))
  (arc (start 159.452849 76.584351) (mid 159.518749 76.74345) (end 159.452847 76.902549) (width 0.146) (layer "In5.Cu") (net 206))
  (arc (start 162.388952 79.266491) (mid 162.440208 79.390235) (end 162.388951 79.513978) (width 0.146) (layer "In5.Cu") (net 206))
  (arc (start 162.742511 80.610001) (mid 162.866255 80.661257) (end 162.989999 80.610001) (width 0.146) (layer "In5.Cu") (net 206))
  (arc (start 162.106107 79.231134) (mid 162.229851 79.179878) (end 162.353595 79.231134) (width 0.146) (layer "In5.Cu") (net 206))
  (arc (start 158.74574 76.584351) (mid 158.922519 76.657574) (end 159.099294 76.584351) (width 0.146) (layer "In5.Cu") (net 206))
  (arc (start 159.368256 77.305338) (mid 159.527355 77.371239) (end 159.686454 77.305338) (width 0.146) (layer "In5.Cu") (net 206))
  (arc (start 161.25757 78.135109) (mid 161.308826 78.258853) (end 161.257569 78.382596) (width 0.146) (layer "In5.Cu") (net 206))
  (arc (start 159.099296 76.58435) (mid 159.276073 76.511127) (end 159.452849 76.584351) (width 0.146) (layer "In5.Cu") (net 206))
  (arc (start 161.04544 78.912929) (mid 161.169184 78.964185) (end 161.292927 78.912928) (width 0.146) (layer "In5.Cu") (net 206))
  (arc (start 158.745741 75.877241) (mid 158.818964 76.054018) (end 158.745741 76.230795) (width 0.146) (layer "In5.Cu") (net 206))
  (arc (start 162.707155 80.327157) (mid 162.655899 80.450901) (end 162.707155 80.574645) (width 0.146) (layer "In5.Cu") (net 206))
  (arc (start 160.974725 78.099752) (mid 161.098469 78.048496) (end 161.222213 78.099752) (width 0.146) (layer "In5.Cu") (net 206))
  (arc (start 160.727238 78.099752) (mid 160.850982 78.151008) (end 160.974726 78.099752) (width 0.146) (layer "In5.Cu") (net 206))
  (arc (start 161.611131 79.47862) (mid 161.734875 79.529876) (end 161.858618 79.478619) (width 0.146) (layer "In5.Cu") (net 206))
  (arc (start 158.74574 76.230796) (mid 158.672517 76.407573) (end 158.745741 76.584349) (width 0.146) (layer "In5.Cu") (net 206))
  (arc (start 161.823261 78.7008) (mid 161.874517 78.824544) (end 161.82326 78.948287) (width 0.146) (layer "In5.Cu") (net 206))
  (segment (start 184.136328 79.560008) (end 183.636328 79.060008) (width 0.127) (layer "F.Cu") (net 207))
  (segment (start 167.586328 59.660008) (end 167.586328 60.960008) (width 0.2) (layer "F.Cu") (net 207))
  (segment (start 183.636328 79.060008) (end 183.636328 79.0405) (width 0.127) (layer "F.Cu") (net 207))
  (via (at 167.586328 60.960008) (size 0.5) (drill 0.2) (layers "F.Cu" "B.Cu") (net 207))
  (via (at 183.636328 79.0405) (size 0.5) (drill 0.2) (layers "F.Cu" "B.Cu") (net 207))
  (segment (start 177.285 65.666616) (end 177.285 66.233384) (width 0.16) (layer "In9.Cu") (net 207))
  (segment (start 173.17 65.95) (end 176.61 65.95) (width 0.16) (layer "In9.Cu") (net 207))
  (segment (start 180.690813 67.11819) (end 180.690813 67.118191) (width 0.16) (layer "In9.Cu") (net 207))
  (segment (start 182.9 75.55) (end 182.9 69.8) (width 0.16) (layer "In9.Cu") (net 207))
  (segment (start 182.9 69.8) (end 181.25 68.15) (width 0.16) (layer "In9.Cu") (net 207))
  (segment (start 169.17 61.95) (end 168 61.95) (width 0.16) (layer "In9.Cu") (net 207))
  (segment (start 167.59 60.96368) (end 167.586328 60.960008) (width 0.16) (layer "In9.Cu") (net 207))
  (segment (start 179.263588 66.636211) (end 179.26359 66.636212) (width 0.16) (layer "In9.Cu") (net 207))
  (segment (start 179.899991 67.272613) (end 180.372611 66.799988) (width 0.16) (layer "In9.Cu") (net 207))
  (segment (start 179.26359 66.636212) (end 179.340801 66.558998) (width 0.16) (layer "In9.Cu") (net 207))
  (segment (start 178.635 65.725) (end 178.635 65.666616) (width 0.16) (layer "In9.Cu") (net 207))
  (segment (start 180.9318 68.149999) (end 180.854588 68.227212) (width 0.16) (layer "In9.Cu") (net 207))
  (segment (start 173.17 65.95) (end 169.17 61.95) (width 0.16) (layer "In9.Cu") (net 207))
  (segment (start 180.931801 68.149999) (end 180.9318 68.149999) (width 0.16) (layer "In9.Cu") (net 207))
  (segment (start 179.05 65.95) (end 178.86 65.95) (width 0.16) (layer "In9.Cu") (net 207))
  (segment (start 167.59 61.54) (end 167.59 60.96368) (width 0.16) (layer "In9.Cu") (net 207))
  (segment (start 168 61.95) (end 167.59 61.54) (width 0.16) (layer "In9.Cu") (net 207))
  (segment (start 182.9 77.6) (end 183.57 78.27) (width 0.1) (layer "In9.Cu") (net 207))
  (segment (start 179.340801 66.2408) (end 179.05 65.95) (width 0.16) (layer "In9.Cu") (net 207))
  (segment (start 183.57 78.27) (end 183.57 78.974172) (width 0.1) (layer "In9.Cu") (net 207))
  (segment (start 177.735 66.233384) (end 177.735 65.666616) (width 0.16) (layer "In9.Cu") (net 207))
  (segment (start 180.536389 67.909013) (end 180.536389 67.909012) (width 0.16) (layer "In9.Cu") (net 207))
  (segment (start 180.536389 67.909012) (end 181.009012 67.436389) (width 0.16) (layer "In9.Cu") (net 207))
  (segment (start 180.690813 67.118191) (end 180.218188 67.590811) (width 0.16) (layer "In9.Cu") (net 207))
  (segment (start 178.185 65.725) (end 178.185 66.233384) (width 0.16) (layer "In9.Cu") (net 207))
  (segment (start 178.185 65.666616) (end 178.185 65.725) (width 0.16) (layer "In9.Cu") (net 207))
  (segment (start 182.9 75.55) (end 182.9 77.6) (width 0.1) (layer "In9.Cu") (net 207))
  (segment (start 180.054412 66.48179) (end 179.581787 66.95441) (width 0.16) (layer "In9.Cu") (net 207))
  (segment (start 176.835 66.233384) (end 176.835 66.175) (width 0.16) (layer "In9.Cu") (net 207))
  (segment (start 183.57 78.974172) (end 183.636328 79.0405) (width 0.1) (layer "In9.Cu") (net 207))
  (segment (start 179.899989 67.272612) (end 179.899991 67.272613) (width 0.16) (layer "In9.Cu") (net 207))
  (segment (start 180.054412 66.481789) (end 180.054412 66.48179) (width 0.16) (layer "In9.Cu") (net 207))
  (arc (start 178.635 65.666616) (mid 178.569099 65.507517) (end 178.41 65.441616) (width 0.16) (layer "In9.Cu") (net 207))
  (arc (start 179.89999 67.590811) (mid 179.834089 67.431713) (end 179.899989 67.272612) (width 0.16) (layer "In9.Cu") (net 207))
  (arc (start 179.581787 66.95441) (mid 179.422688 67.020311) (end 179.263589 66.95441) (width 0.16) (layer "In9.Cu") (net 207))
  (arc (start 178.41 65.441616) (mid 178.250901 65.507517) (end 178.185 65.666616) (width 0.16) (layer "In9.Cu") (net 207))
  (arc (start 181.25 68.15) (mid 181.0909 68.084097) (end 180.931801 68.149999) (width 0.16) (layer "In9.Cu") (net 207))
  (arc (start 178.86 65.95) (mid 178.700901 65.884099) (end 178.635 65.725) (width 0.16) (layer "In9.Cu") (net 207))
  (arc (start 177.96 66.458384) (mid 177.800901 66.392483) (end 177.735 66.233384) (width 0.16) (layer "In9.Cu") (net 207))
  (arc (start 177.06 66.458384) (mid 176.900901 66.392483) (end 176.835 66.233384) (width 0.16) (layer "In9.Cu") (net 207))
  (arc (start 181.009012 67.118191) (mid 180.849913 67.052289) (end 180.690813 67.11819) (width 0.16) (layer "In9.Cu") (net 207))
  (arc (start 180.372611 66.799988) (mid 180.438512 66.640889) (end 180.372611 66.48179) (width 0.16) (layer "In9.Cu") (net 207))
  (arc (start 179.340801 66.558998) (mid 179.406702 66.399899) (end 179.340801 66.2408) (width 0.16) (layer "In9.Cu") (net 207))
  (arc (start 180.372611 66.48179) (mid 180.213512 66.415888) (end 180.054412 66.481789) (width 0.16) (layer "In9.Cu") (net 207))
  (arc (start 177.735 65.666616) (mid 177.669099 65.507517) (end 177.51 65.441616) (width 0.16) (layer "In9.Cu") (net 207))
  (arc (start 178.185 66.233384) (mid 178.119099 66.392483) (end 177.96 66.458384) (width 0.16) (layer "In9.Cu") (net 207))
  (arc (start 181.009012 67.436389) (mid 181.074913 67.27729) (end 181.009012 67.118191) (width 0.16) (layer "In9.Cu") (net 207))
  (arc (start 180.854588 68.227212) (mid 180.695489 68.293113) (end 180.53639 68.227212) (width 0.16) (layer "In9.Cu") (net 207))
  (arc (start 180.218188 67.590811) (mid 180.059089 67.656712) (end 179.89999 67.590811) (width 0.16) (layer "In9.Cu") (net 207))
  (arc (start 177.51 65.441616) (mid 177.350901 65.507517) (end 177.285 65.666616) (width 0.16) (layer "In9.Cu") (net 207))
  (arc (start 176.835 66.175) (mid 176.769099 66.015901) (end 176.61 65.95) (width 0.16) (layer "In9.Cu") (net 207))
  (arc (start 179.263589 66.95441) (mid 179.197688 66.795312) (end 179.263588 66.636211) (width 0.16) (layer "In9.Cu") (net 207))
  (arc (start 180.53639 68.227212) (mid 180.470487 68.068112) (end 180.536389 67.909013) (width 0.16) (layer "In9.Cu") (net 207))
  (arc (start 177.285 66.233384) (mid 177.219099 66.392483) (end 177.06 66.458384) (width 0.16) (layer "In9.Cu") (net 207))
  (segment (start 185.136328 83.560008) (end 184.636328 83.060008) (width 0.127) (layer "F.Cu") (net 208))
  (segment (start 184.636328 83.060008) (end 184.636328 83.0405) (width 0.127) (layer "F.Cu") (net 208))
  (segment (start 173.536328 59.660008) (end 173.536328 60.960008) (width 0.2) (layer "F.Cu") (net 208))
  (via (at 173.536328 60.960008) (size 0.5) (drill 0.2) (layers "F.Cu" "B.Cu") (net 208))
  (via (at 184.636328 83.0405) (size 0.5) (drill 0.2) (layers "F.Cu" "B.Cu") (net 208))
  (segment (start 185.7 75.5) (end 185.7 76.1) (width 0.1) (layer "In9.Cu") (net 208))
  (segment (start 182.361617 65.438182) (end 182.802826 64.996971) (width 0.16) (layer "In9.Cu") (net 208))
  (segment (start 185.675 70.175) (end 186.525 70.175) (width 0.16) (layer "In9.Cu") (net 208))
  (segment (start 181.275 63.025) (end 180.6 62.35) (width 0.16) (layer "In9.Cu") (net 208))
  (segment (start 185.1 79.5) (end 184.95 79.65) (width 0.1) (layer "In9.Cu") (net 208))
  (segment (start 185.675 69.725) (end 186.525 69.725) (width 0.16) (layer "In9.Cu") (net 208))
  (segment (start 184.95 81.55) (end 185.2 81.8) (width 0.1) (layer "In9.Cu") (net 208))
  (segment (start 184.0318 66.949999) (end 183.952617 67.029183) (width 0.16) (layer "In9.Cu") (net 208))
  (segment (start 185.7 76.1) (end 185.1 76.7) (width 0.1) (layer "In9.Cu") (net 208))
  (segment (start 185.2 81.8) (end 185.2 82.476828) (width 0.1) (layer "In9.Cu") (net 208))
  (segment (start 182.998018 66.074584) (end 182.998018 66.074583) (width 0.16) (layer "In9.Cu") (net 208))
  (segment (start 182.998018 66.074583) (end 183.439227 65.633372) (width 0.16) (layer "In9.Cu") (net 208))
  (segment (start 185.1 76.7) (end 185.1 79.5) (width 0.1) (layer "In9.Cu") (net 208))
  (segment (start 185.2 82.476828) (end 184.636328 83.0405) (width 0.1) (layer "In9.Cu") (net 208))
  (segment (start 184.95 79.65) (end 184.95 81.55) (width 0.1) (layer "In9.Cu") (net 208))
  (segment (start 182.361617 65.438183) (end 182.361617 65.438182) (width 0.16) (layer "In9.Cu") (net 208))
  (segment (start 181.275 63.875) (end 181.275 63.025) (width 0.16) (layer "In9.Cu") (net 208))
  (segment (start 173.536328 61.536328) (end 173.536328 60.960008) (width 0.16) (layer "In9.Cu") (net 208))
  (segment (start 182.484627 64.678773) (end 182.440798 64.722601) (width 0.16) (layer "In9.Cu") (net 208))
  (segment (start 180.6 62.35) (end 174.35 62.35) (width 0.16) (layer "In9.Cu") (net 208))
  (segment (start 182.998019 66.392782) (end 182.998019 66.392783) (width 0.16) (layer "In9.Cu") (net 208))
  (segment (start 184.031801 66.949999) (end 184.0318 66.949999) (width 0.16) (layer "In9.Cu") (net 208))
  (segment (start 186.525 69.275) (end 186.325 69.275) (width 0.16) (layer "In9.Cu") (net 208))
  (segment (start 182.361618 65.756381) (end 182.361618 65.756382) (width 0.16) (layer "In9.Cu") (net 208))
  (segment (start 183.634418 66.710983) (end 184.075628 66.269773) (width 0.16) (layer "In9.Cu") (net 208))
  (segment (start 182.484627 64.678772) (end 182.484627 64.678773) (width 0.16) (layer "In9.Cu") (net 208))
  (segment (start 185.7 75.5) (end 185.7 71.9) (width 0.16) (layer "In9.Cu") (net 208))
  (segment (start 183.121028 65.315173) (end 183.121028 65.315174) (width 0.16) (layer "In9.Cu") (net 208))
  (segment (start 185.7 71.9) (end 186.1 71.5) (width 0.16) (layer "In9.Cu") (net 208))
  (segment (start 183.757429 65.951575) (end 183.316217 66.392782) (width 0.16) (layer "In9.Cu") (net 208))
  (segment (start 186.1 69.05) (end 186.1 68.7) (width 0.16) (layer "In9.Cu") (net 208))
  (segment (start 183.757429 65.951574) (end 183.757429 65.951575) (width 0.16) (layer "In9.Cu") (net 208))
  (segment (start 185.875 71.075) (end 185.675 71.075) (width 0.16) (layer "In9.Cu") (net 208))
  (segment (start 186.1 71.5) (end 186.1 71.3) (width 0.16) (layer "In9.Cu") (net 208))
  (segment (start 185.675 70.625) (end 186.525 70.625) (width 0.16) (layer "In9.Cu") (net 208))
  (segment (start 182.1226 64.722601) (end 181.275 63.875) (width 0.16) (layer "In9.Cu") (net 208))
  (segment (start 186.1 68.7) (end 184.35 66.95) (width 0.16) (layer "In9.Cu") (net 208))
  (segment (start 174.35 62.35) (end 173.536328 61.536328) (width 0.16) (layer "In9.Cu") (net 208))
  (segment (start 183.121028 65.315174) (end 182.679816 65.756381) (width 0.16) (layer "In9.Cu") (net 208))
  (segment (start 183.634418 66.710984) (end 183.634418 66.710983) (width 0.16) (layer "In9.Cu") (net 208))
  (arc (start 182.998019 66.392783) (mid 182.932116 66.233683) (end 182.998018 66.074584) (width 0.16) (layer "In9.Cu") (net 208))
  (arc (start 185.45 69.95) (mid 185.515901 69.790901) (end 185.675 69.725) (width 0.16) (layer "In9.Cu") (net 208))
  (arc (start 186.75 69.5) (mid 186.684099 69.340901) (end 186.525 69.275) (width 0.16) (layer "In9.Cu") (net 208))
  (arc (start 186.1 71.3) (mid 186.034099 71.140901) (end 185.875 71.075) (width 0.16) (layer "In9.Cu") (net 208))
  (arc (start 182.679816 65.756381) (mid 182.520717 65.822282) (end 182.361618 65.756381) (width 0.16) (layer "In9.Cu") (net 208))
  (arc (start 182.361618 65.756382) (mid 182.295715 65.597282) (end 182.361617 65.438183) (width 0.16) (layer "In9.Cu") (net 208))
  (arc (start 186.75 70.4) (mid 186.684099 70.240901) (end 186.525 70.175) (width 0.16) (layer "In9.Cu") (net 208))
  (arc (start 185.675 71.075) (mid 185.515901 71.009099) (end 185.45 70.85) (width 0.16) (layer "In9.Cu") (net 208))
  (arc (start 185.45 70.85) (mid 185.515901 70.690901) (end 185.675 70.625) (width 0.16) (layer "In9.Cu") (net 208))
  (arc (start 182.440798 64.722601) (mid 182.281699 64.788502) (end 182.1226 64.722601) (width 0.16) (layer "In9.Cu") (net 208))
  (arc (start 184.075628 66.269773) (mid 184.141529 66.110674) (end 184.075628 65.951575) (width 0.16) (layer "In9.Cu") (net 208))
  (arc (start 184.35 66.95) (mid 184.1909 66.884097) (end 184.031801 66.949999) (width 0.16) (layer "In9.Cu") (net 208))
  (arc (start 183.439227 65.315174) (mid 183.280128 65.249272) (end 183.121028 65.315173) (width 0.16) (layer "In9.Cu") (net 208))
  (arc (start 186.325 69.275) (mid 186.165901 69.209099) (end 186.1 69.05) (width 0.16) (layer "In9.Cu") (net 208))
  (arc (start 183.316217 66.392782) (mid 183.157118 66.458683) (end 182.998019 66.392782) (width 0.16) (layer "In9.Cu") (net 208))
  (arc (start 184.075628 65.951575) (mid 183.916529 65.885673) (end 183.757429 65.951574) (width 0.16) (layer "In9.Cu") (net 208))
  (arc (start 183.952617 67.029183) (mid 183.793518 67.095084) (end 183.634419 67.029183) (width 0.16) (layer "In9.Cu") (net 208))
  (arc (start 186.525 70.625) (mid 186.684099 70.559099) (end 186.75 70.4) (width 0.16) (layer "In9.Cu") (net 208))
  (arc (start 183.634419 67.029183) (mid 183.568516 66.870083) (end 183.634418 66.710984) (width 0.16) (layer "In9.Cu") (net 208))
  (arc (start 186.525 69.725) (mid 186.684099 69.659099) (end 186.75 69.5) (width 0.16) (layer "In9.Cu") (net 208))
  (arc (start 182.802826 64.678773) (mid 182.643727 64.612871) (end 182.484627 64.678772) (width 0.16) (layer "In9.Cu") (net 208))
  (arc (start 182.802826 64.996971) (mid 182.868727 64.837872) (end 182.802826 64.678773) (width 0.16) (layer "In9.Cu") (net 208))
  (arc (start 185.675 70.175) (mid 185.515901 70.109099) (end 185.45 69.95) (width 0.16) (layer "In9.Cu") (net 208))
  (arc (start 183.439227 65.633372) (mid 183.505128 65.474273) (end 183.439227 65.315174) (width 0.16) (layer "In9.Cu") (net 208))
  (segment (start 187.136328 83.560008) (end 186.636328 83.060008) (width 0.127) (layer "F.Cu") (net 209))
  (segment (start 169.286328 59.660008) (end 169.286328 60.960008) (width 0.2) (layer "F.Cu") (net 209))
  (via (at 169.286328 60.960008) (size 0.5) (drill 0.2) (layers "F.Cu" "B.Cu") (net 209))
  (via blind (at 186.636328 83.060008) (size 0.5) (drill 0.2) (layers "F.Cu" "In5.Cu") (net 209))
  (segment (start 185.17 75.56) (end 185.17 68.37) (width 0.146) (layer "In5.Cu") (net 209))
  (segment (start 182.417989 66.045801) (end 182.41799 66.0458) (width 0.146) (layer "In5.Cu") (net 209))
  (segment (start 183.125098 66.75291) (end 183.125099 66.752909) (width 0.146) (layer "In5.Cu") (net 209))
  (segment (start 169.286328 60.913672) (end 169.286328 60.960008) (width 0.146) (layer "In5.Cu") (net 209))
  (segment (start 184.613572 67.385765) (end 184.185763 67.813573) (width 0.146) (layer "In5.Cu") (net 209))
  (segment (start 181.748009 64.948008) (end 181.748008 64.94801) (width 0.146) (layer "In5.Cu") (net 209))
  (segment (start 184.929999 67.776446) (end 184.967126 67.739318) (width 0.146) (layer "In5.Cu") (net 209))
  (segment (start 186.636328 83.060008) (end 185.860008 83.060008) (width 0.09) (layer "In5.Cu") (net 209))
  (segment (start 185.12 82.32) (end 185.12 76.08) (width 0.09) (layer "In5.Cu") (net 209))
  (segment (start 183.832208 67.460018) (end 184.260017 67.032208) (width 0.146) (layer "In5.Cu") (net 209))
  (segment (start 184.613573 67.385764) (end 184.613572 67.385765) (width 0.146) (layer "In5.Cu") (net 209))
  (segment (start 184.967126 67.385764) (end 184.967126 67.385765) (width 0.146) (layer "In5.Cu") (net 209))
  (segment (start 173.05 61.55) (end 171.8 60.3) (width 0.146) (layer "In5.Cu") (net 209))
  (segment (start 181.710881 65.338691) (end 181.748009 65.301562) (width 0.146) (layer "In5.Cu") (net 209))
  (segment (start 185.17 76.03) (end 185.17 75.56) (width 0.09) (layer "In5.Cu") (net 209))
  (segment (start 182.492245 65.264436) (end 182.492244 65.264437) (width 0.146) (layer "In5.Cu") (net 209))
  (segment (start 183.832207 67.460019) (end 183.832208 67.460018) (width 0.146) (layer "In5.Cu") (net 209))
  (segment (start 171.8 60.3) (end 169.9 60.3) (width 0.146) (layer "In5.Cu") (net 209))
  (segment (start 183.199353 65.971546) (end 182.771545 66.399355) (width 0.146) (layer "In5.Cu") (net 209))
  (segment (start 176.45 61.075) (end 175.975 61.55) (width 0.146) (layer "In5.Cu") (net 209))
  (segment (start 185.860008 83.060008) (end 185.12 82.32) (width 0.09) (layer "In5.Cu") (net 209))
  (segment (start 181.31 64.510001) (end 181.31 64.06) (width 0.146) (layer "In5.Cu") (net 209))
  (segment (start 175.975 61.55) (end 173.05 61.55) (width 0.146) (layer "In5.Cu") (net 209))
  (segment (start 183.125099 66.752909) (end 183.552908 66.325099) (width 0.146) (layer "In5.Cu") (net 209))
  (segment (start 182.492244 65.264437) (end 182.064436 65.692246) (width 0.146) (layer "In5.Cu") (net 209))
  (segment (start 184.929999 67.776447) (end 184.929999 67.776446) (width 0.146) (layer "In5.Cu") (net 209))
  (segment (start 181.748008 64.94801) (end 181.31 64.510001) (width 0.146) (layer "In5.Cu") (net 209))
  (segment (start 183.199354 65.971545) (end 183.199353 65.971546) (width 0.146) (layer "In5.Cu") (net 209))
  (segment (start 185.12 76.08) (end 185.17 76.03) (width 0.09) (layer "In5.Cu") (net 209))
  (segment (start 169.9 60.3) (end 169.286328 60.913672) (width 0.146) (layer "In5.Cu") (net 209))
  (segment (start 181.71088 65.338692) (end 181.710881 65.338691) (width 0.146) (layer "In5.Cu") (net 209))
  (segment (start 178.325 61.075) (end 176.45 61.075) (width 0.146) (layer "In5.Cu") (net 209))
  (segment (start 185.17 68.37) (end 184.93 68.13) (width 0.146) (layer "In5.Cu") (net 209))
  (segment (start 182.41799 66.0458) (end 182.845799 65.61799) (width 0.146) (layer "In5.Cu") (net 209))
  (segment (start 181.31 64.06) (end 178.325 61.075) (width 0.146) (layer "In5.Cu") (net 209))
  (segment (start 183.906463 66.678654) (end 183.906462 66.678655) (width 0.146) (layer "In5.Cu") (net 209))
  (segment (start 183.906462 66.678655) (end 183.478654 67.106464) (width 0.146) (layer "In5.Cu") (net 209))
  (arc (start 184.260017 67.032208) (mid 184.33324 66.855431) (end 184.260016 66.678655) (width 0.146) (layer "In5.Cu") (net 209))
  (arc (start 182.064436 65.692246) (mid 181.887659 65.765469) (end 181.710883 65.692245) (width 0.146) (layer "In5.Cu") (net 209))
  (arc (start 183.125101 67.106463) (mid 183.051877 66.929687) (end 183.125098 66.75291) (width 0.146) (layer "In5.Cu") (net 209))
  (arc (start 182.771545 66.399355) (mid 182.594768 66.472578) (end 182.417992 66.399354) (width 0.146) (layer "In5.Cu") (net 209))
  (arc (start 184.260016 66.678655) (mid 184.08324 66.605431) (end 183.906463 66.678654) (width 0.146) (layer "In5.Cu") (net 209))
  (arc (start 183.478654 67.106464) (mid 183.301877 67.179687) (end 183.125101 67.106463) (width 0.146) (layer "In5.Cu") (net 209))
  (arc (start 184.185763 67.813573) (mid 184.008986 67.886796) (end 183.83221 67.813572) (width 0.146) (layer "In5.Cu") (net 209))
  (arc (start 183.552908 66.325099) (mid 183.626131 66.148322) (end 183.552907 65.971546) (width 0.146) (layer "In5.Cu") (net 209))
  (arc (start 181.748009 65.301562) (mid 181.821232 65.124785) (end 181.748009 64.948008) (width 0.146) (layer "In5.Cu") (net 209))
  (arc (start 181.710883 65.692245) (mid 181.637659 65.515469) (end 181.71088 65.338692) (width 0.146) (layer "In5.Cu") (net 209))
  (arc (start 184.967126 67.739318) (mid 185.040349 67.562541) (end 184.967126 67.385764) (width 0.146) (layer "In5.Cu") (net 209))
  (arc (start 182.845798 65.264437) (mid 182.669022 65.191213) (end 182.492245 65.264436) (width 0.146) (layer "In5.Cu") (net 209))
  (arc (start 183.552907 65.971546) (mid 183.376131 65.898322) (end 183.199354 65.971545) (width 0.146) (layer "In5.Cu") (net 209))
  (arc (start 184.967126 67.385765) (mid 184.79035 67.312541) (end 184.613573 67.385764) (width 0.146) (layer "In5.Cu") (net 209))
  (arc (start 182.845799 65.61799) (mid 182.919022 65.441213) (end 182.845798 65.264437) (width 0.146) (layer "In5.Cu") (net 209))
  (arc (start 183.83221 67.813572) (mid 183.758986 67.636796) (end 183.832207 67.460019) (width 0.146) (layer "In5.Cu") (net 209))
  (arc (start 182.417992 66.399354) (mid 182.344768 66.222578) (end 182.417989 66.045801) (width 0.146) (layer "In5.Cu") (net 209))
  (arc (start 184.93 68.13) (mid 184.856776 67.953224) (end 184.929999 67.776447) (width 0.146) (layer "In5.Cu") (net 209))
  (segment (start 184.136328 82.560008) (end 184.636328 82.060008) (width 0.127) (layer "F.Cu") (net 210))
  (segment (start 170.986328 59.660008) (end 170.986328 60.960008) (width 0.2) (layer "F.Cu") (net 210))
  (segment (start 184.636328 82.060008) (end 184.655836 82.060008) (width 0.127) (layer "F.Cu") (net 210))
  (via (at 170.986328 60.960008) (size 0.5) (drill 0.2) (layers "F.Cu" "B.Cu") (net 210))
  (via (at 184.655836 82.060008) (size 0.5) (drill 0.2) (layers "F.Cu" "B.Cu") (net 210))
  (segment (start 182.158236 68.036543) (end 182.158238 68.036544) (width 0.16) (layer "In9.Cu") (net 210))
  (segment (start 181.92009 67.320091) (end 179.45 64.85) (width 0.16) (layer "In9.Cu") (net 210))
  (segment (start 184.15 72.15) (end 183.611021 72.15) (width 0.16) (layer "In9.Cu") (net 210))
  (segment (start 183.611021 70.65) (end 184.188979 70.65) (width 0.16) (layer "In9.Cu") (net 210))
  (segment (start 182.954744 67.876438) (end 182.476435 68.354742) (width 0.16) (layer "In9.Cu") (net 210))
  (segment (start 184.15 72.65) (end 184.188979 72.65) (width 0.16) (layer "In9.Cu") (net 210))
  (segment (start 182.318343 67.240036) (end 182.318343 67.240037) (width 0.16) (layer "In9.Cu") (net 210))
  (segment (start 183.9 75.65) (end 183.216328 76.333672) (width 0.1) (layer "In9.Cu") (net 210))
  (segment (start 184.188979 72.15) (end 184.15 72.15) (width 0.16) (layer "In9.Cu") (net 210))
  (segment (start 173.82 64.85) (end 170.98 62.01) (width 0.16) (layer "In9.Cu") (net 210))
  (segment (start 183.829289 68.911091) (end 183.82929 68.911091) (width 0.16) (layer "In9.Cu") (net 210))
  (segment (start 183.611021 71.65) (end 184.188979 71.65) (width 0.16) (layer "In9.Cu") (net 210))
  (segment (start 183.9 69.9) (end 183.9 69.3) (width 0.16) (layer "In9.Cu") (net 210))
  (segment (start 184.2 78.25) (end 184.2 81.604172) (width 0.1) (layer "In9.Cu") (net 210))
  (segment (start 183.9 75.5) (end 183.9 72.9) (width 0.16) (layer "In9.Cu") (net 210))
  (segment (start 182.794637 68.672944) (end 182.794639 68.672945) (width 0.16) (layer "In9.Cu") (net 210))
  (segment (start 183.9 75.5) (end 183.9 75.65) (width 0.1) (layer "In9.Cu") (net 210))
  (segment (start 183.82929 68.911091) (end 183.909344 68.831036) (width 0.16) (layer "In9.Cu") (net 210))
  (segment (start 184.2 81.604172) (end 184.655836 82.060008) (width 0.1) (layer "In9.Cu") (net 210))
  (segment (start 183.611021 71.15) (end 184.188979 71.15) (width 0.16) (layer "In9.Cu") (net 210))
  (segment (start 170.98 60.966336) (end 170.986328 60.960008) (width 0.16) (layer "In9.Cu") (net 210))
  (segment (start 182.318343 67.240037) (end 182.238288 67.320091) (width 0.16) (layer "In9.Cu") (net 210))
  (segment (start 170.98 62.01) (end 170.98 60.966336) (width 0.16) (layer "In9.Cu") (net 210))
  (segment (start 183.591145 68.512838) (end 183.112836 68.991143) (width 0.16) (layer "In9.Cu") (net 210))
  (segment (start 184.188979 70.15) (end 184.15 70.15) (width 0.16) (layer "In9.Cu") (net 210))
  (segment (start 183.9 69.3) (end 183.82929 69.22929) (width 0.16) (layer "In9.Cu") (net 210))
  (segment (start 179.45 64.85) (end 173.82 64.85) (width 0.16) (layer "In9.Cu") (net 210))
  (segment (start 182.158238 68.036544) (end 182.636542 67.558235) (width 0.16) (layer "In9.Cu") (net 210))
  (segment (start 183.216328 76.333672) (end 183.216328 77.266328) (width 0.1) (layer "In9.Cu") (net 210))
  (segment (start 182.794639 68.672945) (end 183.272943 68.194636) (width 0.16) (layer "In9.Cu") (net 210))
  (segment (start 183.216328 77.266328) (end 184.2 78.25) (width 0.1) (layer "In9.Cu") (net 210))
  (segment (start 183.591145 68.512837) (end 183.591145 68.512838) (width 0.16) (layer "In9.Cu") (net 210))
  (segment (start 182.954744 67.876437) (end 182.954744 67.876438) (width 0.16) (layer "In9.Cu") (net 210))
  (arc (start 183.909344 68.831036) (mid 183.975245 68.671937) (end 183.909344 68.512838) (width 0.16) (layer "In9.Cu") (net 210))
  (arc (start 184.438979 71.4) (mid 184.365756 71.223223) (end 184.188979 71.15) (width 0.16) (layer "In9.Cu") (net 210))
  (arc (start 183.909344 68.512838) (mid 183.750245 68.446936) (end 183.591145 68.512837) (width 0.16) (layer "In9.Cu") (net 210))
  (arc (start 184.188979 70.65) (mid 184.365756 70.576777) (end 184.438979 70.4) (width 0.16) (layer "In9.Cu") (net 210))
  (arc (start 182.238288 67.320091) (mid 182.079189 67.385992) (end 181.92009 67.320091) (width 0.16) (layer "In9.Cu") (net 210))
  (arc (start 183.272943 67.876438) (mid 183.113844 67.810536) (end 182.954744 67.876437) (width 0.16) (layer "In9.Cu") (net 210))
  (arc (start 184.438979 72.4) (mid 184.365756 72.223223) (end 184.188979 72.15) (width 0.16) (layer "In9.Cu") (net 210))
  (arc (start 183.611021 72.15) (mid 183.434244 72.076777) (end 183.361021 71.9) (width 0.16) (layer "In9.Cu") (net 210))
  (arc (start 183.361021 70.9) (mid 183.434244 70.723223) (end 183.611021 70.65) (width 0.16) (layer "In9.Cu") (net 210))
  (arc (start 184.438979 70.4) (mid 184.365756 70.223223) (end 184.188979 70.15) (width 0.16) (layer "In9.Cu") (net 210))
  (arc (start 182.636542 67.240037) (mid 182.477443 67.174135) (end 182.318343 67.240036) (width 0.16) (layer "In9.Cu") (net 210))
  (arc (start 183.9 72.9) (mid 183.973223 72.723223) (end 184.15 72.65) (width 0.16) (layer "In9.Cu") (net 210))
  (arc (start 184.188979 72.65) (mid 184.365756 72.576777) (end 184.438979 72.4) (width 0.16) (layer "In9.Cu") (net 210))
  (arc (start 184.15 70.15) (mid 183.973223 70.076777) (end 183.9 69.9) (width 0.16) (layer "In9.Cu") (net 210))
  (arc (start 183.611021 71.15) (mid 183.434244 71.076777) (end 183.361021 70.9) (width 0.16) (layer "In9.Cu") (net 210))
  (arc (start 183.272943 68.194636) (mid 183.338844 68.035537) (end 183.272943 67.876438) (width 0.16) (layer "In9.Cu") (net 210))
  (arc (start 184.188979 71.65) (mid 184.365756 71.576777) (end 184.438979 71.4) (width 0.16) (layer "In9.Cu") (net 210))
  (arc (start 183.112836 68.991143) (mid 182.953737 69.057044) (end 182.794638 68.991143) (width 0.16) (layer "In9.Cu") (net 210))
  (arc (start 182.636542 67.558235) (mid 182.702443 67.399136) (end 182.636542 67.240037) (width 0.16) (layer "In9.Cu") (net 210))
  (arc (start 183.82929 69.22929) (mid 183.763388 69.070191) (end 183.829289 68.911091) (width 0.16) (layer "In9.Cu") (net 210))
  (arc (start 182.158237 68.354742) (mid 182.092336 68.195644) (end 182.158236 68.036543) (width 0.16) (layer "In9.Cu") (net 210))
  (arc (start 182.794638 68.991143) (mid 182.728737 68.832045) (end 182.794637 68.672944) (width 0.16) (layer "In9.Cu") (net 210))
  (arc (start 182.476435 68.354742) (mid 182.317336 68.420643) (end 182.158237 68.354742) (width 0.16) (layer "In9.Cu") (net 210))
  (arc (start 183.361021 71.9) (mid 183.434244 71.723223) (end 183.611021 71.65) (width 0.16) (layer "In9.Cu") (net 210))
  (segment (start 174.386328 60.960008) (end 174.386328 59.660008) (width 0.2) (layer "F.Cu") (net 211))
  (segment (start 187.136328 81.54368) (end 187.62 81.060008) (width 0.127) (layer "F.Cu") (net 211))
  (segment (start 187.136328 81.560008) (end 187.136328 81.54368) (width 0.127) (layer "F.Cu") (net 211))
  (via blind (at 174.386328 60.960008) (size 0.5) (drill 0.2) (layers "F.Cu" "In2.Cu") (net 211))
  (via blind (at 187.62 81.060008) (size 0.5) (drill 0.2) (layers "F.Cu" "In2.Cu") (net 211))
  (segment (start 185.056328 75.956328) (end 184.93 75.83) (width 0.1) (layer "In2.Cu") (net 211))
  (segment (start 185.051 81.101) (end 185.051 79.859) (width 0.1) (layer "In2.Cu") (net 211))
  (segment (start 175.35 58.80104) (end 175.35 59.95) (width 0.16) (layer "In2.Cu") (net 211))
  (segment (start 178.645361 61.876418) (end 178.645362 61.87642) (width 0.16) (layer "In2.Cu") (net 211))
  (segment (start 177.75 60.25) (end 176.25 60.25) (width 0.16) (layer "In2.Cu") (net 211))
  (segment (start 182.180916 65.058422) (end 182.180917 65.058421) (width 0.16) (layer "In2.Cu") (net 211))
  (segment (start 181.497755 63.620249) (end 181.497754 63.62025) (width 0.16) (layer "In2.Cu") (net 211))
  (segment (start 179.729974 61.498917) (end 179.729975 61.498917) (width 0.16) (layer "In2.Cu") (net 211))
  (segment (start 174.386328 60.913672) (end 174.386328 60.960008) (width 0.16) (layer "In2.Cu") (net 211))
  (segment (start 179.376421 61.498917) (end 178.998914 61.876419) (width 0.16) (layer "In2.Cu") (net 211))
  (segment (start 178.645362 61.522866) (end 178.657336 61.510889) (width 0.16) (layer "In2.Cu") (net 211))
  (segment (start 185.559 81.609) (end 185.051 81.101) (width 0.1) (layer "In2.Cu") (net 211))
  (segment (start 182.204866 64.32736) (end 182.204865 64.327361) (width 0.16) (layer "In2.Cu") (net 211))
  (segment (start 180.766694 63.997751) (end 180.766695 63.997753) (width 0.16) (layer "In2.Cu") (net 211))
  (segment (start 181.851307 63.62025) (end 181.851308 63.62025) (width 0.16) (layer "In2.Cu") (net 211))
  (segment (start 181.497754 63.62025) (end 181.120247 63.997752) (width 0.16) (layer "In2.Cu") (net 211))
  (segment (start 185.051 79.859) (end 185.52 79.39) (width 0.1) (layer "In2.Cu") (net 211))
  (segment (start 181.473806 64.35131) (end 181.851308 63.973803) (width 0.16) (layer "In2.Cu") (net 211))
  (segment (start 180.059583 62.937089) (end 180.059584 62.937088) (width 0.16) (layer "In2.Cu") (net 211))
  (segment (start 178.657336 61.157335) (end 178.657337 61.157337) (width 0.16) (layer "In2.Cu") (net 211))
  (segment (start 182.180917 65.058421) (end 182.192891 65.046444) (width 0.16) (layer "In2.Cu") (net 211))
  (segment (start 180.059583 63.29064) (end 180.059584 63.290642) (width 0.16) (layer "In2.Cu") (net 211))
  (segment (start 182.180915 65.411974) (end 182.180917 65.411975) (width 0.16) (layer "In2.Cu") (net 211))
  (segment (start 185.52 78.72) (end 185.056328 78.256328) (width 0.1) (layer "In2.Cu") (net 211))
  (segment (start 180.790644 62.913138) (end 180.790643 62.913139) (width 0.16) (layer "In2.Cu") (net 211))
  (segment (start 179.352472 62.583529) (end 179.352473 62.583531) (width 0.16) (layer "In2.Cu") (net 211))
  (segment (start 178.645361 61.522867) (end 178.645362 61.522866) (width 0.16) (layer "In2.Cu") (net 211))
  (segment (start 187.071008 81.609) (end 187.62 81.060008) (width 0.1) (layer "In2.Cu") (net 211))
  (segment (start 180.766694 63.6442) (end 180.766695 63.644199) (width 0.16) (layer "In2.Cu") (net 211))
  (segment (start 180.083533 62.206027) (end 180.083532 62.206028) (width 0.16) (layer "In2.Cu") (net 211))
  (segment (start 185.52 79.39) (end 185.52 78.72) (width 0.1) (layer "In2.Cu") (net 211))
  (segment (start 180.790643 62.913139) (end 180.413136 63.290641) (width 0.16) (layer "In2.Cu") (net 211))
  (segment (start 180.059584 62.937088) (end 180.437086 62.559581) (width 0.16) (layer "In2.Cu") (net 211))
  (segment (start 182.192891 65.046444) (end 182.558419 64.680914) (width 0.16) (layer "In2.Cu") (net 211))
  (segment (start 181.144196 62.913139) (end 181.144197 62.913139) (width 0.16) (layer "In2.Cu") (net 211))
  (segment (start 182.546446 65.4) (end 182.534469 65.411974) (width 0.16) (layer "In2.Cu") (net 211))
  (segment (start 182.558418 64.327361) (end 182.558419 64.327361) (width 0.16) (layer "In2.Cu") (net 211))
  (segment (start 184.93 75.83) (end 184.93 75.55) (width 0.1) (layer "In2.Cu") (net 211))
  (segment (start 187.071008 81.609) (end 185.559 81.609) (width 0.1) (layer "In2.Cu") (net 211))
  (segment (start 182.546447 65.399999) (end 182.546446 65.4) (width 0.16) (layer "In2.Cu") (net 211))
  (segment (start 179.352472 62.229978) (end 179.352473 62.229977) (width 0.16) (layer "In2.Cu") (net 211))
  (segment (start 181.473805 64.351311) (end 181.473806 64.35131) (width 0.16) (layer "In2.Cu") (net 211))
  (segment (start 178.657337 61.157337) (end 177.75 60.25) (width 0.16) (layer "In2.Cu") (net 211))
  (segment (start 175.05 60.25) (end 174.386328 60.913672) (width 0.16) (layer "In2.Cu") (net 211))
  (segment (start 180.766695 63.644199) (end 181.144197 63.266692) (width 0.16) (layer "In2.Cu") (net 211))
  (segment (start 179.352473 62.229977) (end 179.729975 61.85247) (width 0.16) (layer "In2.Cu") (net 211))
  (segment (start 182.204865 64.327361) (end 181.827358 64.704863) (width 0.16) (layer "In2.Cu") (net 211))
  (segment (start 181.473805 64.704862) (end 181.473806 64.704864) (width 0.16) (layer "In2.Cu") (net 211))
  (segment (start 184.93 75.55) (end 184.93 67.43) (width 0.16) (layer "In2.Cu") (net 211))
  (segment (start 185.056328 78.256328) (end 185.056328 75.956328) (width 0.1) (layer "In2.Cu") (net 211))
  (segment (start 179.376422 61.498916) (end 179.376421 61.498917) (width 0.16) (layer "In2.Cu") (net 211))
  (segment (start 175.95 59.95) (end 175.95 58.80104) (width 0.16) (layer "In2.Cu") (net 211))
  (segment (start 180.083532 62.206028) (end 179.706025 62.58353) (width 0.16) (layer "In2.Cu") (net 211))
  (segment (start 184.93 67.43) (end 182.9 65.4) (width 0.16) (layer "In2.Cu") (net 211))
  (segment (start 180.437085 62.206028) (end 180.437086 62.206028) (width 0.16) (layer "In2.Cu") (net 211))
  (arc (start 178.998914 61.876419) (mid 178.822137 61.949642) (end 178.645361 61.876418) (width 0.16) (layer "In2.Cu") (net 211))
  (arc (start 182.558419 64.680914) (mid 182.631642 64.504137) (end 182.558418 64.327361) (width 0.16) (layer "In2.Cu") (net 211))
  (arc (start 181.851308 63.973803) (mid 181.924531 63.797026) (end 181.851307 63.62025) (width 0.16) (layer "In2.Cu") (net 211))
  (arc (start 181.827358 64.704863) (mid 181.650581 64.778086) (end 181.473805 64.704862) (width 0.16) (layer "In2.Cu") (net 211))
  (arc (start 175.95 58.80104) (mid 175.862132 58.588908) (end 175.65 58.50104) (width 0.16) (layer "In2.Cu") (net 211))
  (arc (start 182.180917 65.411975) (mid 182.107693 65.235199) (end 182.180916 65.058422) (width 0.16) (layer "In2.Cu") (net 211))
  (arc (start 176.25 60.25) (mid 176.037868 60.162132) (end 175.95 59.95) (width 0.16) (layer "In2.Cu") (net 211))
  (arc (start 179.706025 62.58353) (mid 179.529248 62.656753) (end 179.352472 62.583529) (width 0.16) (layer "In2.Cu") (net 211))
  (arc (start 178.657336 61.510889) (mid 178.730559 61.334112) (end 178.657336 61.157335) (width 0.16) (layer "In2.Cu") (net 211))
  (arc (start 175.35 59.95) (mid 175.262132 60.162132) (end 175.05 60.25) (width 0.16) (layer "In2.Cu") (net 211))
  (arc (start 179.729975 61.85247) (mid 179.803198 61.675693) (end 179.729974 61.498917) (width 0.16) (layer "In2.Cu") (net 211))
  (arc (start 175.65 58.50104) (mid 175.437868 58.588908) (end 175.35 58.80104) (width 0.16) (layer "In2.Cu") (net 211))
  (arc (start 178.645362 61.87642) (mid 178.572138 61.699644) (end 178.645361 61.522867) (width 0.16) (layer "In2.Cu") (net 211))
  (arc (start 182.534469 65.411974) (mid 182.357692 65.485197) (end 182.180915 65.411974) (width 0.16) (layer "In2.Cu") (net 211))
  (arc (start 181.473806 64.704864) (mid 181.400582 64.528088) (end 181.473805 64.351311) (width 0.16) (layer "In2.Cu") (net 211))
  (arc (start 182.9 65.4) (mid 182.723224 65.326776) (end 182.546447 65.399999) (width 0.16) (layer "In2.Cu") (net 211))
  (arc (start 179.352473 62.583531) (mid 179.279249 62.406755) (end 179.352472 62.229978) (width 0.16) (layer "In2.Cu") (net 211))
  (arc (start 181.120247 63.997752) (mid 180.94347 64.070975) (end 180.766694 63.997751) (width 0.16) (layer "In2.Cu") (net 211))
  (arc (start 180.413136 63.290641) (mid 180.236359 63.363864) (end 180.059583 63.29064) (width 0.16) (layer "In2.Cu") (net 211))
  (arc (start 179.729975 61.498917) (mid 179.553199 61.425693) (end 179.376422 61.498916) (width 0.16) (layer "In2.Cu") (net 211))
  (arc (start 181.851308 63.62025) (mid 181.674532 63.547026) (end 181.497755 63.620249) (width 0.16) (layer "In2.Cu") (net 211))
  (arc (start 181.144197 63.266692) (mid 181.21742 63.089915) (end 181.144196 62.913139) (width 0.16) (layer "In2.Cu") (net 211))
  (arc (start 180.766695 63.997753) (mid 180.693471 63.820977) (end 180.766694 63.6442) (width 0.16) (layer "In2.Cu") (net 211))
  (arc (start 182.558419 64.327361) (mid 182.381643 64.254137) (end 182.204866 64.32736) (width 0.16) (layer "In2.Cu") (net 211))
  (arc (start 180.437086 62.206028) (mid 180.26031 62.132804) (end 180.083533 62.206027) (width 0.16) (layer "In2.Cu") (net 211))
  (arc (start 181.144197 62.913139) (mid 180.967421 62.839915) (end 180.790644 62.913138) (width 0.16) (layer "In2.Cu") (net 211))
  (arc (start 180.059584 63.290642) (mid 179.98636 63.113866) (end 180.059583 62.937089) (width 0.16) (layer "In2.Cu") (net 211))
  (arc (start 180.437086 62.559581) (mid 180.510309 62.382804) (end 180.437085 62.206028) (width 0.16) (layer "In2.Cu") (net 211))
  (segment (start 160.786328 59.660008) (end 160.786328 60.960008) (width 0.2) (layer "F.Cu") (net 212))
  (segment (start 183.136328 79.560008) (end 182.636328 79.060008) (width 0.127) (layer "F.Cu") (net 212))
  (via blind (at 160.786328 60.960008) (size 0.5) (drill 0.2) (layers "F.Cu" "In5.Cu") (net 212))
  (via blind (at 182.636328 79.060008) (size 0.5) (drill 0.2) (layers "F.Cu" "In5.Cu") (net 212))
  (segment (start 171.55 65.125) (end 171.55 65.675) (width 0.146) (layer "In5.Cu") (net 212))
  (segment (start 162.1 62.7) (end 165.2 62.7) (width 0.146) (layer "In5.Cu") (net 212))
  (segment (start 160.786328 60.960008) (end 160.786328 61.386328) (width 0.146) (layer "In5.Cu") (net 212))
  (segment (start 171.1 65.675) (end 171.1 65.125) (width 0.146) (layer "In5.Cu") (net 212))
  (segment (start 182.17 78.59368) (end 182.17 75.56) (width 0.09) (layer "In5.Cu") (net 212))
  (segment (start 170.2 65.675) (end 170.2 65.125) (width 0.146) (layer "In5.Cu") (net 212))
  (segment (start 177.95 68.25) (end 182.17 72.47) (width 0.146) (layer "In5.Cu") (net 212))
  (segment (start 174.888949 65.4) (end 175.075 65.4) (width 0.146) (layer "In5.Cu") (net 212))
  (segment (start 173.8 65.675) (end 173.8 65.125) (width 0.146) (layer "In5.Cu") (net 212))
  (segment (start 174.25 65.125) (end 174.25 65.675) (width 0.146) (layer "In5.Cu") (net 212))
  (segment (start 174.7 65.675) (end 174.7 65.588949) (width 0.146) (layer "In5.Cu") (net 212))
  (segment (start 182.17 72.47) (end 182.17 75.56) (width 0.146) (layer "In5.Cu") (net 212))
  (segment (start 173.35 65.125) (end 173.35 65.675) (width 0.146) (layer "In5.Cu") (net 212))
  (segment (start 177.65 68.25) (end 177.95 68.25) (width 0.146) (layer "In5.Cu") (net 212))
  (segment (start 169.75 65.125) (end 169.75 65.675) (width 0.146) (layer "In5.Cu") (net 212))
  (segment (start 172.9 65.675) (end 172.9 65.125) (width 0.146) (layer "In5.Cu") (net 212))
  (segment (start 172 65.675) (end 172 65.125) (width 0.146) (layer "In5.Cu") (net 212))
  (segment (start 175.3 65.9) (end 177.65 68.25) (width 0.146) (layer "In5.Cu") (net 212))
  (segment (start 167.9 65.4) (end 168.175 65.4) (width 0.146) (layer "In5.Cu") (net 212))
  (segment (start 172.45 65.125) (end 172.45 65.675) (width 0.146) (layer "In5.Cu") (net 212))
  (segment (start 175.3 65.625) (end 175.3 65.9) (width 0.146) (layer "In5.Cu") (net 212))
  (segment (start 165.2 62.7) (end 167.9 65.4) (width 0.146) (layer "In5.Cu") (net 212))
  (segment (start 182.636328 79.060008) (end 182.17 78.59368) (width 0.09) (layer "In5.Cu") (net 212))
  (segment (start 160.786328 61.386328) (end 162.1 62.7) (width 0.146) (layer "In5.Cu") (net 212))
  (segment (start 170.65 65.125) (end 170.65 65.675) (width 0.146) (layer "In5.Cu") (net 212))
  (segment (start 169.3 65.675) (end 169.3 65.125) (width 0.146) (layer "In5.Cu") (net 212))
  (segment (start 168.4 65.175) (end 168.4 65.125) (width 0.146) (layer "In5.Cu") (net 212))
  (segment (start 168.85 65.125) (end 168.85 65.675) (width 0.146) (layer "In5.Cu") (net 212))
  (arc (start 169.3 65.125) (mid 169.365901 64.965901) (end 169.525 64.9) (width 0.146) (layer "In5.Cu") (net 212))
  (arc (start 171.55 65.675) (mid 171.615901 65.834099) (end 171.775 65.9) (width 0.146) (layer "In5.Cu") (net 212))
  (arc (start 170.2 65.125) (mid 170.265901 64.965901) (end 170.425 64.9) (width 0.146) (layer "In5.Cu") (net 212))
  (arc (start 169.975 65.9) (mid 170.134099 65.834099) (end 170.2 65.675) (width 0.146) (layer "In5.Cu") (net 212))
  (arc (start 169.525 64.9) (mid 169.684099 64.965901) (end 169.75 65.125) (width 0.146) (layer "In5.Cu") (net 212))
  (arc (start 172.675 65.9) (mid 172.834099 65.834099) (end 172.9 65.675) (width 0.146) (layer "In5.Cu") (net 212))
  (arc (start 172.9 65.125) (mid 172.965901 64.965901) (end 173.125 64.9) (width 0.146) (layer "In5.Cu") (net 212))
  (arc (start 170.875 65.9) (mid 171.034099 65.834099) (end 171.1 65.675) (width 0.146) (layer "In5.Cu") (net 212))
  (arc (start 169.75 65.675) (mid 169.815901 65.834099) (end 169.975 65.9) (width 0.146) (layer "In5.Cu") (net 212))
  (arc (start 170.425 64.9) (mid 170.584099 64.965901) (end 170.65 65.125) (width 0.146) (layer "In5.Cu") (net 212))
  (arc (start 173.125 64.9) (mid 173.284099 64.965901) (end 173.35 65.125) (width 0.146) (layer "In5.Cu") (net 212))
  (arc (start 169.075 65.9) (mid 169.234099 65.834099) (end 169.3 65.675) (width 0.146) (layer "In5.Cu") (net 212))
  (arc (start 174.475 65.9) (mid 174.634099 65.834099) (end 174.7 65.675) (width 0.146) (layer "In5.Cu") (net 212))
  (arc (start 168.625 64.9) (mid 168.784099 64.965901) (end 168.85 65.125) (width 0.146) (layer "In5.Cu") (net 212))
  (arc (start 175.075 65.4) (mid 175.234099 65.465901) (end 175.3 65.625) (width 0.146) (layer "In5.Cu") (net 212))
  (arc (start 171.1 65.125) (mid 171.165901 64.965901) (end 171.325 64.9) (width 0.146) (layer "In5.Cu") (net 212))
  (arc (start 172.225 64.9) (mid 172.384099 64.965901) (end 172.45 65.125) (width 0.146) (layer "In5.Cu") (net 212))
  (arc (start 174.25 65.675) (mid 174.315901 65.834099) (end 174.475 65.9) (width 0.146) (layer "In5.Cu") (net 212))
  (arc (start 172.45 65.675) (mid 172.515901 65.834099) (end 172.675 65.9) (width 0.146) (layer "In5.Cu") (net 212))
  (arc (start 171.325 64.9) (mid 171.484099 64.965901) (end 171.55 65.125) (width 0.146) (layer "In5.Cu") (net 212))
  (arc (start 170.65 65.675) (mid 170.715901 65.834099) (end 170.875 65.9) (width 0.146) (layer "In5.Cu") (net 212))
  (arc (start 172 65.125) (mid 172.065901 64.965901) (end 172.225 64.9) (width 0.146) (layer "In5.Cu") (net 212))
  (arc (start 173.575 65.9) (mid 173.734099 65.834099) (end 173.8 65.675) (width 0.146) (layer "In5.Cu") (net 212))
  (arc (start 174.025 64.9) (mid 174.184099 64.965901) (end 174.25 65.125) (width 0.146) (layer "In5.Cu") (net 212))
  (arc (start 171.775 65.9) (mid 171.934099 65.834099) (end 172 65.675) (width 0.146) (layer "In5.Cu") (net 212))
  (arc (start 168.175 65.4) (mid 168.334099 65.334099) (end 168.4 65.175) (width 0.146) (layer "In5.Cu") (net 212))
  (arc (start 168.85 65.675) (mid 168.915901 65.834099) (end 169.075 65.9) (width 0.146) (layer "In5.Cu") (net 212))
  (arc (start 173.35 65.675) (mid 173.415901 65.834099) (end 173.575 65.9) (width 0.146) (layer "In5.Cu") (net 212))
  (arc (start 173.8 65.125) (mid 173.865901 64.965901) (end 174.025 64.9) (width 0.146) (layer "In5.Cu") (net 212))
  (arc (start 168.4 65.125) (mid 168.465901 64.965901) (end 168.625 64.9) (width 0.146) (layer "In5.Cu") (net 212))
  (arc (start 174.7 65.588949) (mid 174.755342 65.455342) (end 174.888949 65.4) (width 0.146) (layer "In5.Cu") (net 212))
  (segment (start 176.636328 77.060008) (end 176.636328 77.0405) (width 0.127) (layer "F.Cu") (net 213))
  (segment (start 153.136328 59.660008) (end 153.136328 60.960008) (width 0.2) (layer "F.Cu") (net 213))
  (segment (start 177.136328 77.560008) (end 176.636328 77.060008) (width 0.127) (layer "F.Cu") (net 213))
  (via blind (at 153.136328 60.960008) (size 0.5) (drill 0.2) (layers "F.Cu" "In5.Cu") (net 213))
  (via blind (at 176.636328 77.0405) (size 0.5) (drill 0.2) (layers "F.Cu" "In5.Cu") (net 213))
  (segment (start 169.8 74.419132) (end 169.8 73.980868) (width 0.146) (layer "In5.Cu") (net 213))
  (segment (start 168.4 74.2) (end 167.7 74.2) (width 0.146) (layer "In5.Cu") (net 213))
  (segment (start 176.35 76.754172) (end 176.35 75.56) (width 0.09) (layer "In5.Cu") (net 213))
  (segment (start 173.7 74) (end 173.7 74.4) (width 0.146) (layer "In5.Cu") (net 213))
  (segment (start 174.1 74.4) (end 174.1 74) (width 0.146) (layer "In5.Cu") (net 213))
  (segment (start 170.6 74.419132) (end 170.6 73.980868) (width 0.146) (layer "In5.Cu") (net 213))
  (segment (start 157.4 69) (end 153.136328 64.736328) (width 0.146) (layer "In5.Cu") (net 213))
  (segment (start 171.4 74) (end 171.4 73.980868) (width 0.146) (layer "In5.Cu") (net 213))
  (segment (start 162.5 69) (end 157.4 69) (width 0.146) (layer "In5.Cu") (net 213))
  (segment (start 173.3 74.4) (end 173.3 74) (width 0.146) (layer "In5.Cu") (net 213))
  (segment (start 176.35 75.35) (end 175.2 74.2) (width 0.146) (layer "In5.Cu") (net 213))
  (segment (start 153.136328 64.736328) (end 153.136328 60.960008) (width 0.146) (layer "In5.Cu") (net 213))
  (segment (start 170.2 73.980868) (end 170.2 74.419132) (width 0.146) (layer "In5.Cu") (net 213))
  (segment (start 167.7 74.2) (end 162.5 69) (width 0.146) (layer "In5.Cu") (net 213))
  (segment (start 172.7 74.2) (end 171.6 74.2) (width 0.146) (layer "In5.Cu") (net 213))
  (segment (start 169.4 73.980868) (end 169.4 74.419132) (width 0.146) (layer "In5.Cu") (net 213))
  (segment (start 168.6 73.980868) (end 168.6 74) (width 0.146) (layer "In5.Cu") (net 213))
  (segment (start 169 74.419132) (end 169 73.980868) (width 0.146) (layer "In5.Cu") (net 213))
  (segment (start 176.35 75.56) (end 176.35 75.35) (width 0.146) (layer "In5.Cu") (net 213))
  (segment (start 171 73.980868) (end 171 74) (width 0.146) (layer "In5.Cu") (net 213))
  (segment (start 176.636328 77.0405) (end 176.35 76.754172) (width 0.09) (layer "In5.Cu") (net 213))
  (segment (start 175.2 74.2) (end 174.7 74.2) (width 0.146) (layer "In5.Cu") (net 213))
  (segment (start 171 74) (end 171 74.419132) (width 0.146) (layer "In5.Cu") (net 213))
  (arc (start 169.2 74.619132) (mid 169.058579 74.560553) (end 169 74.419132) (width 0.146) (layer "In5.Cu") (net 213))
  (arc (start 174.5 74.4) (mid 174.441421 74.541421) (end 174.3 74.6) (width 0.146) (layer "In5.Cu") (net 213))
  (arc (start 168.8 73.780868) (mid 168.658579 73.839447) (end 168.6 73.980868) (width 0.146) (layer "In5.Cu") (net 213))
  (arc (start 173.7 74.4) (mid 173.641421 74.541421) (end 173.5 74.6) (width 0.146) (layer "In5.Cu") (net 213))
  (arc (start 172.9 74) (mid 172.841421 74.141421) (end 172.7 74.2) (width 0.146) (layer "In5.Cu") (net 213))
  (arc (start 170.4 73.780868) (mid 170.258579 73.839447) (end 170.2 73.980868) (width 0.146) (layer "In5.Cu") (net 213))
  (arc (start 171.6 74.2) (mid 171.458579 74.141421) (end 171.4 74) (width 0.146) (layer "In5.Cu") (net 213))
  (arc (start 173.1 73.8) (mid 172.958579 73.858579) (end 172.9 74) (width 0.146) (layer "In5.Cu") (net 213))
  (arc (start 174.7 74.2) (mid 174.558579 74.258579) (end 174.5 74.4) (width 0.146) (layer "In5.Cu") (net 213))
  (arc (start 174.3 74.6) (mid 174.158579 74.541421) (end 174.1 74.4) (width 0.146) (layer "In5.Cu") (net 213))
  (arc (start 174.1 74) (mid 174.041421 73.858579) (end 173.9 73.8) (width 0.146) (layer "In5.Cu") (net 213))
  (arc (start 173.5 74.6) (mid 173.358579 74.541421) (end 173.3 74.4) (width 0.146) (layer "In5.Cu") (net 213))
  (arc (start 169.6 73.780868) (mid 169.458579 73.839447) (end 169.4 73.980868) (width 0.146) (layer "In5.Cu") (net 213))
  (arc (start 173.9 73.8) (mid 173.758579 73.858579) (end 173.7 74) (width 0.146) (layer "In5.Cu") (net 213))
  (arc (start 173.3 74) (mid 173.241421 73.858579) (end 173.1 73.8) (width 0.146) (layer "In5.Cu") (net 213))
  (arc (start 170 74.619132) (mid 169.858579 74.560553) (end 169.8 74.419132) (width 0.146) (layer "In5.Cu") (net 213))
  (arc (start 171 74.419132) (mid 170.941421 74.560553) (end 170.8 74.619132) (width 0.146) (layer "In5.Cu") (net 213))
  (arc (start 169.4 74.419132) (mid 169.341421 74.560553) (end 169.2 74.619132) (width 0.146) (layer "In5.Cu") (net 213))
  (arc (start 168.6 74) (mid 168.541421 74.141421) (end 168.4 74.2) (width 0.146) (layer "In5.Cu") (net 213))
  (arc (start 171.2 73.780868) (mid 171.058579 73.839447) (end 171 73.980868) (width 0.146) (layer "In5.Cu") (net 213))
  (arc (start 170.6 73.980868) (mid 170.541421 73.839447) (end 170.4 73.780868) (width 0.146) (layer "In5.Cu") (net 213))
  (arc (start 169 73.980868) (mid 168.941421 73.839447) (end 168.8 73.780868) (width 0.146) (layer "In5.Cu") (net 213))
  (arc (start 170.8 74.619132) (mid 170.658579 74.560553) (end 170.6 74.419132) (width 0.146) (layer "In5.Cu") (net 213))
  (arc (start 170.2 74.419132) (mid 170.141421 74.560553) (end 170 74.619132) (width 0.146) (layer "In5.Cu") (net 213))
  (arc (start 171.4 73.980868) (mid 171.341421 73.839447) (end 171.2 73.780868) (width 0.146) (layer "In5.Cu") (net 213))
  (arc (start 169.8 73.980868) (mid 169.741421 73.839447) (end 169.6 73.780868) (width 0.146) (layer "In5.Cu") (net 213))
  (segment (start 116.851328 64.160008) (end 115.336328 64.160008) (width 0.15) (layer "F.Cu") (net 214))
  (segment (start 123.386328 55.060008) (end 123.386328 53.735008) (width 0.15) (layer "F.Cu") (net 214))
  (segment (start 112.821328 64.160008) (end 115.336328 64.160008) (width 0.15) (layer "F.Cu") (net 214))
  (via (at 115.336328 64.160008) (size 0.5) (drill 0.2) (layers "F.Cu" "B.Cu") (net 214))
  (via (at 123.386328 53.735008) (size 0.5) (drill 0.2) (layers "F.Cu" "B.Cu") (net 214))
  (segment (start 123.111328 53.235008) (end 123.386328 53.510008) (width 0.15) (layer "B.Cu") (net 214))
  (segment (start 117.011328 54.910008) (end 118.686328 53.235008) (width 0.15) (layer "B.Cu") (net 214))
  (segment (start 118.686328 53.235008) (end 123.111328 53.235008) (width 0.15) (layer "B.Cu") (net 214))
  (segment (start 115.336328 64.160008) (end 117.011328 62.485008) (width 0.15) (layer "B.Cu") (net 214))
  (segment (start 123.386328 53.510008) (end 123.386328 53.735008) (width 0.15) (layer "B.Cu") (net 214))
  (segment (start 117.011328 62.485008) (end 117.011328 54.910008) (width 0.15) (layer "B.Cu") (net 214))
  (segment (start 183.136328 85.560008) (end 182.636328 85.060008) (width 0.127) (layer "F.Cu") (net 215))
  (segment (start 131.886328 55.060008) (end 131.886328 56.360008) (width 0.2) (layer "F.Cu") (net 215))
  (via (at 131.886328 56.360008) (size 0.5) (drill 0.2) (layers "F.Cu" "B.Cu") (net 215))
  (via (at 182.636328 85.060008) (size 0.5) (drill 0.2) (layers "F.Cu" "B.Cu") (net 215))
  (segment (start 181.4 83.5) (end 181.88 83.5) (width 0.1) (layer "In9.Cu") (net 215))
  (segment (start 181.88 83.5) (end 182.14 83.76) (width 0.1) (layer "In9.Cu") (net 215))
  (segment (start 180.36 80.92) (end 181.1 81.66) (width 0.1) (layer "In9.Cu") (net 215))
  (segment (start 163.95 67.7) (end 137.5 67.7) (width 0.16) (layer "In9.Cu") (net 215))
  (segment (start 164.606667 69.325561) (end 165.575559 68.356664) (width 0.16) (layer "In9.Cu") (net 215))
  (segment (start 180.36 78.42) (end 180.36 80.92) (width 0.1) (layer "In9.Cu") (net 215))
  (segment (start 137.5 67.7) (end 131.886328 62.086328) (width 0.16) (layer "In9.Cu") (net 215))
  (segment (start 165.974999 69.371447) (end 165.975 69.371446) (width 0.16) (layer "In9.Cu") (net 215))
  (segment (start 181.1 83.2) (end 181.4 83.5) (width 0.1) (layer "In9.Cu") (net 215))
  (segment (start 179.6 77.66) (end 180.36 78.42) (width 0.1) (layer "In9.Cu") (net 215))
  (segment (start 179.6 75.52) (end 179.6 77.66) (width 0.1) (layer "In9.Cu") (net 215))
  (segment (start 163.899554 68.972003) (end 163.899556 68.972004) (width 0.16) (layer "In9.Cu") (net 215))
  (segment (start 181.1 81.66) (end 181.1 83.2) (width 0.1) (layer "In9.Cu") (net 215))
  (segment (start 182.636328 84.896328) (end 182.636328 85.060008) (width 0.1) (layer "In9.Cu") (net 215))
  (segment (start 166.15 69.9) (end 165.975 69.725) (width 0.16) (layer "In9.Cu") (net 215))
  (segment (start 165.222005 68.003111) (end 164.253108 68.972003) (width 0.16) (layer "In9.Cu") (net 215))
  (segment (start 165.929117 68.71022) (end 165.929116 68.710221) (width 0.16) (layer "In9.Cu") (net 215))
  (segment (start 165.975 69.371446) (end 166.28267 69.063775) (width 0.16) (layer "In9.Cu") (net 215))
  (segment (start 131.886328 62.086328) (end 131.886328 56.360008) (width 0.16) (layer "In9.Cu") (net 215))
  (segment (start 163.899555 68.618451) (end 163.899556 68.61845) (width 0.16) (layer "In9.Cu") (net 215))
  (segment (start 164.606665 69.679114) (end 164.606667 69.679115) (width 0.16) (layer "In9.Cu") (net 215))
  (segment (start 177.7 69.9) (end 166.15 69.9) (width 0.16) (layer "In9.Cu") (net 215))
  (segment (start 165.575559 68.00311) (end 165.575559 68.003111) (width 0.16) (layer "In9.Cu") (net 215))
  (segment (start 165.222006 68.00311) (end 165.222005 68.003111) (width 0.16) (layer "In9.Cu") (net 215))
  (segment (start 164.606666 69.325562) (end 164.606667 69.325561) (width 0.16) (layer "In9.Cu") (net 215))
  (segment (start 164.207225 67.957224) (end 163.95 67.7) (width 0.16) (layer "In9.Cu") (net 215))
  (segment (start 179.6 71.8) (end 177.7 69.9) (width 0.16) (layer "In9.Cu") (net 215))
  (segment (start 182.14 83.76) (end 182.14 84.4) (width 0.1) (layer "In9.Cu") (net 215))
  (segment (start 179.6 75.52) (end 179.6 71.8) (width 0.16) (layer "In9.Cu") (net 215))
  (segment (start 163.899556 68.61845) (end 164.207225 68.310778) (width 0.16) (layer "In9.Cu") (net 215))
  (segment (start 165.929116 68.710221) (end 164.960219 69.679114) (width 0.16) (layer "In9.Cu") (net 215))
  (segment (start 182.14 84.4) (end 182.636328 84.896328) (width 0.1) (layer "In9.Cu") (net 215))
  (arc (start 163.899556 68.972004) (mid 163.826332 68.795228) (end 163.899555 68.618451) (width 0.16) (layer "In9.Cu") (net 215))
  (arc (start 166.28267 69.063775) (mid 166.355893 68.886998) (end 166.28267 68.710221) (width 0.16) (layer "In9.Cu") (net 215))
  (arc (start 164.253108 68.972003) (mid 164.076331 69.045226) (end 163.899554 68.972003) (width 0.16) (layer "In9.Cu") (net 215))
  (arc (start 164.960219 69.679114) (mid 164.783442 69.752337) (end 164.606665 69.679114) (width 0.16) (layer "In9.Cu") (net 215))
  (arc (start 165.575559 68.003111) (mid 165.398783 67.929887) (end 165.222006 68.00311) (width 0.16) (layer "In9.Cu") (net 215))
  (arc (start 166.28267 68.710221) (mid 166.105894 68.636997) (end 165.929117 68.71022) (width 0.16) (layer "In9.Cu") (net 215))
  (arc (start 165.975 69.725) (mid 165.901776 69.548224) (end 165.974999 69.371447) (width 0.16) (layer "In9.Cu") (net 215))
  (arc (start 165.575559 68.356664) (mid 165.648782 68.179887) (end 165.575559 68.00311) (width 0.16) (layer "In9.Cu") (net 215))
  (arc (start 164.207225 68.310778) (mid 164.280448 68.134001) (end 164.207225 67.957224) (width 0.16) (layer "In9.Cu") (net 215))
  (arc (start 164.606667 69.679115) (mid 164.533443 69.502339) (end 164.606666 69.325562) (width 0.16) (layer "In9.Cu") (net 215))
  (segment (start 177.77632 84.2) (end 178.136328 84.560008) (width 0.127) (layer "F.Cu") (net 216))
  (segment (start 177.656828 84.2) (end 177.77632 84.2) (width 0.127) (layer "F.Cu") (net 216))
  (segment (start 125.936328 55.060008) (end 125.936328 56.360008) (width 0.2) (layer "F.Cu") (net 216))
  (via (at 177.656828 84.2) (size 0.5) (drill 0.2) (layers "F.Cu" "B.Cu") (net 216))
  (via (at 125.936328 56.360008) (size 0.5) (drill 0.2) (layers "F.Cu" "B.Cu") (net 216))
  (segment (start 175.75 77.55) (end 175.6 77.7) (width 0.1) (layer "In9.Cu") (net 216))
  (segment (start 165.2 74.5) (end 164.1 75.6) (width 0.16) (layer "In9.Cu") (net 216))
  (segment (start 175.6 76) (end 175.75 76.15) (width 0.1) (layer "In9.Cu") (net 216))
  (segment (start 175.6 75.56) (end 175.6 76) (width 0.1) (layer "In9.Cu") (net 216))
  (segment (start 175.75 76.15) (end 175.75 77.55) (width 0.1) (layer "In9.Cu") (net 216))
  (segment (start 125.936328 67.246328) (end 125.936328 56.360008) (width 0.16) (layer "In9.Cu") (net 216))
  (segment (start 175.61 75.55) (end 175.6 75.56) (width 0.1) (layer "In9.Cu") (net 216))
  (segment (start 177.195828 83.739) (end 177.656828 84.2) (width 0.1) (layer "In9.Cu") (net 216))
  (segment (start 177.195828 82.505828) (end 177.195828 83.739) (width 0.1) (layer "In9.Cu") (net 216))
  (segment (start 134.29 75.6) (end 125.936328 67.246328) (width 0.16) (layer "In9.Cu") (net 216))
  (segment (start 175.61 75.55) (end 175.61 74.99) (width 0.16) (layer "In9.Cu") (net 216))
  (segment (start 175.6 80.91) (end 177.195828 82.505828) (width 0.1) (layer "In9.Cu") (net 216))
  (segment (start 175.6 77.7) (end 175.6 80.91) (width 0.1) (layer "In9.Cu") (net 216))
  (segment (start 175.12 74.5) (end 165.2 74.5) (width 0.16) (layer "In9.Cu") (net 216))
  (segment (start 175.61 74.99) (end 175.12 74.5) (width 0.16) (layer "In9.Cu") (net 216))
  (segment (start 164.1 75.6) (end 134.29 75.6) (width 0.16) (layer "In9.Cu") (net 216))
  (segment (start 178.716597 84.140277) (end 179.136328 84.560008) (width 0.127) (layer "F.Cu") (net 217))
  (segment (start 127.636328 55.060008) (end 127.636328 56.360008) (width 0.2) (layer "F.Cu") (net 217))
  (segment (start 178.564379 84.140277) (end 178.716597 84.140277) (width 0.127) (layer "F.Cu") (net 217))
  (via (at 127.636328 56.360008) (size 0.5) (drill 0.2) (layers "F.Cu" "B.Cu") (net 217))
  (via (at 178.564379 84.140277) (size 0.5) (drill 0.2) (layers "F.Cu" "B.Cu") (net 217))
  (segment (start 135.48 73.6) (end 158.35 73.6) (width 0.16) (layer "In9.Cu") (net 217))
  (segment (start 162.4 73.6) (end 160 73.6) (width 0.16) (layer "In9.Cu") (net 217))
  (segment (start 135.48 73.6) (end 127.636328 65.756328) (width 0.16) (layer "In9.Cu") (net 217))
  (segment (start 176.46 80.55) (end 178.564379 82.654379) (width 0.1) (layer "In9.Cu") (net 217))
  (segment (start 176.55 73.99) (end 175.86 73.3) (width 0.16) (layer "In9.Cu") (net 217))
  (segment (start 159.175 73.934638) (end 159.175 73.875) (width 0.16) (layer "In9.Cu") (net 217))
  (segment (start 158.625 73.265362) (end 158.625 73.325) (width 0.16) (layer "In9.Cu") (net 217))
  (segment (start 176.55 75.55) (end 176.55 73.99) (width 0.16) (layer "In9.Cu") (net 217))
  (segment (start 176.46 76.59) (end 176.46 80.55) (width 0.1) (layer "In9.Cu") (net 217))
  (segment (start 175.86 73.3) (end 162.7 73.3) (width 0.16) (layer "In9.Cu") (net 217))
  (segment (start 176.55 76.5) (end 176.46 76.59) (width 0.1) (layer "In9.Cu") (net 217))
  (segment (start 159.175 73.875) (end 159.175 73.265362) (width 0.16) (layer "In9.Cu") (net 217))
  (segment (start 178.564379 82.654379) (end 178.564379 84.140277) (width 0.1) (layer "In9.Cu") (net 217))
  (segment (start 159.725 73.875) (end 159.725 73.934638) (width 0.16) (layer "In9.Cu") (net 217))
  (segment (start 127.636328 65.756328) (end 127.636328 56.360008) (width 0.16) (layer "In9.Cu") (net 217))
  (segment (start 176.55 75.55) (end 176.55 76.5) (width 0.1) (layer "In9.Cu") (net 217))
  (segment (start 162.7 73.3) (end 162.4 73.6) (width 0.16) (layer "In9.Cu") (net 217))
  (arc (start 158.625 73.325) (mid 158.544454 73.519454) (end 158.35 73.6) (width 0.16) (layer "In9.Cu") (net 217))
  (arc (start 159.175 73.265362) (mid 159.094454 73.070908) (end 158.9 72.990362) (width 0.16) (layer "In9.Cu") (net 217))
  (arc (start 160 73.6) (mid 159.805546 73.680546) (end 159.725 73.875) (width 0.16) (layer "In9.Cu") (net 217))
  (arc (start 158.9 72.990362) (mid 158.705546 73.070908) (end 158.625 73.265362) (width 0.16) (layer "In9.Cu") (net 217))
  (arc (start 159.45 74.209638) (mid 159.255546 74.129092) (end 159.175 73.934638) (width 0.16) (layer "In9.Cu") (net 217))
  (arc (start 159.725 73.934638) (mid 159.644454 74.129092) (end 159.45 74.209638) (width 0.16) (layer "In9.Cu") (net 217))
  (segment (start 124.236328 55.060008) (end 124.236328 53.710008) (width 0.15) (layer "F.Cu") (net 218))
  (segment (start 114.336328 65.160008) (end 116.851328 65.160008) (width 0.15) (layer "F.Cu") (net 218))
  (segment (start 112.821328 65.160008) (end 114.336328 65.160008) (width 0.15) (layer "F.Cu") (net 218))
  (via (at 124.236328 53.710008) (size 0.5) (drill 0.2) (layers "F.Cu" "B.Cu") (net 218))
  (via (at 114.336328 65.160008) (size 0.5) (drill 0.2) (layers "F.Cu" "B.Cu") (net 218))
  (segment (start 116.361328 62.135008) (end 116.361328 54.910008) (width 0.15) (layer "B.Cu") (net 218))
  (segment (start 114.336328 65.160008) (end 114.336328 64.160008) (width 0.15) (layer "B.Cu") (net 218))
  (segment (start 124.236328 53.285008) (end 124.236328 53.710008) (width 0.15) (layer "B.Cu") (net 218))
  (segment (start 114.336328 64.160008) (end 116.361328 62.135008) (width 0.15) (layer "B.Cu") (net 218))
  (segment (start 116.361328 54.910008) (end 118.411328 52.860008) (width 0.15) (layer "B.Cu") (net 218))
  (segment (start 118.411328 52.860008) (end 123.811328 52.860008) (width 0.15) (layer "B.Cu") (net 218))
  (segment (start 123.811328 52.860008) (end 124.236328 53.285008) (width 0.15) (layer "B.Cu") (net 218))
  (segment (start 177.61632 82.04) (end 178.136328 82.560008) (width 0.127) (layer "F.Cu") (net 219))
  (segment (start 177.56 82.04) (end 177.61632 82.04) (width 0.127) (layer "F.Cu") (net 219))
  (segment (start 135.286328 55.060008) (end 135.286328 56.360008) (width 0.127) (layer "F.Cu") (net 219))
  (via blind (at 177.56 82.04) (size 0.5) (drill 0.2) (layers "F.Cu" "In5.Cu") (net 219))
  (via blind (at 135.286328 56.360008) (size 0.5) (drill 0.2) (layers "F.Cu" "In5.Cu") (net 219))
  (segment (start 169.75 81.88) (end 175.02 81.88) (width 0.09) (layer "In5.Cu") (net 219))
  (segment (start 146.1 76.4) (end 135.286328 65.586328) (width 0.146) (layer "In5.Cu") (net 219))
  (segment (start 169.1 81.4) (end 169.27 81.4) (width 0.09) (layer "In5.Cu") (net 219))
  (segment (start 175.02 81.88) (end 175.52 81.38) (width 0.09) (layer "In5.Cu") (net 219))
  (segment (start 176.4955 81.6255) (end 177.1455 81.6255) (width 0.09) (layer "In5.Cu") (net 219))
  (segment (start 177.1455 81.6255) (end 177.56 82.04) (width 0.09) (layer "In5.Cu") (net 219))
  (segment (start 163.004 81.404) (end 158 76.4) (width 0.146) (layer "In5.Cu") (net 219))
  (segment (start 175.52 81.38) (end 176.25 81.38) (width 0.09) (layer "In5.Cu") (net 219))
  (segment (start 169.1 81.4) (end 169.096 81.404) (width 0.146) (layer "In5.Cu") (net 219))
  (segment (start 169.27 81.4) (end 169.75 81.88) (width 0.09) (layer "In5.Cu") (net 219))
  (segment (start 169.096 81.404) (end 163.004 81.404) (width 0.146) (layer "In5.Cu") (net 219))
  (segment (start 135.286328 65.586328) (end 135.286328 56.360008) (width 0.146) (layer "In5.Cu") (net 219))
  (segment (start 158 76.4) (end 146.1 76.4) (width 0.146) (layer "In5.Cu") (net 219))
  (segment (start 176.25 81.38) (end 176.4955 81.6255) (width 0.09) (layer "In5.Cu") (net 219))
  (segment (start 136.986328 55.060008) (end 136.986328 56.360008) (width 0.127) (layer "F.Cu") (net 220))
  (segment (start 177.480007 81.060007) (end 177.636327 81.060007) (width 0.127) (layer "F.Cu") (net 220))
  (segment (start 177.636327 81.060007) (end 178.136328 81.560008) (width 0.127) (layer "F.Cu") (net 220))
  (via blind (at 177.480007 81.060007) (size 0.5) (drill 0.2) (layers "F.Cu" "In5.Cu") (net 220))
  (via blind (at 136.986328 56.360008) (size 0.5) (drill 0.2) (layers "F.Cu" "In5.Cu") (net 220))
  (segment (start 163.419672 80.0223) (end 163.424817 80.017156) (width 0.146) (layer "In5.Cu") (net 220))
  (segment (start 158.690503 75) (end 147.7 75) (width 0.146) (layer "In5.Cu") (net 220))
  (segment (start 163.707659 80.299999) (end 163.702515 80.305144) (width 0.146) (layer "In5.Cu") (net 220))
  (segment (start 147.7 75) (end 136.986328 64.286328) (width 0.146) (layer "In5.Cu") (net 220))
  (segment (start 163.424817 79.734314) (end 158.690503 75) (width 0.146) (layer "In5.Cu") (net 220))
  (segment (start 169.1 80.3) (end 163.990503 80.3) (width 0.146) (layer "In5.Cu") (net 220))
  (segment (start 163.424816 79.734313) (end 163.424817 79.734314) (width 0.146) (layer "In5.Cu") (net 220))
  (segment (start 170.075 81.17) (end 169.205 80.3) (width 0.09) (layer "In5.Cu") (net 220))
  (segment (start 177.0455 80.6255) (end 176.464429 80.6255) (width 0.09) (layer "In5.Cu") (net 220))
  (segment (start 163.70766 80.299999) (end 163.707659 80.299999) (width 0.146) (layer "In5.Cu") (net 220))
  (segment (start 174.464429 80.645008) (end 173.939437 81.17) (width 0.09) (layer "In5.Cu") (net 220))
  (segment (start 176.464429 80.6255) (end 176.289929 80.8) (width 0.09) (layer "In5.Cu") (net 220))
  (segment (start 175.1 80.8) (end 174.945008 80.645008) (width 0.09) (layer "In5.Cu") (net 220))
  (segment (start 163.419672 80.305143) (end 163.419673 80.305144) (width 0.146) (layer "In5.Cu") (net 220))
  (segment (start 176.289929 80.8) (end 175.1 80.8) (width 0.09) (layer "In5.Cu") (net 220))
  (segment (start 163.419672 80.022301) (end 163.419672 80.0223) (width 0.146) (layer "In5.Cu") (net 220))
  (segment (start 177.480007 81.060007) (end 177.0455 80.6255) (width 0.09) (layer "In5.Cu") (net 220))
  (segment (start 169.205 80.3) (end 169.1 80.3) (width 0.09) (layer "In5.Cu") (net 220))
  (segment (start 136.986328 64.286328) (end 136.986328 56.360008) (width 0.146) (layer "In5.Cu") (net 220))
  (segment (start 173.939437 81.17) (end 170.075 81.17) (width 0.09) (layer "In5.Cu") (net 220))
  (segment (start 174.945008 80.645008) (end 174.464429 80.645008) (width 0.09) (layer "In5.Cu") (net 220))
  (arc (start 163.419673 80.305144) (mid 163.361094 80.163723) (end 163.419672 80.022301) (width 0.146) (layer "In5.Cu") (net 220))
  (arc (start 163.990503 80.3) (mid 163.849082 80.241421) (end 163.70766 80.299999) (width 0.146) (layer "In5.Cu") (net 220))
  (arc (start 163.424817 80.017156) (mid 163.483395 79.875734) (end 163.424816 79.734313) (width 0.146) (layer "In5.Cu") (net 220))
  (arc (start 163.702515 80.305144) (mid 163.561093 80.363722) (end 163.419672 80.305143) (width 0.146) (layer "In5.Cu") (net 220))
  (segment (start 183.136328 84.560008) (end 182.636328 84.060008) (width 0.127) (layer "F.Cu") (net 221))
  (segment (start 133.586328 55.060008) (end 133.586328 56.360008) (width 0.2) (layer "F.Cu") (net 221))
  (via (at 133.586328 56.360008) (size 0.5) (drill 0.2) (layers "F.Cu" "B.Cu") (net 221))
  (via (at 182.636328 84.060008) (size 0.5) (drill 0.2) (layers "F.Cu" "B.Cu") (net 221))
  (segment (start 168.45 68.3) (end 168.15 68) (width 0.16) (layer "In9.Cu") (net 221))
  (segment (start 166.700424 65.560473) (end 166.700423 65.560474) (width 0.16) (layer "In9.Cu") (net 221))
  (segment (start 181.03447 78.391814) (end 180.95 78.476284) (width 0.1) (layer "In9.Cu") (net 221))
  (segment (start 181.03447 77.88447) (end 181.03447 78.391814) (width 0.1) (layer "In9.Cu") (net 221))
  (segment (start 180.4405 77.2905) (end 181.03447 77.88447) (width 0.1) (layer "In9.Cu") (net 221))
  (segment (start 182.1 83.14) (end 182.636328 83.676328) (width 0.1) (layer "In9.Cu") (net 221))
  (segment (start 168.114644 66.974694) (end 167.124692 67.964641) (width 0.16) (layer "In9.Cu") (net 221))
  (segment (start 182.636328 83.676328) (end 182.636328 84.060008) (width 0.1) (layer "In9.Cu") (net 221))
  (segment (start 180.6 75.54) (end 180.6 70.8) (width 0.16) (layer "In9.Cu") (net 221))
  (segment (start 180.95 78.476284) (end 180.95 80.35) (width 0.1) (layer "In9.Cu") (net 221))
  (segment (start 168.149999 67.646447) (end 168.15 67.646446) (width 0.16) (layer "In9.Cu") (net 221))
  (segment (start 168.15 67.646446) (end 168.468198 67.328247) (width 0.16) (layer "In9.Cu") (net 221))
  (segment (start 166.771139 67.964642) (end 166.771138 67.964641) (width 0.16) (layer "In9.Cu") (net 221))
  (segment (start 166.771137 67.611088) (end 166.771138 67.611087) (width 0.16) (layer "In9.Cu") (net 221))
  (segment (start 166.028671 65.878671) (end 166.028671 65.878672) (width 0.16) (layer "In9.Cu") (net 221))
  (segment (start 166.700423 65.560474) (end 166.382224 65.878672) (width 0.16) (layer "In9.Cu") (net 221))
  (segment (start 139.09 65.49) (end 164.16 65.49) (width 0.16) (layer "In9.Cu") (net 221))
  (segment (start 167.407534 66.267583) (end 167.407533 66.267584) (width 0.16) (layer "In9.Cu") (net 221))
  (segment (start 166.028671 65.878672) (end 165.64 65.49) (width 0.16) (layer "In9.Cu") (net 221))
  (segment (start 182.1 81.5) (end 182.1 83.14) (width 0.1) (layer "In9.Cu") (net 221))
  (segment (start 167.053978 65.560475) (end 167.053977 65.560474) (width 0.16) (layer "In9.Cu") (net 221))
  (segment (start 180.6 70.8) (end 178.1 68.3) (width 0.16) (layer "In9.Cu") (net 221))
  (segment (start 167.407533 66.267584) (end 166.417582 67.257531) (width 0.16) (layer "In9.Cu") (net 221))
  (segment (start 168.468197 66.974694) (end 168.468198 66.974694) (width 0.16) (layer "In9.Cu") (net 221))
  (segment (start 180.95 80.35) (end 182.1 81.5) (width 0.1) (layer "In9.Cu") (net 221))
  (segment (start 133.586328 59.986328) (end 133.586328 56.360008) (width 0.16) (layer "In9.Cu") (net 221))
  (segment (start 166.771138 67.611087) (end 167.761087 66.621138) (width 0.16) (layer "In9.Cu") (net 221))
  (segment (start 166.064029 67.257532) (end 166.064028 67.257531) (width 0.16) (layer "In9.Cu") (net 221))
  (segment (start 180.6 75.88) (end 180.4405 76.0395) (width 0.1) (layer "In9.Cu") (net 221))
  (segment (start 180.4405 76.0395) (end 180.4405 77.2905) (width 0.1) (layer "In9.Cu") (net 221))
  (segment (start 165.64 65.49) (end 165.36 65.49) (width 0.16) (layer "In9.Cu") (net 221))
  (segment (start 167.761088 66.267585) (end 167.761087 66.267584) (width 0.16) (layer "In9.Cu") (net 221))
  (segment (start 180.6 75.54) (end 180.6 75.88) (width 0.1) (layer "In9.Cu") (net 221))
  (segment (start 139.09 65.49) (end 133.586328 59.986328) (width 0.16) (layer "In9.Cu") (net 221))
  (segment (start 166.064028 66.903977) (end 167.053977 65.914028) (width 0.16) (layer "In9.Cu") (net 221))
  (segment (start 165.06 65.19) (end 165.06 64.957349) (width 0.16) (layer "In9.Cu") (net 221))
  (segment (start 166.064027 66.903978) (end 166.064028 66.903977) (width 0.16) (layer "In9.Cu") (net 221))
  (segment (start 164.46 64.957349) (end 164.46 65.19) (width 0.16) (layer "In9.Cu") (net 221))
  (segment (start 168.114645 66.974693) (end 168.114644 66.974694) (width 0.16) (layer "In9.Cu") (net 221))
  (segment (start 178.1 68.3) (end 168.45 68.3) (width 0.16) (layer "In9.Cu") (net 221))
  (arc (start 167.053977 65.914028) (mid 167.127201 65.737252) (end 167.053978 65.560475) (width 0.16) (layer "In9.Cu") (net 221))
  (arc (start 166.382224 65.878672) (mid 166.205447 65.951895) (end 166.028671 65.878671) (width 0.16) (layer "In9.Cu") (net 221))
  (arc (start 167.124692 67.964641) (mid 166.947916 68.037865) (end 166.771139 67.964642) (width 0.16) (layer "In9.Cu") (net 221))
  (arc (start 167.761087 66.621138) (mid 167.834311 66.444362) (end 167.761088 66.267585) (width 0.16) (layer "In9.Cu") (net 221))
  (arc (start 165.06 64.957349) (mid 164.972132 64.745217) (end 164.76 64.657349) (width 0.16) (layer "In9.Cu") (net 221))
  (arc (start 165.36 65.49) (mid 165.147868 65.402132) (end 165.06 65.19) (width 0.16) (layer "In9.Cu") (net 221))
  (arc (start 164.76 64.657349) (mid 164.547868 64.745217) (end 164.46 64.957349) (width 0.16) (layer "In9.Cu") (net 221))
  (arc (start 166.064028 67.257531) (mid 165.990804 67.080755) (end 166.064027 66.903978) (width 0.16) (layer "In9.Cu") (net 221))
  (arc (start 166.771138 67.964641) (mid 166.697914 67.787865) (end 166.771137 67.611088) (width 0.16) (layer "In9.Cu") (net 221))
  (arc (start 168.468198 66.974694) (mid 168.291422 66.90147) (end 168.114645 66.974693) (width 0.16) (layer "In9.Cu") (net 221))
  (arc (start 168.468198 67.328247) (mid 168.541421 67.15147) (end 168.468197 66.974694) (width 0.16) (layer "In9.Cu") (net 221))
  (arc (start 166.417582 67.257531) (mid 166.240806 67.330755) (end 166.064029 67.257532) (width 0.16) (layer "In9.Cu") (net 221))
  (arc (start 164.46 65.19) (mid 164.372132 65.402132) (end 164.16 65.49) (width 0.16) (layer "In9.Cu") (net 221))
  (arc (start 167.761087 66.267584) (mid 167.584311 66.19436) (end 167.407534 66.267583) (width 0.16) (layer "In9.Cu") (net 221))
  (arc (start 167.053977 65.560474) (mid 166.877201 65.48725) (end 166.700424 65.560473) (width 0.16) (layer "In9.Cu") (net 221))
  (arc (start 168.15 68) (mid 168.076776 67.823224) (end 168.149999 67.646447) (width 0.16) (layer "In9.Cu") (net 221))
  (segment (start 178.136328 80.560008) (end 177.664103 80.087783) (width 0.127) (layer "F.Cu") (net 222))
  (segment (start 177.664103 80.087783) (end 177.611773 80.087783) (width 0.127) (layer "F.Cu") (net 222))
  (segment (start 146.336328 55.060008) (end 146.336328 56.360008) (width 0.2) (layer "F.Cu") (net 222))
  (via blind (at 146.336328 56.360008) (size 0.5) (drill 0.2) (layers "F.Cu" "In2.Cu") (net 222))
  (via blind (at 177.611773 80.087783) (size 0.5) (drill 0.2) (layers "F.Cu" "In2.Cu") (net 222))
  (segment (start 146.336328 66.236328) (end 146.336328 56.360008) (width 0.16) (layer "In2.Cu") (net 222))
  (segment (start 152.08 71.98) (end 162.22 71.98) (width 0.16) (layer "In2.Cu") (net 222))
  (segment (start 164.52 72.18) (end 164.52 72.23) (width 0.16) (layer "In2.Cu") (net 222))
  (segment (start 163.07 71.98) (end 163.02 71.98) (width 0.16) (layer "In2.Cu") (net 222))
  (segment (start 174.576328 79.576328) (end 174.3 79.3) (width 0.1) (layer "In2.Cu") (net 222))
  (segment (start 163.92 71.98) (end 163.87 71.98) (width 0.16) (layer "In2.Cu") (net 222))
  (segment (start 173.948 76.55) (end 173.74 76.55) (width 0.1) (layer "In2.Cu") (net 222))
  (segment (start 173.74 76.55) (end 173.46 76.27) (width 0.1) (layer "In2.Cu") (net 222))
  (segment (start 175.600298 79.576328) (end 174.576328 79.576328) (width 0.1) (layer "In2.Cu") (net 222))
  (segment (start 162.82 72.18) (end 162.82 72.192758) (width 0.16) (layer "In2.Cu") (net 222))
  (segment (start 173.46 74.56) (end 170.88 71.98) (width 0.16) (layer "In2.Cu") (net 222))
  (segment (start 164.12 72.23) (end 164.12 72.18) (width 0.16) (layer "In2.Cu") (net 222))
  (segment (start 174.3 79.3) (end 174.3 78.63) (width 0.1) (layer "In2.Cu") (net 222))
  (segment (start 174.203 77.254) (end 174.203 76.805) (width 0.1) (layer "In2.Cu") (net 222))
  (segment (start 174.203 76.805) (end 173.948 76.55) (width 0.1) (layer "In2.Cu") (net 222))
  (segment (start 152.08 71.98) (end 146.336328 66.236328) (width 0.16) (layer "In2.Cu") (net 222))
  (segment (start 177.611773 80.087783) (end 177.60399 80.08) (width 0.1) (layer "In2.Cu") (net 222))
  (segment (start 174.141 78.471) (end 174.141 77.316) (width 0.1) (layer "In2.Cu") (net 222))
  (segment (start 162.42 72.192758) (end 162.42 72.18) (width 0.16) (layer "In2.Cu") (net 222))
  (segment (start 163.27 72.23) (end 163.27 72.18) (width 0.16) (layer "In2.Cu") (net 222))
  (segment (start 170.88 71.98) (end 164.72 71.98) (width 0.16) (layer "In2.Cu") (net 222))
  (segment (start 174.141 77.316) (end 174.203 77.254) (width 0.1) (layer "In2.Cu") (net 222))
  (segment (start 163.67 72.18) (end 163.67 72.23) (width 0.16) (layer "In2.Cu") (net 222))
  (segment (start 177.60399 80.08) (end 176.10397 80.08) (width 0.1) (layer "In2.Cu") (net 222))
  (segment (start 176.10397 80.08) (end 175.600298 79.576328) (width 0.1) (layer "In2.Cu") (net 222))
  (segment (start 173.46 75.52) (end 173.46 74.56) (width 0.16) (layer "In2.Cu") (net 222))
  (segment (start 173.46 76.27) (end 173.46 75.52) (width 0.1) (layer "In2.Cu") (net 222))
  (segment (start 174.3 78.63) (end 174.141 78.471) (width 0.1) (layer "In2.Cu") (net 222))
  (arc (start 163.67 72.23) (mid 163.611421 72.371421) (end 163.47 72.43) (width 0.16) (layer "In2.Cu") (net 222))
  (arc (start 162.62 72.392758) (mid 162.478579 72.334179) (end 162.42 72.192758) (width 0.16) (layer "In2.Cu") (net 222))
  (arc (start 163.47 72.43) (mid 163.328579 72.371421) (end 163.27 72.23) (width 0.16) (layer "In2.Cu") (net 222))
  (arc (start 163.02 71.98) (mid 162.878579 72.038579) (end 162.82 72.18) (width 0.16) (layer "In2.Cu") (net 222))
  (arc (start 164.72 71.98) (mid 164.578579 72.038579) (end 164.52 72.18) (width 0.16) (layer "In2.Cu") (net 222))
  (arc (start 163.87 71.98) (mid 163.728579 72.038579) (end 163.67 72.18) (width 0.16) (layer "In2.Cu") (net 222))
  (arc (start 164.52 72.23) (mid 164.461421 72.371421) (end 164.32 72.43) (width 0.16) (layer "In2.Cu") (net 222))
  (arc (start 164.32 72.43) (mid 164.178579 72.371421) (end 164.12 72.23) (width 0.16) (layer "In2.Cu") (net 222))
  (arc (start 164.12 72.18) (mid 164.061421 72.038579) (end 163.92 71.98) (width 0.16) (layer "In2.Cu") (net 222))
  (arc (start 163.27 72.18) (mid 163.211421 72.038579) (end 163.07 71.98) (width 0.16) (layer "In2.Cu") (net 222))
  (arc (start 162.42 72.18) (mid 162.361421 72.038579) (end 162.22 71.98) (width 0.16) (layer "In2.Cu") (net 222))
  (arc (start 162.82 72.192758) (mid 162.761421 72.334179) (end 162.62 72.392758) (width 0.16) (layer "In2.Cu") (net 222))
  (segment (start 183.136328 82.560008) (end 182.636328 82.060008) (width 0.127) (layer "F.Cu") (net 223))
  (segment (start 142.936328 55.060008) (end 142.936328 56.360008) (width 0.2) (layer "F.Cu") (net 223))
  (segment (start 182.636328 82.060008) (end 182.636328 82.0405) (width 0.127) (layer "F.Cu") (net 223))
  (via blind (at 182.636328 82.0405) (size 0.5) (drill 0.2) (layers "F.Cu" "In5.Cu") (net 223))
  (via blind (at 142.936328 56.360008) (size 0.5) (drill 0.2) (layers "F.Cu" "In5.Cu") (net 223))
  (segment (start 142.936328 59.636328) (end 142.936328 56.360008) (width 0.146) (layer "In5.Cu") (net 223))
  (segment (start 165.387937 73.705093) (end 165.387937 73.705094) (width 0.146) (layer "In5.Cu") (net 223))
  (segment (start 166.236468 74.270783) (end 166.236468 74.270782) (width 0.146) (layer "In5.Cu") (net 223))
  (segment (start 161.710965 70.310966) (end 161.710966 70.310966) (width 0.146) (layer "In5.Cu") (net 223))
  (segment (start 164.82225 73.987935) (end 164.82225 73.987936) (width 0.146) (layer "In5.Cu") (net 223))
  (segment (start 162.559497 70.876653) (end 162.559497 70.876654) (width 0.146) (layer "In5.Cu") (net 223))
  (segment (start 161.993809 70.876653) (end 161.993809 70.876652) (width 0.146) (layer "In5.Cu") (net 223))
  (segment (start 166.519313 75.402157) (end 166.519313 75.402156) (width 0.146) (layer "In5.Cu") (net 223))
  (segment (start 180.181364 79.585536) (end 182.636328 82.0405) (width 0.09) (layer "In5.Cu") (net 223))
  (segment (start 163.125185 72.008029) (end 163.125185 72.008028) (width 0.146) (layer "In5.Cu") (net 223))
  (segment (start 163.408028 71.442343) (end 163.408028 71.442342) (width 0.146) (layer "In5.Cu") (net 223))
  (segment (start 152.8068 69.824999) (end 152.682462 69.949338) (width 0.146) (layer "In5.Cu") (net 223))
  (segment (start 152.806801 69.824999) (end 152.8068 69.824999) (width 0.146) (layer "In5.Cu") (net 223))
  (segment (start 165.953625 74.270782) (end 165.67078 74.553623) (width 0.146) (layer "In5.Cu") (net 223))
  (segment (start 169.65 75.65) (end 175.15 75.65) (width 0.09) (layer "In5.Cu") (net 223))
  (segment (start 165.105092 73.139407) (end 165.105092 73.139406) (width 0.146) (layer "In5.Cu") (net 223))
  (segment (start 163.690873 72.00803) (end 163.408028 72.290871) (width 0.146) (layer "In5.Cu") (net 223))
  (segment (start 164.539404 72.573719) (end 164.539404 72.573718) (width 0.146) (layer "In5.Cu") (net 223))
  (segment (start 169.117 75.943) (end 167.343 75.943) (width 0.146) (layer "In5.Cu") (net 223))
  (segment (start 162.559497 70.876654) (end 162.276652 71.159495) (width 0.146) (layer "In5.Cu") (net 223))
  (segment (start 166.519313 75.402156) (end 166.802156 75.119313) (width 0.146) (layer "In5.Cu") (net 223))
  (segment (start 164.256561 72.573717) (end 164.256561 72.573718) (width 0.146) (layer "In5.Cu") (net 223))
  (segment (start 161.993809 70.876652) (end 162.276652 70.593809) (width 0.146) (layer "In5.Cu") (net 223))
  (segment (start 176.03 76.53) (end 176.03 77.48) (width 0.09) (layer "In5.Cu") (net 223))
  (segment (start 165.953625 74.836469) (end 165.953625 74.836468) (width 0.146) (layer "In5.Cu") (net 223))
  (segment (start 164.822249 73.705092) (end 165.105092 73.422249) (width 0.146) (layer "In5.Cu") (net 223))
  (segment (start 165.953626 75.119311) (end 165.953626 75.119312) (width 0.146) (layer "In5.Cu") (net 223))
  (segment (start 176.03 77.48) (end 177.0055 78.4555) (width 0.09) (layer "In5.Cu") (net 223))
  (segment (start 142.936328 59.636328) (end 152.170402 68.870403) (width 0.146) (layer "In5.Cu") (net 223))
  (segment (start 177.0055 78.4555) (end 179.638227 78.4555) (width 0.09) (layer "In5.Cu") (net 223))
  (segment (start 179.638227 78.4555) (end 180.181364 78.998636) (width 0.09) (layer "In5.Cu") (net 223))
  (segment (start 161.710966 70.310966) (end 161.5 70.1) (width 0.146) (layer "In5.Cu") (net 223))
  (segment (start 180.181364 78.998636) (end 180.181364 79.585536) (width 0.09) (layer "In5.Cu") (net 223))
  (segment (start 165.387937 73.705094) (end 165.105092 73.987935) (width 0.146) (layer "In5.Cu") (net 223))
  (segment (start 162.559498 71.725183) (end 162.559498 71.725184) (width 0.146) (layer "In5.Cu") (net 223))
  (segment (start 165.67078 73.705095) (end 165.67078 73.705094) (width 0.146) (layer "In5.Cu") (net 223))
  (segment (start 163.690873 72.573717) (end 163.690873 72.573716) (width 0.146) (layer "In5.Cu") (net 223))
  (segment (start 169.12 75.94) (end 169.36 75.94) (width 0.09) (layer "In5.Cu") (net 223))
  (segment (start 162.276652 70.310967) (end 162.276652 70.310966) (width 0.146) (layer "In5.Cu") (net 223))
  (segment (start 166.802156 74.836471) (end 166.802156 74.83647) (width 0.146) (layer "In5.Cu") (net 223))
  (segment (start 165.387937 74.270781) (end 165.387937 74.27078) (width 0.146) (layer "In5.Cu") (net 223))
  (segment (start 163.690874 72.856559) (end 163.690874 72.85656) (width 0.146) (layer "In5.Cu") (net 223))
  (segment (start 163.125186 72.290871) (end 163.125186 72.290872) (width 0.146) (layer "In5.Cu") (net 223))
  (segment (start 166.519313 74.836469) (end 166.519313 74.83647) (width 0.146) (layer "In5.Cu") (net 223))
  (segment (start 153.4 70.1) (end 153.125 69.825) (width 0.146) (layer "In5.Cu") (net 223))
  (segment (start 164.256561 72.573718) (end 163.973716 72.856559) (width 0.146) (layer "In5.Cu") (net 223))
  (segment (start 152.612939 68.746065) (end 152.4886 68.870403) (width 0.146) (layer "In5.Cu") (net 223))
  (segment (start 163.973716 72.008031) (end 163.973716 72.00803) (width 0.146) (layer "In5.Cu") (net 223))
  (segment (start 165.953625 74.270781) (end 165.953625 74.270782) (width 0.146) (layer "In5.Cu") (net 223))
  (segment (start 162.84234 70.876655) (end 162.84234 70.876654) (width 0.146) (layer "In5.Cu") (net 223))
  (segment (start 164.822249 73.705093) (end 164.822249 73.705092) (width 0.146) (layer "In5.Cu") (net 223))
  (segment (start 165.387938 74.553623) (end 165.387938 74.553624) (width 0.146) (layer "In5.Cu") (net 223))
  (segment (start 162.559497 71.442341) (end 162.559497 71.44234) (width 0.146) (layer "In5.Cu") (net 223))
  (segment (start 162.559497 71.44234) (end 162.84234 71.159497) (width 0.146) (layer "In5.Cu") (net 223))
  (segment (start 163.690873 72.573716) (end 163.973716 72.290873) (width 0.146) (layer "In5.Cu") (net 223))
  (segment (start 166.519313 74.83647) (end 166.236468 75.119311) (width 0.146) (layer "In5.Cu") (net 223))
  (segment (start 165.953625 74.836468) (end 166.236468 74.553625) (width 0.146) (layer "In5.Cu") (net 223))
  (segment (start 161.5 70.1) (end 153.4 70.1) (width 0.146) (layer "In5.Cu") (net 223))
  (segment (start 163.125185 71.442342) (end 162.84234 71.725183) (width 0.146) (layer "In5.Cu") (net 223))
  (segment (start 164.256561 73.139404) (end 164.539404 72.856561) (width 0.146) (layer "In5.Cu") (net 223))
  (segment (start 152.364263 69.631139) (end 152.364263 69.631138) (width 0.146) (layer "In5.Cu") (net 223))
  (segment (start 163.125185 72.008028) (end 163.408028 71.725185) (width 0.146) (layer "In5.Cu") (net 223))
  (segment (start 164.822249 73.139406) (end 164.539404 73.422247) (width 0.146) (layer "In5.Cu") (net 223))
  (segment (start 152.364263 69.631138) (end 152.931138 69.064263) (width 0.146) (layer "In5.Cu") (net 223))
  (segment (start 164.256562 73.422247) (end 164.256562 73.422248) (width 0.146) (layer "In5.Cu") (net 223))
  (segment (start 169.12 75.94) (end 169.117 75.943) (width 0.146) (layer "In5.Cu") (net 223))
  (segment (start 163.690873 72.008029) (end 163.690873 72.00803) (width 0.146) (layer "In5.Cu") (net 223))
  (segment (start 163.125185 71.442341) (end 163.125185 71.442342) (width 0.146) (layer "In5.Cu") (net 223))
  (segment (start 164.256561 73.139405) (end 164.256561 73.139404) (width 0.146) (layer "In5.Cu") (net 223))
  (segment (start 161.993809 70.310965) (end 161.993809 70.310966) (width 0.146) (layer "In5.Cu") (net 223))
  (segment (start 152.612939 68.746064) (end 152.612939 68.746065) (width 0.146) (layer "In5.Cu") (net 223))
  (segment (start 166.519312 75.684999) (end 166.519314 75.685) (width 0.146) (layer "In5.Cu") (net 223))
  (segment (start 167.343 75.943) (end 167.085 75.685) (width 0.146) (layer "In5.Cu") (net 223))
  (segment (start 169.36 75.94) (end 169.65 75.65) (width 0.09) (layer "In5.Cu") (net 223))
  (segment (start 165.387937 74.27078) (end 165.67078 73.987937) (width 0.146) (layer "In5.Cu") (net 223))
  (segment (start 166.802157 75.684999) (end 166.802156 75.684999) (width 0.146) (layer "In5.Cu") (net 223))
  (segment (start 164.822249 73.139405) (end 164.822249 73.139406) (width 0.146) (layer "In5.Cu") (net 223))
  (segment (start 175.15 75.65) (end 176.03 76.53) (width 0.09) (layer "In5.Cu") (net 223))
  (segment (start 161.99381 71.159495) (end 161.99381 71.159496) (width 0.146) (layer "In5.Cu") (net 223))
  (arc (start 161.993809 70.310966) (mid 161.852387 70.369545) (end 161.710965 70.310966) (width 0.146) (layer "In5.Cu") (net 223))
  (arc (start 163.690874 72.85656) (mid 163.632295 72.715139) (end 163.690873 72.573717) (width 0.146) (layer "In5.Cu") (net 223))
  (arc (start 165.67078 73.987937) (mid 165.729358 73.846516) (end 165.67078 73.705095) (width 0.146) (layer "In5.Cu") (net 223))
  (arc (start 163.408028 72.290871) (mid 163.266608 72.34945) (end 163.125186 72.290871) (width 0.146) (layer "In5.Cu") (net 223))
  (arc (start 162.276652 70.593809) (mid 162.33523 70.452388) (end 162.276652 70.310967) (width 0.146) (layer "In5.Cu") (net 223))
  (arc (start 162.84234 71.725183) (mid 162.70092 71.783762) (end 162.559498 71.725183) (width 0.146) (layer "In5.Cu") (net 223))
  (arc (start 163.408028 71.725185) (mid 163.466606 71.583764) (end 163.408028 71.442343) (width 0.146) (layer "In5.Cu") (net 223))
  (arc (start 162.559498 71.725184) (mid 162.500919 71.583763) (end 162.559497 71.442341) (width 0.146) (layer "In5.Cu") (net 223))
  (arc (start 153.125 69.825) (mid 152.9659 69.759097) (end 152.806801 69.824999) (width 0.146) (layer "In5.Cu") (net 223))
  (arc (start 165.105092 73.422249) (mid 165.16367 73.280828) (end 165.105092 73.139407) (width 0.146) (layer "In5.Cu") (net 223))
  (arc (start 163.125186 72.290872) (mid 163.066607 72.149451) (end 163.125185 72.008029) (width 0.146) (layer "In5.Cu") (net 223))
  (arc (start 163.973716 72.856559) (mid 163.832296 72.915138) (end 163.690874 72.856559) (width 0.146) (layer "In5.Cu") (net 223))
  (arc (start 164.82225 73.987936) (mid 164.763671 73.846515) (end 164.822249 73.705093) (width 0.146) (layer "In5.Cu") (net 223))
  (arc (start 164.539404 72.573718) (mid 164.397983 72.515139) (end 164.256561 72.573717) (width 0.146) (layer "In5.Cu") (net 223))
  (arc (start 162.276652 71.159495) (mid 162.135232 71.218074) (end 161.99381 71.159495) (width 0.146) (layer "In5.Cu") (net 223))
  (arc (start 164.539404 72.856561) (mid 164.597982 72.71514) (end 164.539404 72.573719) (width 0.146) (layer "In5.Cu") (net 223))
  (arc (start 152.931138 68.746065) (mid 152.772039 68.680163) (end 152.612939 68.746064) (width 0.146) (layer "In5.Cu") (net 223))
  (arc (start 163.408028 71.442342) (mid 163.266607 71.383763) (end 163.125185 71.442341) (width 0.146) (layer "In5.Cu") (net 223))
  (arc (start 152.931138 69.064263) (mid 152.997039 68.905164) (end 152.931138 68.746065) (width 0.146) (layer "In5.Cu") (net 223))
  (arc (start 152.682462 69.949338) (mid 152.523363 70.015239) (end 152.364264 69.949338) (width 0.146) (layer "In5.Cu") (net 223))
  (arc (start 165.67078 74.553623) (mid 165.52936 74.612202) (end 165.387938 74.553623) (width 0.146) (layer "In5.Cu") (net 223))
  (arc (start 166.802156 75.684999) (mid 166.660735 75.743579) (end 166.519312 75.684999) (width 0.146) (layer "In5.Cu") (net 223))
  (arc (start 166.236468 75.119311) (mid 166.095048 75.17789) (end 165.953626 75.119311) (width 0.146) (layer "In5.Cu") (net 223))
  (arc (start 165.67078 73.705094) (mid 165.529359 73.646515) (end 165.387937 73.705093) (width 0.146) (layer "In5.Cu") (net 223))
  (arc (start 152.4886 68.870403) (mid 152.329501 68.936304) (end 152.170402 68.870403) (width 0.146) (layer "In5.Cu") (net 223))
  (arc (start 164.256562 73.422248) (mid 164.197983 73.280827) (end 164.256561 73.139405) (width 0.146) (layer "In5.Cu") (net 223))
  (arc (start 162.84234 70.876654) (mid 162.700919 70.818075) (end 162.559497 70.876653) (width 0.146) (layer "In5.Cu") (net 223))
  (arc (start 163.973716 72.290873) (mid 164.032294 72.149452) (end 163.973716 72.008031) (width 0.146) (layer "In5.Cu") (net 223))
  (arc (start 167.085 75.685) (mid 166.943579 75.626421) (end 166.802157 75.684999) (width 0.146) (layer "In5.Cu") (net 223))
  (arc (start 166.802156 75.119313) (mid 166.860734 74.977892) (end 166.802156 74.836471) (width 0.146) (layer "In5.Cu") (net 223))
  (arc (start 161.99381 71.159496) (mid 161.935231 71.018075) (end 161.993809 70.876653) (width 0.146) (layer "In5.Cu") (net 223))
  (arc (start 162.84234 71.159497) (mid 162.900918 71.018076) (end 162.84234 70.876655) (width 0.146) (layer "In5.Cu") (net 223))
  (arc (start 163.973716 72.00803) (mid 163.832295 71.949451) (end 163.690873 72.008029) (width 0.146) (layer "In5.Cu") (net 223))
  (arc (start 165.953626 75.119312) (mid 165.895047 74.977891) (end 165.953625 74.836469) (width 0.146) (layer "In5.Cu") (net 223))
  (arc (start 164.539404 73.422247) (mid 164.397984 73.480826) (end 164.256562 73.422247) (width 0.146) (layer "In5.Cu") (net 223))
  (arc (start 162.276652 70.310966) (mid 162.135231 70.252387) (end 161.993809 70.310965) (width 0.146) (layer "In5.Cu") (net 223))
  (arc (start 166.802156 74.83647) (mid 166.660735 74.777891) (end 166.519313 74.836469) (width 0.146) (layer "In5.Cu") (net 223))
  (arc (start 166.519314 75.685) (mid 166.460735 75.543579) (end 166.519313 75.402157) (width 0.146) (layer "In5.Cu") (net 223))
  (arc (start 152.364264 69.949338) (mid 152.298361 69.790238) (end 152.364263 69.631139) (width 0.146) (layer "In5.Cu") (net 223))
  (arc (start 165.387938 74.553624) (mid 165.329359 74.412203) (end 165.387937 74.270781) (width 0.146) (layer "In5.Cu") (net 223))
  (arc (start 166.236468 74.270782) (mid 166.095047 74.212203) (end 165.953625 74.270781) (width 0.146) (layer "In5.Cu") (net 223))
  (arc (start 166.236468 74.553625) (mid 166.295046 74.412204) (end 166.236468 74.270783) (width 0.146) (layer "In5.Cu") (net 223))
  (arc (start 165.105092 73.987935) (mid 164.963672 74.046514) (end 164.82225 73.987935) (width 0.146) (layer "In5.Cu") (net 223))
  (arc (start 165.105092 73.139406) (mid 164.963671 73.080827) (end 164.822249 73.139405) (width 0.146) (layer "In5.Cu") (net 223))
  (segment (start 181.136328 80.560008) (end 180.636328 80.060008) (width 0.127) (layer "F.Cu") (net 224))
  (segment (start 144.636328 55.060008) (end 144.636328 56.360008) (width 0.2) (layer "F.Cu") (net 224))
  (via blind (at 180.636328 80.060008) (size 0.5) (drill 0.2) (layers "F.Cu" "In2.Cu") (net 224))
  (via blind (at 144.636328 56.360008) (size 0.5) (drill 0.2) (layers "F.Cu" "In2.Cu") (net 224))
  (segment (start 172.127 76.919) (end 172.127 79.214142) (width 0.1) (layer "In2.Cu") (net 224))
  (segment (start 179.24 81.32) (end 179.24 80.97) (width 0.1) (layer "In2.Cu") (net 224))
  (segment (start 144.636328 67.426328) (end 151.11 73.9) (width 0.16) (layer "In2.Cu") (net 224))
  (segment (start 171.81 75.5) (end 171.81 76.602) (width 0.1) (layer "In2.Cu") (net 224))
  (segment (start 175.805579 80.933579) (end 176.392 81.52) (width 0.1) (layer "In2.Cu") (net 224))
  (segment (start 176.392 81.52) (end 179.04 81.52) (width 0.1) (layer "In2.Cu") (net 224))
  (segment (start 179.62 80.59) (end 180.106336 80.59) (width 0.1) (layer "In2.Cu") (net 224))
  (segment (start 172.552866 79.640008) (end 172.990008 79.640008) (width 0.1) (layer "In2.Cu") (net 224))
  (segment (start 174.722843 80.22) (end 175.436421 80.933579) (width 0.1) (layer "In2.Cu") (net 224))
  (segment (start 180.106336 80.59) (end 180.636328 80.060008) (width 0.1) (layer "In2.Cu") (net 224))
  (segment (start 144.636328 56.360008) (end 144.636328 67.426328) (width 0.16) (layer "In2.Cu") (net 224))
  (segment (start 172.990008 79.640008) (end 173.57 80.22) (width 0.1) (layer "In2.Cu") (net 224))
  (segment (start 151.11 73.9) (end 170.55 73.9) (width 0.16) (layer "In2.Cu") (net 224))
  (segment (start 173.57 80.22) (end 174.722843 80.22) (width 0.1) (layer "In2.Cu") (net 224))
  (segment (start 171.81 75.16) (end 171.81 75.5) (width 0.16) (layer "In2.Cu") (net 224))
  (segment (start 175.436421 80.933579) (end 175.805579 80.933579) (width 0.1) (layer "In2.Cu") (net 224))
  (segment (start 179.04 81.52) (end 179.24 81.32) (width 0.1) (layer "In2.Cu") (net 224))
  (segment (start 179.24 80.97) (end 179.62 80.59) (width 0.1) (layer "In2.Cu") (net 224))
  (segment (start 172.127 79.214142) (end 172.552866 79.640008) (width 0.1) (layer "In2.Cu") (net 224))
  (segment (start 170.55 73.9) (end 171.81 75.16) (width 0.16) (layer "In2.Cu") (net 224))
  (segment (start 171.81 76.602) (end 172.127 76.919) (width 0.1) (layer "In2.Cu") (net 224))
  (segment (start 181.636328 82.060008) (end 181.636328 82.0405) (width 0.127) (layer "F.Cu") (net 225))
  (segment (start 182.136328 82.560008) (end 181.636328 82.060008) (width 0.127) (layer "F.Cu") (net 225))
  (segment (start 141.236328 55.060008) (end 141.236328 56.360008) (width 0.2) (layer "F.Cu") (net 225))
  (via blind (at 141.236328 56.360008) (size 0.5) (drill 0.2) (layers "F.Cu" "In5.Cu") (net 225))
  (via blind (at 181.636328 82.0405) (size 0.5) (drill 0.2) (layers "F.Cu" "In5.Cu") (net 225))
  (segment (start 164.366901 75.081058) (end 164.084056 75.363899) (width 0.146) (layer "In5.Cu") (net 225))
  (segment (start 180.226 81.386) (end 180.226 80.651136) (width 0.09) (layer "In5.Cu") (net 225))
  (segment (start 163.164814 74.7275) (end 163.129458 74.692144) (width 0.146) (layer "In5.Cu") (net 225))
  (segment (start 147.037695 66.35742) (end 147.037694 66.357421) (width 0.146) (layer "In5.Cu") (net 225))
  (segment (start 147.010977 67.444804) (end 147.010976 67.444803) (width 0.146) (layer "In5.Cu") (net 225))
  (segment (start 148.085 67.431446) (end 148.09836 67.418085) (width 0.146) (layer "In5.Cu") (net 225))
  (segment (start 178.634864 79.06) (end 176.42 79.06) (width 0.09) (layer "In5.Cu") (net 225))
  (segment (start 147.744807 67.064531) (end 147.744806 67.064532) (width 0.146) (layer "In5.Cu") (net 225))
  (segment (start 162.493057 73.7729) (end 162.7759 73.490057) (width 0.146) (layer "In5.Cu") (net 225))
  (segment (start 165.003301 75.717458) (end 164.720456 76.000299) (width 0.146) (layer "In5.Cu") (net 225))
  (segment (start 180.37 81.53) (end 180.226 81.386) (width 0.09) (layer "In5.Cu") (net 225))
  (segment (start 161.892014 73.454699) (end 161.892014 73.4547) (width 0.146) (layer "In5.Cu") (net 225))
  (segment (start 146.330584 65.650309) (end 146.330583 65.65031) (width 0.146) (layer "In5.Cu") (net 225))
  (segment (start 162.457701 73.171858) (end 162.174856 73.454699) (width 0.146) (layer "In5.Cu") (net 225))
  (segment (start 163.730501 74.444658) (end 163.447656 74.727499) (width 0.146) (layer "In5.Cu") (net 225))
  (segment (start 150.816471 70.516471) (end 148.085 67.785) (width 0.146) (layer "In5.Cu") (net 225))
  (segment (start 164.437614 76.0003) (end 164.402258 75.964944) (width 0.146) (layer "In5.Cu") (net 225))
  (segment (start 166.093 77.09) (end 165.3215 76.3185) (width 0.146) (layer "In5.Cu") (net 225))
  (segment (start 145.963669 65.663669) (end 145.963669 65.66367) (width 0.146) (layer "In5.Cu") (net 225))
  (segment (start 147.010976 67.091249) (end 147.391248 66.710975) (width 0.146) (layer "In5.Cu") (net 225))
  (segment (start 165.3215 75.752814) (end 165.286144 75.717458) (width 0.146) (layer "In5.Cu") (net 225))
  (segment (start 163.094101 73.808258) (end 162.811256 74.091099) (width 0.146) (layer "In5.Cu") (net 225))
  (segment (start 163.094101 73.808259) (end 163.094101 73.808258) (width 0.146) (layer "In5.Cu") (net 225))
  (segment (start 147.391249 66.357422) (end 147.391248 66.357421) (width 0.146) (layer "In5.Cu") (net 225))
  (segment (start 180.226 80.651136) (end 178.634864 79.06) (width 0.09) (layer "In5.Cu") (net 225))
  (segment (start 148.084999 67.431447) (end 148.085 67.431446) (width 0.146) (layer "In5.Cu") (net 225))
  (segment (start 161.255614 72.818299) (end 161.255614 72.8183) (width 0.146) (layer "In5.Cu") (net 225))
  (segment (start 160.503 71.5) (end 151.8 71.5) (width 0.146) (layer "In5.Cu") (net 225))
  (segment (start 147.744806 67.064532) (end 147.36453 67.444803) (width 0.146) (layer "In5.Cu") (net 225))
  (segment (start 163.801214 75.3639) (end 163.765858 75.328544) (width 0.146) (layer "In5.Cu") (net 225))
  (segment (start 162.528414 74.0911) (end 162.493058 74.055744) (width 0.146) (layer "In5.Cu") (net 225))
  (segment (start 161.821301 72.535459) (end 161.821301 72.535458) (width 0.146) (layer "In5.Cu") (net 225))
  (segment (start 161.5031 71.934414) (end 161.467744 71.899058) (width 0.146) (layer "In5.Cu") (net 225))
  (segment (start 162.1395 72.570814) (end 162.104144 72.535458) (width 0.146) (layer "In5.Cu") (net 225))
  (segment (start 151.8 71.5) (end 151.665 71.365) (width 0.146) (layer "In5.Cu") (net 225))
  (segment (start 145.963669 65.66367) (end 141.236328 60.936328) (width 0.146) (layer "In5.Cu") (net 225))
  (segment (start 164.437614 76.000299) (end 164.437614 76.0003) (width 0.146) (layer "In5.Cu") (net 225))
  (segment (start 147.010975 67.09125) (end 147.010976 67.091249) (width 0.146) (layer "In5.Cu") (net 225))
  (segment (start 171.633668 77.475769) (end 171.509437 77.6) (width 0.09) (layer "In5.Cu") (net 225))
  (segment (start 162.7759 73.207215) (end 162.7759 73.207214) (width 0.146) (layer "In5.Cu") (net 225))
  (segment (start 164.0487 74.480015) (end 164.0487 74.480014) (width 0.146) (layer "In5.Cu") (net 225))
  (segment (start 147.037694 66.357421) (end 146.657419 66.737692) (width 0.146) (layer "In5.Cu") (net 225))
  (segment (start 160.902058 71.899058) (end 160.503 71.5) (width 0.146) (layer "In5.Cu") (net 225))
  (segment (start 146.303865 66.384138) (end 146.684137 66.003864) (width 0.146) (layer "In5.Cu") (net 225))
  (segment (start 162.528414 74.091099) (end 162.528414 74.0911) (width 0.146) (layer "In5.Cu") (net 225))
  (segment (start 163.730501 74.444659) (end 163.730501 74.444658) (width 0.146) (layer "In5.Cu") (net 225))
  (segment (start 162.7759 73.207214) (end 162.740544 73.171858) (width 0.146) (layer "In5.Cu") (net 225))
  (segment (start 163.765859 75.045701) (end 163.765857 75.0457) (width 0.146) (layer "In5.Cu") (net 225))
  (segment (start 161.892014 73.4547) (end 161.856658 73.419344) (width 0.146) (layer "In5.Cu") (net 225))
  (segment (start 161.821301 72.535458) (end 161.538456 72.818299) (width 0.146) (layer "In5.Cu") (net 225))
  (segment (start 170.3 77.6) (end 169.79 77.09) (width 0.09) (layer "In5.Cu") (net 225))
  (segment (start 165.003301 75.717459) (end 165.003301 75.717458) (width 0.146) (layer "In5.Cu") (net 225))
  (segment (start 161.220257 72.5001) (end 161.5031 72.217257) (width 0.146) (layer "In5.Cu") (net 225))
  (segment (start 164.6851 75.116415) (end 164.6851 75.116414) (width 0.146) (layer "In5.Cu") (net 225))
  (segment (start 146.330583 65.65031) (end 146.317222 65.66367) (width 0.146) (layer "In5.Cu") (net 225))
  (segment (start 150.887181 70.587181) (end 150.816471 70.516471) (width 0.146) (layer "In5.Cu") (net 225))
  (segment (start 146.684138 65.650311) (end 146.684137 65.65031) (width 0.146) (layer "In5.Cu") (net 225))
  (segment (start 163.4123 73.843614) (end 163.376944 73.808258) (width 0.146) (layer "In5.Cu") (net 225))
  (segment (start 164.402259 75.682101) (end 164.402257 75.6821) (width 0.146) (layer "In5.Cu") (net 225))
  (segment (start 146.303864 66.384139) (end 146.303865 66.384138) (width 0.146) (layer "In5.Cu") (net 225))
  (segment (start 161.255614 72.8183) (end 161.220258 72.782944) (width 0.146) (layer "In5.Cu") (net 225))
  (segment (start 162.493059 73.772901) (end 162.493057 73.7729) (width 0.146) (layer "In5.Cu") (net 225))
  (segment (start 165.3215 75.752813) (end 165.3215 75.752814) (width 0.146) (layer "In5.Cu") (net 225))
  (segment (start 163.4123 73.843615) (end 163.4123 73.843614) (width 0.146) (layer "In5.Cu") (net 225))
  (segment (start 164.402257 75.6821) (end 164.6851 75.399257) (width 0.146) (layer "In5.Cu") (net 225))
  (segment (start 181.636328 82.0405) (end 181.125828 81.53) (width 0.09) (layer "In5.Cu") (net 225))
  (segment (start 163.765857 75.0457) (end 164.0487 74.762857) (width 0.146) (layer "In5.Cu") (net 225))
  (segment (start 161.856659 73.136501) (end 161.856657 73.1365) (width 0.146) (layer "In5.Cu") (net 225))
  (segment (start 151.665 70.657892) (end 151.594289 70.587181) (width 0.146) (layer "In5.Cu") (net 225))
  (segment (start 164.6851 75.116414) (end 164.649744 75.081058) (width 0.146) (layer "In5.Cu") (net 225))
  (segment (start 161.184901 71.899059) (end 161.184901 71.899058) (width 0.146) (layer "In5.Cu") (net 225))
  (segment (start 151.664999 71.011447) (end 151.665 71.011446) (width 0.146) (layer "In5.Cu") (net 225))
  (segment (start 160.902057 71.899058) (end 160.902058 71.899058) (width 0.146) (layer "In5.Cu") (net 225))
  (segment (start 164.0487 74.480014) (end 164.013344 74.444658) (width 0.146) (layer "In5.Cu") (net 225))
  (segment (start 176.42 79.06) (end 174.835769 77.475769) (width 0.09) (layer "In5.Cu") (net 225))
  (segment (start 162.457701 73.171859) (end 162.457701 73.171858) (width 0.146) (layer "In5.Cu") (net 225))
  (segment (start 171.509437 77.6) (end 170.3 77.6) (width 0.09) (layer "In5.Cu") (net 225))
  (segment (start 162.1395 72.570815) (end 162.1395 72.570814) (width 0.146) (layer "In5.Cu") (net 225))
  (segment (start 174.835769 77.475769) (end 171.633668 77.475769) (width 0.09) (layer "In5.Cu") (net 225))
  (segment (start 163.801214 75.363899) (end 163.801214 75.3639) (width 0.146) (layer "In5.Cu") (net 225))
  (segment (start 181.125828 81.53) (end 180.37 81.53) (width 0.09) (layer "In5.Cu") (net 225))
  (segment (start 148.098359 67.064532) (end 148.09836 67.064532) (width 0.146) (layer "In5.Cu") (net 225))
  (segment (start 163.129459 74.409301) (end 163.129457 74.4093) (width 0.146) (layer "In5.Cu") (net 225))
  (segment (start 161.220259 72.500101) (end 161.220257 72.5001) (width 0.146) (layer "In5.Cu") (net 225))
  (segment (start 161.856657 73.1365) (end 162.1395 72.853657) (width 0.146) (layer "In5.Cu") (net 225))
  (segment (start 169.79 77.09) (end 169.13 77.09) (width 0.09) (layer "In5.Cu") (net 225))
  (segment (start 169.13 77.09) (end 166.093 77.09) (width 0.146) (layer "In5.Cu") (net 225))
  (segment (start 163.164814 74.727499) (end 163.164814 74.7275) (width 0.146) (layer "In5.Cu") (net 225))
  (segment (start 165.321499 76.035657) (end 165.3215 76.035657) (width 0.146) (layer "In5.Cu") (net 225))
  (segment (start 146.303866 66.737693) (end 146.303865 66.737692) (width 0.146) (layer "In5.Cu") (net 225))
  (segment (start 164.366901 75.081059) (end 164.366901 75.081058) (width 0.146) (layer "In5.Cu") (net 225))
  (segment (start 163.129457 74.4093) (end 163.4123 74.126457) (width 0.146) (layer "In5.Cu") (net 225))
  (segment (start 141.236328 60.936328) (end 141.236328 56.360008) (width 0.146) (layer "In5.Cu") (net 225))
  (segment (start 161.5031 71.934415) (end 161.5031 71.934414) (width 0.146) (layer "In5.Cu") (net 225))
  (arc (start 163.765858 75.328544) (mid 163.70728 75.187122) (end 163.765859 75.045701) (width 0.146) (layer "In5.Cu") (net 225))
  (arc (start 151.240735 70.587181) (mid 151.063958 70.660404) (end 150.887181 70.587181) (width 0.146) (layer "In5.Cu") (net 225))
  (arc (start 148.085 67.785) (mid 148.011776 67.608224) (end 148.084999 67.431447) (width 0.146) (layer "In5.Cu") (net 225))
  (arc (start 164.402258 75.964944) (mid 164.34368 75.823522) (end 164.402259 75.682101) (width 0.146) (layer "In5.Cu") (net 225))
  (arc (start 162.740544 73.171858) (mid 162.599122 73.11328) (end 162.457701 73.171859) (width 0.146) (layer "In5.Cu") (net 225))
  (arc (start 163.129458 74.692144) (mid 163.07088 74.550722) (end 163.129459 74.409301) (width 0.146) (layer "In5.Cu") (net 225))
  (arc (start 164.649744 75.081058) (mid 164.508322 75.02248) (end 164.366901 75.081059) (width 0.146) (layer "In5.Cu") (net 225))
  (arc (start 161.856658 73.419344) (mid 161.79808 73.277922) (end 161.856659 73.136501) (width 0.146) (layer "In5.Cu") (net 225))
  (arc (start 146.684137 65.65031) (mid 146.507361 65.577086) (end 146.330584 65.650309) (width 0.146) (layer "In5.Cu") (net 225))
  (arc (start 146.317222 65.66367) (mid 146.140445 65.736893) (end 145.963669 65.663669) (width 0.146) (layer "In5.Cu") (net 225))
  (arc (start 147.36453 67.444803) (mid 147.187754 67.518027) (end 147.010977 67.444804) (width 0.146) (layer "In5.Cu") (net 225))
  (arc (start 161.5031 72.217257) (mid 161.561678 72.075836) (end 161.5031 71.934415) (width 0.146) (layer "In5.Cu") (net 225))
  (arc (start 161.538456 72.818299) (mid 161.397036 72.876878) (end 161.255614 72.818299) (width 0.146) (layer "In5.Cu") (net 225))
  (arc (start 164.0487 74.762857) (mid 164.107278 74.621436) (end 164.0487 74.480015) (width 0.146) (layer "In5.Cu") (net 225))
  (arc (start 161.184901 71.899058) (mid 161.043479 71.957637) (end 160.902057 71.899058) (width 0.146) (layer "In5.Cu") (net 225))
  (arc (start 162.104144 72.535458) (mid 161.962722 72.47688) (end 161.821301 72.535459) (width 0.146) (layer "In5.Cu") (net 225))
  (arc (start 147.010976 67.444803) (mid 146.937752 67.268027) (end 147.010975 67.09125) (width 0.146) (layer "In5.Cu") (net 225))
  (arc (start 146.303865 66.737692) (mid 146.230641 66.560916) (end 146.303864 66.384139) (width 0.146) (layer "In5.Cu") (net 225))
  (arc (start 161.220258 72.782944) (mid 161.16168 72.641522) (end 161.220259 72.500101) (width 0.146) (layer "In5.Cu") (net 225))
  (arc (start 151.665 71.011446) (mid 151.738223 70.834669) (end 151.665 70.657892) (width 0.146) (layer "In5.Cu") (net 225))
  (arc (start 164.013344 74.444658) (mid 163.871922 74.38608) (end 163.730501 74.444659) (width 0.146) (layer "In5.Cu") (net 225))
  (arc (start 163.376944 73.808258) (mid 163.235522 73.74968) (end 163.094101 73.808259) (width 0.146) (layer "In5.Cu") (net 225))
  (arc (start 165.3215 76.035657) (mid 165.380079 75.894235) (end 165.3215 75.752813) (width 0.146) (layer "In5.Cu") (net 225))
  (arc (start 161.467744 71.899058) (mid 161.326322 71.84048) (end 161.184901 71.899059) (width 0.146) (layer "In5.Cu") (net 225))
  (arc (start 162.1395 72.853657) (mid 162.198078 72.712236) (end 162.1395 72.570815) (width 0.146) (layer "In5.Cu") (net 225))
  (arc (start 164.084056 75.363899) (mid 163.942636 75.422478) (end 163.801214 75.363899) (width 0.146) (layer "In5.Cu") (net 225))
  (arc (start 162.493058 74.055744) (mid 162.43448 73.914322) (end 162.493059 73.772901) (width 0.146) (layer "In5.Cu") (net 225))
  (arc (start 164.720456 76.000299) (mid 164.579036 76.058878) (end 164.437614 76.000299) (width 0.146) (layer "In5.Cu") (net 225))
  (arc (start 163.4123 74.126457) (mid 163.470878 73.985036) (end 163.4123 73.843615) (width 0.146) (layer "In5.Cu") (net 225))
  (arc (start 151.665 71.365) (mid 151.591776 71.188224) (end 151.664999 71.011447) (width 0.146) (layer "In5.Cu") (net 225))
  (arc (start 162.174856 73.454699) (mid 162.033436 73.513278) (end 161.892014 73.454699) (width 0.146) (layer "In5.Cu") (net 225))
  (arc (start 147.391248 66.710975) (mid 147.464472 66.534199) (end 147.391249 66.357422) (width 0.146) (layer "In5.Cu") (net 225))
  (arc (start 165.286144 75.717458) (mid 165.144722 75.65888) (end 165.003301 75.717459) (width 0.146) (layer "In5.Cu") (net 225))
  (arc (start 165.3215 76.3185) (mid 165.262921 76.177079) (end 165.321499 76.035657) (width 0.146) (layer "In5.Cu") (net 225))
  (arc (start 147.391248 66.357421) (mid 147.214472 66.284197) (end 147.037695 66.35742) (width 0.146) (layer "In5.Cu") (net 225))
  (arc (start 148.09836 67.418085) (mid 148.171583 67.241308) (end 148.098359 67.064532) (width 0.146) (layer "In5.Cu") (net 225))
  (arc (start 162.7759 73.490057) (mid 162.834478 73.348636) (end 162.7759 73.207215) (width 0.146) (layer "In5.Cu") (net 225))
  (arc (start 162.811256 74.091099) (mid 162.669836 74.149678) (end 162.528414 74.091099) (width 0.146) (layer "In5.Cu") (net 225))
  (arc (start 148.09836 67.064532) (mid 147.921584 66.991308) (end 147.744807 67.064531) (width 0.146) (layer "In5.Cu") (net 225))
  (arc (start 164.6851 75.399257) (mid 164.743678 75.257836) (end 164.6851 75.116415) (width 0.146) (layer "In5.Cu") (net 225))
  (arc (start 151.594289 70.587181) (mid 151.417512 70.513958) (end 151.240735 70.587181) (width 0.146) (layer "In5.Cu") (net 225))
  (arc (start 146.684137 66.003864) (mid 146.757361 65.827088) (end 146.684138 65.650311) (width 0.146) (layer "In5.Cu") (net 225))
  (arc (start 146.657419 66.737692) (mid 146.480643 66.810916) (end 146.303866 66.737693) (width 0.146) (layer "In5.Cu") (net 225))
  (arc (start 163.447656 74.727499) (mid 163.306236 74.786078) (end 163.164814 74.727499) (width 0.146) (layer "In5.Cu") (net 225))
  (segment (start 152.286328 55.060008) (end 152.286328 56.360008) (width 0.2) (layer "F.Cu") (net 226))
  (segment (start 183.136328 80.560008) (end 182.636328 80.060008) (width 0.127) (layer "F.Cu") (net 226))
  (via blind (at 182.636328 80.060008) (size 0.5) (drill 0.2) (layers "F.Cu" "In2.Cu") (net 226))
  (via blind (at 152.286328 56.360008) (size 0.5) (drill 0.2) (layers "F.Cu" "In2.Cu") (net 226))
  (segment (start 159.45 65.75) (end 159.45 65.79823) (width 0.16) (layer "In2.Cu") (net 226))
  (segment (start 181.12 78.75) (end 180.91 78.54) (width 0.1) (layer "In2.Cu") (net 226))
  (segment (start 163.95 65.79823) (end 163.95 65.20177) (width 0.16) (layer "In2.Cu") (net 226))
  (segment (start 180.17 75.6) (end 180.23 75.54) (width 0.1) (layer "In2.Cu") (net 226))
  (segment (start 160.95 65.79823) (end 160.95 65.20177) (width 0.16) (layer "In2.Cu") (net 226))
  (segment (start 152.286328 61.686328) (end 156.1 65.5) (width 0.16) (layer "In2.Cu") (net 226))
  (segment (start 159.95 65.75) (end 159.95 65.20177) (width 0.16) (layer "In2.Cu") (net 226))
  (segment (start 164.45 65.20177) (end 164.45 65.79823) (width 0.16) (layer "In2.Cu") (net 226))
  (segment (start 174.8 65.5) (end 180.23 70.93) (width 0.16) (layer "In2.Cu") (net 226))
  (segment (start 152.286328 56.360008) (end 152.286328 61.686328) (width 0.16) (layer "In2.Cu") (net 226))
  (segment (start 161.45 65.20177) (end 161.45 65.79823) (width 0.16) (layer "In2.Cu") (net 226))
  (segment (start 164.95 65.79823) (end 164.95 65.75) (width 0.16) (layer "In2.Cu") (net 226))
  (segment (start 180.91 78.54) (end 180.58 78.54) (width 0.1) (layer "In2.Cu") (net 226))
  (segment (start 181.73 79.52) (end 181.3 79.52) (width 0.1) (layer "In2.Cu") (net 226))
  (segment (start 162.95 65.79823) (end 162.95 65.20177) (width 0.16) (layer "In2.Cu") (net 226))
  (segment (start 161.95 65.79823) (end 161.95 65.20177) (width 0.16) (layer "In2.Cu") (net 226))
  (segment (start 180.23 70.93) (end 180.23 75.54) (width 0.16) (layer "In2.Cu") (net 226))
  (segment (start 181.3 79.52) (end 181.12 79.34) (width 0.1) (layer "In2.Cu") (net 226))
  (segment (start 181.12 79.34) (end 181.12 78.75) (width 0.1) (layer "In2.Cu") (net 226))
  (segment (start 182.270008 80.060008) (end 181.73 79.52) (width 0.1) (layer "In2.Cu") (net 226))
  (segment (start 156.1 65.5) (end 159.2 65.5) (width 0.16) (layer "In2.Cu") (net 226))
  (segment (start 163.45 65.20177) (end 163.45 65.79823) (width 0.16) (layer "In2.Cu") (net 226))
  (segment (start 160.45 65.20177) (end 160.45 65.79823) (width 0.16) (layer "In2.Cu") (net 226))
  (segment (start 180.58 78.54) (end 180.17 78.13) (width 0.1) (layer "In2.Cu") (net 226))
  (segment (start 182.636328 80.060008) (end 182.270008 80.060008) (width 0.1) (layer "In2.Cu") (net 226))
  (segment (start 162.45 65.20177) (end 162.45 65.79823) (width 0.16) (layer "In2.Cu") (net 226))
  (segment (start 165.2 65.5) (end 174.8 65.5) (width 0.16) (layer "In2.Cu") (net 226))
  (segment (start 159.95 65.79823) (end 159.95 65.75) (width 0.16) (layer "In2.Cu") (net 226))
  (segment (start 180.17 78.13) (end 180.17 75.6) (width 0.1) (layer "In2.Cu") (net 226))
  (arc (start 164.45 65.79823) (mid 164.523223 65.975007) (end 164.7 66.04823) (width 0.16) (layer "In2.Cu") (net 226))
  (arc (start 163.45 65.79823) (mid 163.523223 65.975007) (end 163.7 66.04823) (width 0.16) (layer "In2.Cu") (net 226))
  (arc (start 164.95 65.75) (mid 165.023223 65.573223) (end 165.2 65.5) (width 0.16) (layer "In2.Cu") (net 226))
  (arc (start 160.95 65.20177) (mid 161.023223 65.024993) (end 161.2 64.95177) (width 0.16) (layer "In2.Cu") (net 226))
  (arc (start 162.7 66.04823) (mid 162.876777 65.975007) (end 162.95 65.79823) (width 0.16) (layer "In2.Cu") (net 226))
  (arc (start 161.95 65.20177) (mid 162.023223 65.024993) (end 162.2 64.95177) (width 0.16) (layer "In2.Cu") (net 226))
  (arc (start 162.95 65.20177) (mid 163.023223 65.024993) (end 163.2 64.95177) (width 0.16) (layer "In2.Cu") (net 226))
  (arc (start 159.2 65.5) (mid 159.376777 65.573223) (end 159.45 65.75) (width 0.16) (layer "In2.Cu") (net 226))
  (arc (start 160.45 65.79823) (mid 160.523223 65.975007) (end 160.7 66.04823) (width 0.16) (layer "In2.Cu") (net 226))
  (arc (start 159.7 66.04823) (mid 159.876777 65.975007) (end 159.95 65.79823) (width 0.16) (layer "In2.Cu") (net 226))
  (arc (start 159.95 65.20177) (mid 160.023223 65.024993) (end 160.2 64.95177) (width 0.16) (layer "In2.Cu") (net 226))
  (arc (start 164.2 64.95177) (mid 164.376777 65.024993) (end 164.45 65.20177) (width 0.16) (layer "In2.Cu") (net 226))
  (arc (start 160.7 66.04823) (mid 160.876777 65.975007) (end 160.95 65.79823) (width 0.16) (layer "In2.Cu") (net 226))
  (arc (start 162.2 64.95177) (mid 162.376777 65.024993) (end 162.45 65.20177) (width 0.16) (layer "In2.Cu") (net 226))
  (arc (start 159.45 65.79823) (mid 159.523223 65.975007) (end 159.7 66.04823) (width 0.16) (layer "In2.Cu") (net 226))
  (arc (start 164.7 66.04823) (mid 164.876777 65.975007) (end 164.95 65.79823) (width 0.16) (layer "In2.Cu") (net 226))
  (arc (start 163.95 65.20177) (mid 164.023223 65.024993) (end 164.2 64.95177) (width 0.16) (layer "In2.Cu") (net 226))
  (arc (start 163.2 64.95177) (mid 163.376777 65.024993) (end 163.45 65.20177) (width 0.16) (layer "In2.Cu") (net 226))
  (arc (start 162.45 65.79823) (mid 162.523223 65.975007) (end 162.7 66.04823) (width 0.16) (layer "In2.Cu") (net 226))
  (arc (start 161.45 65.79823) (mid 161.523223 65.975007) (end 161.7 66.04823) (width 0.16) (layer "In2.Cu") (net 226))
  (arc (start 160.2 64.95177) (mid 160.376777 65.024993) (end 160.45 65.20177) (width 0.16) (layer "In2.Cu") (net 226))
  (arc (start 161.2 64.95177) (mid 161.376777 65.024993) (end 161.45 65.20177) (width 0.16) (layer "In2.Cu") (net 226))
  (arc (start 163.7 66.04823) (mid 163.876777 65.975007) (end 163.95 65.79823) (width 0.16) (layer "In2.Cu") (net 226))
  (arc (start 161.7 66.04823) (mid 161.876777 65.975007) (end 161.95 65.79823) (width 0.16) (layer "In2.Cu") (net 226))
  (segment (start 177.597 77.037) (end 177.61332 77.037) (width 0.127) (layer "F.Cu") (net 227))
  (segment (start 153.986328 55.060008) (end 153.986328 56.360008) (width 0.2) (layer "F.Cu") (net 227))
  (segment (start 177.61332 77.037) (end 178.136328 77.560008) (width 0.127) (layer "F.Cu") (net 227))
  (via blind (at 177.597 77.037) (size 0.5) (drill 0.2) (layers "F.Cu" "In5.Cu") (net 227))
  (via blind (at 153.986328 56.360008) (size 0.5) (drill 0.2) (layers "F.Cu" "In5.Cu") (net 227))
  (segment (start 176.92 76.37) (end 176.92 75.56) (width 0.09) (layer "In5.Cu") (net 227))
  (segment (start 171.325 73.14752) (end 171.325 73.175) (width 0.146) (layer "In5.Cu") (net 227))
  (segment (start 167.9 73.4) (end 171.1 73.4) (width 0.146) (layer "In5.Cu") (net 227))
  (segment (start 167.9 73.4) (end 162.8 68.3) (width 0.146) (layer "In5.Cu") (net 227))
  (segment (start 162.8 68.3) (end 158.1 68.3) (width 0.146) (layer "In5.Cu") (net 227))
  (segment (start 172.225 73.175) (end 172.225 73.65248) (width 0.146) (layer "In5.Cu") (net 227))
  (segment (start 177.597 77.037) (end 177.587 77.037) (width 0.09) (layer "In5.Cu") (net 227))
  (segment (start 153.986328 64.186328) (end 153.986328 56.360008) (width 0.146) (layer "In5.Cu") (net 227))
  (segment (start 177.587 77.037) (end 176.92 76.37) (width 0.09) (layer "In5.Cu") (net 227))
  (segment (start 176.92 75.02) (end 175.3 73.4) (width 0.146) (layer "In5.Cu") (net 227))
  (segment (start 171.775 73.65248) (end 171.775 73.14752) (width 0.146) (layer "In5.Cu") (net 227))
  (segment (start 172.225 73.14752) (end 172.225 73.175) (width 0.146) (layer "In5.Cu") (net 227))
  (segment (start 175.3 73.4) (end 172.9 73.4) (width 0.146) (layer "In5.Cu") (net 227))
  (segment (start 158.1 68.3) (end 153.986328 64.186328) (width 0.146) (layer "In5.Cu") (net 227))
  (segment (start 172.675 73.175) (end 172.675 73.14752) (width 0.146) (layer "In5.Cu") (net 227))
  (segment (start 176.92 75.56) (end 176.92 75.02) (width 0.146) (layer "In5.Cu") (net 227))
  (arc (start 172.45 72.92252) (mid 172.290901 72.988421) (end 172.225 73.14752) (width 0.146) (layer "In5.Cu") (net 227))
  (arc (start 171.55 72.92252) (mid 171.390901 72.988421) (end 171.325 73.14752) (width 0.146) (layer "In5.Cu") (net 227))
  (arc (start 171.775 73.14752) (mid 171.709099 72.988421) (end 171.55 72.92252) (width 0.146) (layer "In5.Cu") (net 227))
  (arc (start 172.675 73.14752) (mid 172.609099 72.988421) (end 172.45 72.92252) (width 0.146) (layer "In5.Cu") (net 227))
  (arc (start 171.325 73.175) (mid 171.259099 73.334099) (end 171.1 73.4) (width 0.146) (layer "In5.Cu") (net 227))
  (arc (start 172 73.87748) (mid 171.840901 73.811579) (end 171.775 73.65248) (width 0.146) (layer "In5.Cu") (net 227))
  (arc (start 172.225 73.65248) (mid 172.159099 73.811579) (end 172 73.87748) (width 0.146) (layer "In5.Cu") (net 227))
  (arc (start 172.9 73.4) (mid 172.740901 73.334099) (end 172.675 73.175) (width 0.146) (layer "In5.Cu") (net 227))
  (segment (start 155.686328 56.360008) (end 155.686328 55.060008) (width 0.2) (layer "F.Cu") (net 228))
  (segment (start 178.4945 77.03) (end 178.60632 77.03) (width 0.127) (layer "F.Cu") (net 228))
  (segment (start 178.60632 77.03) (end 179.136328 77.560008) (width 0.127) (layer "F.Cu") (net 228))
  (via blind (at 155.686328 56.360008) (size 0.5) (drill 0.2) (layers "F.Cu" "In5.Cu") (net 228))
  (via blind (at 178.4945 77.03) (size 0.5) (drill 0.2) (layers "F.Cu" "In5.Cu") (net 228))
  (segment (start 172.775 71.225) (end 172.775 71.575) (width 0.146) (layer "In5.Cu") (net 228))
  (segment (start 172.325 72) (end 172.325 71.225) (width 0.146) (layer "In5.Cu") (net 228))
  (segment (start 171.875 71.775) (end 171.875 72) (width 0.146) (layer "In5.Cu") (net 228))
  (segment (start 163.6 66.9) (end 168.25 71.55) (width 0.146) (layer "In5.Cu") (net 228))
  (segment (start 168.25 71.55) (end 171.65 71.55) (width 0.146) (layer "In5.Cu") (net 228))
  (segment (start 155.686328 56.360008) (end 155.686328 63.236328) (width 0.146) (layer "In5.Cu") (net 228))
  (segment (start 155.686328 63.236328) (end 159.35 66.9) (width 0.146) (layer "In5.Cu") (net 228))
  (segment (start 173 71.8) (end 175.4 71.8) (width 0.146) (layer "In5.Cu") (net 228))
  (segment (start 177.965 74.365) (end 177.965 75.575) (width 0.146) (layer "In5.Cu") (net 228))
  (segment (start 177.965 76.065) (end 177.965 75.575) (width 0.09) (layer "In5.Cu") (net 228))
  (segment (start 175.4 71.8) (end 177.965 74.365) (width 0.146) (layer "In5.Cu") (net 228))
  (segment (start 178.4945 77.03) (end 178.4945 76.5945) (width 0.09) (layer "In5.Cu") (net 228))
  (segment (start 178.4945 76.5945) (end 177.965 76.065) (width 0.09) (layer "In5.Cu") (net 228))
  (segment (start 159.35 66.9) (end 163.6 66.9) (width 0.146) (layer "In5.Cu") (net 228))
  (arc (start 171.65 71.55) (mid 171.809099 71.615901) (end 171.875 71.775) (width 0.146) (layer "In5.Cu") (net 228))
  (arc (start 172.1 72.225) (mid 172.259099 72.159099) (end 172.325 72) (width 0.146) (layer "In5.Cu") (net 228))
  (arc (start 172.325 71.225) (mid 172.390901 71.065901) (end 172.55 71) (width 0.146) (layer "In5.Cu") (net 228))
  (arc (start 172.775 71.575) (mid 172.840901 71.734099) (end 173 71.8) (width 0.146) (layer "In5.Cu") (net 228))
  (arc (start 172.55 71) (mid 172.709099 71.065901) (end 172.775 71.225) (width 0.146) (layer "In5.Cu") (net 228))
  (arc (start 171.875 72) (mid 171.940901 72.159099) (end 172.1 72.225) (width 0.146) (layer "In5.Cu") (net 228))
  (segment (start 150.586328 55.060008) (end 150.586328 56.360008) (width 0.2) (layer "F.Cu") (net 229))
  (segment (start 183.136328 81.560008) (end 182.636328 81.060008) (width 0.127) (layer "F.Cu") (net 229))
  (via blind (at 182.636328 81.060008) (size 0.5) (drill 0.2) (layers "F.Cu" "In2.Cu") (net 229))
  (via blind (at 150.586328 56.360008) (size 0.5) (drill 0.2) (layers "F.Cu" "In2.Cu") (net 229))
  (segment (start 178.85 78.54) (end 178.3 78.54) (width 0.1) (layer "In2.Cu") (net 229))
  (segment (start 179.42 79.57) (end 179.178 79.328) (width 0.1) (layer "In2.Cu") (net 229))
  (segment (start 173.9 67.5) (end 170.4 67.5) (width 0.16) (layer "In2.Cu") (net 229))
  (segment (start 168.475 67.815598) (end 168.475 67.184402) (width 0.16) (layer "In2.Cu") (net 229))
  (segment (start 178.08 75.57) (end 178.08 71.68) (width 0.16) (layer "In2.Cu") (net 229))
  (segment (start 155.45 67.5) (end 150.586328 62.636328) (width 0.16) (layer "In2.Cu") (net 229))
  (segment (start 165.175 67.815598) (end 165.175 67.775) (width 0.16) (layer "In2.Cu") (net 229))
  (segment (start 169.575 67.815598) (end 169.575 67.775) (width 0.16) (layer "In2.Cu") (net 229))
  (segment (start 178.3 78.54) (end 178.134 78.374) (width 0.1) (layer "In2.Cu") (net 229))
  (segment (start 166.275 67.815598) (end 166.275 67.184402) (width 0.16) (layer "In2.Cu") (net 229))
  (segment (start 169.575 67.775) (end 169.575 67.184402) (width 0.16) (layer "In2.Cu") (net 229))
  (segment (start 170.125 67.775) (end 170.125 67.815598) (width 0.16) (layer "In2.Cu") (net 229))
  (segment (start 150.586328 62.636328) (end 150.586328 56.360008) (width 0.16) (layer "In2.Cu") (net 229))
  (segment (start 182.13 80.55368) (end 181.46368 80.55368) (width 0.1) (layer "In2.Cu") (net 229))
  (segment (start 178.134 78.374) (end 178.134 77.403) (width 0.1) (layer "In2.Cu") (net 229))
  (segment (start 165.725 67.184402) (end 165.725 67.815598) (width 0.16) (layer "In2.Cu") (net 229))
  (segment (start 167.375 67.815598) (end 167.375 67.184402) (width 0.16) (layer "In2.Cu") (net 229))
  (segment (start 178.134 77.403) (end 178.08 77.349) (width 0.1) (layer "In2.Cu") (net 229))
  (segment (start 179.178 78.868) (end 178.85 78.54) (width 0.1) (layer "In2.Cu") (net 229))
  (segment (start 166.825 67.184402) (end 166.825 67.815598) (width 0.16) (layer "In2.Cu") (net 229))
  (segment (start 182.636328 81.060008) (end 182.13 80.55368) (width 0.1) (layer "In2.Cu") (net 229))
  (segment (start 169.025 67.184402) (end 169.025 67.815598) (width 0.16) (layer "In2.Cu") (net 229))
  (segment (start 155.45 67.5) (end 164.9 67.5) (width 0.16) (layer "In2.Cu") (net 229))
  (segment (start 178.08 77.349) (end 178.08 75.57) (width 0.1) (layer "In2.Cu") (net 229))
  (segment (start 181.13 80.22) (end 181.13 79.78) (width 0.1) (layer "In2.Cu") (net 229))
  (segment (start 178.08 71.68) (end 173.9 67.5) (width 0.16) (layer "In2.Cu") (net 229))
  (segment (start 181.13 79.78) (end 180.92 79.57) (width 0.1) (layer "In2.Cu") (net 229))
  (segment (start 179.178 79.328) (end 179.178 78.868) (width 0.1) (layer "In2.Cu") (net 229))
  (segment (start 167.925 67.184402) (end 167.925 67.815598) (width 0.16) (layer "In2.Cu") (net 229))
  (segment (start 181.46368 80.55368) (end 181.13 80.22) (width 0.1) (layer "In2.Cu") (net 229))
  (segment (start 180.92 79.57) (end 179.42 79.57) (width 0.1) (layer "In2.Cu") (net 229))
  (arc (start 169.025 67.815598) (mid 168.944454 68.010052) (end 168.75 68.090598) (width 0.16) (layer "In2.Cu") (net 229))
  (arc (start 166.825 67.815598) (mid 166.744454 68.010052) (end 166.55 68.090598) (width 0.16) (layer "In2.Cu") (net 229))
  (arc (start 170.4 67.5) (mid 170.205546 67.580546) (end 170.125 67.775) (width 0.16) (layer "In2.Cu") (net 229))
  (arc (start 165.175 67.775) (mid 165.094454 67.580546) (end 164.9 67.5) (width 0.16) (layer "In2.Cu") (net 229))
  (arc (start 165.725 67.815598) (mid 165.644454 68.010052) (end 165.45 68.090598) (width 0.16) (layer "In2.Cu") (net 229))
  (arc (start 169.85 68.090598) (mid 169.655546 68.010052) (end 169.575 67.815598) (width 0.16) (layer "In2.Cu") (net 229))
  (arc (start 170.125 67.815598) (mid 170.044454 68.010052) (end 169.85 68.090598) (width 0.16) (layer "In2.Cu") (net 229))
  (arc (start 167.925 67.815598) (mid 167.844454 68.010052) (end 167.65 68.090598) (width 0.16) (layer "In2.Cu") (net 229))
  (arc (start 167.375 67.184402) (mid 167.294454 66.989948) (end 167.1 66.909402) (width 0.16) (layer "In2.Cu") (net 229))
  (arc (start 168.75 68.090598) (mid 168.555546 68.010052) (end 168.475 67.815598) (width 0.16) (layer "In2.Cu") (net 229))
  (arc (start 168.2 66.909402) (mid 168.005546 66.989948) (end 167.925 67.184402) (width 0.16) (layer "In2.Cu") (net 229))
  (arc (start 169.575 67.184402) (mid 169.494454 66.989948) (end 169.3 66.909402) (width 0.16) (layer "In2.Cu") (net 229))
  (arc (start 169.3 66.909402) (mid 169.105546 66.989948) (end 169.025 67.184402) (width 0.16) (layer "In2.Cu") (net 229))
  (arc (start 166.275 67.184402) (mid 166.194454 66.989948) (end 166 66.909402) (width 0.16) (layer "In2.Cu") (net 229))
  (arc (start 166 66.909402) (mid 165.805546 66.989948) (end 165.725 67.184402) (width 0.16) (layer "In2.Cu") (net 229))
  (arc (start 165.45 68.090598) (mid 165.255546 68.010052) (end 165.175 67.815598) (width 0.16) (layer "In2.Cu") (net 229))
  (arc (start 167.1 66.909402) (mid 166.905546 66.989948) (end 166.825 67.184402) (width 0.16) (layer "In2.Cu") (net 229))
  (arc (start 166.55 68.090598) (mid 166.355546 68.010052) (end 166.275 67.815598) (width 0.16) (layer "In2.Cu") (net 229))
  (arc (start 167.65 68.090598) (mid 167.455546 68.010052) (end 167.375 67.815598) (width 0.16) (layer "In2.Cu") (net 229))
  (arc (start 168.475 67.184402) (mid 168.394454 66.989948) (end 168.2 66.909402) (width 0.16) (layer "In2.Cu") (net 229))
  (segment (start 163.336328 55.060008) (end 163.336328 56.360008) (width 0.2) (layer "F.Cu") (net 230))
  (segment (start 186.136328 85.560008) (end 186.636328 85.060008) (width 0.127) (layer "F.Cu") (net 230))
  (segment (start 186.636328 85.060008) (end 186.655836 85.060008) (width 0.127) (layer "F.Cu") (net 230))
  (via blind (at 186.655836 85.060008) (size 0.5) (drill 0.2) (layers "F.Cu" "In2.Cu") (net 230))
  (via blind (at 163.336328 56.360008) (size 0.5) (drill 0.2) (layers "F.Cu" "In5.Cu") (net 230))
  (segment (start 166.8 61.5) (end 169.3 64) (width 0.16) (layer "In2.Cu") (net 230))
  (segment (start 181.93 76.15) (end 181.93 75.55) (width 0.1) (layer "In2.Cu") (net 230))
  (segment (start 182.37535 79.553) (end 182.153 79.33065) (width 0.1) (layer "In2.Cu") (net 230))
  (segment (start 166 57.1) (end 166.8 57.9) (width 0.16) (layer "In2.Cu") (net 230))
  (segment (start 176.35 64.85) (end 176.35 65.15) (width 0.16) (layer "In2.Cu") (net 230))
  (segment (start 181.93 70.43) (end 181.93 75.55) (width 0.16) (layer "In2.Cu") (net 230))
  (segment (start 177.9 66.4) (end 181.93 70.43) (width 0.16) (layer "In2.Cu") (net 230))
  (segment (start 181.2805 76.7995) (end 181.93 76.15) (width 0.1) (layer "In2.Cu") (net 230))
  (segment (start 183.102 79.882) (end 182.773 79.553) (width 0.1) (layer "In2.Cu") (net 230))
  (segment (start 186.655836 85.060008) (end 186.141828 84.546) (width 0.1) (layer "In2.Cu") (net 230))
  (segment (start 181.2805 77.6545) (end 181.2805 76.7995) (width 0.1) (layer "In2.Cu") (net 230))
  (segment (start 183.846 84.546) (end 182.878 83.578) (width 0.1) (layer "In2.Cu") (net 230))
  (segment (start 166.8 60.44) (end 166.8 61.5) (width 0.16) (layer "In2.Cu") (net 230))
  (segment (start 167.161893 60.14) (end 167.1 60.14) (width 0.16) (layer "In2.Cu") (net 230))
  (segment (start 177.6 66.4) (end 177.9 66.4) (width 0.16) (layer "In2.Cu") (net 230))
  (segment (start 181.187 77.748) (end 181.2805 77.6545) (width 0.1) (layer "In2.Cu") (net 230))
  (segment (start 175.5 64) (end 176.35 64.85) (width 0.16) (layer "In2.Cu") (net 230))
  (segment (start 176.35 65.15) (end 177.6 66.4) (width 0.16) (layer "In2.Cu") (net 230))
  (segment (start 182.191 81.872) (end 182.544 81.519) (width 0.1) (layer "In2.Cu") (net 230))
  (segment (start 182.153 78.82271) (end 181.89529 78.565) (width 0.1) (layer "In2.Cu") (net 230))
  (segment (start 182.191 83.209) (end 182.191 81.872) (width 0.1) (layer "In2.Cu") (net 230))
  (segment (start 166.5 58.94) (end 166.438107 58.94) (width 0.16) (layer "In2.Cu") (net 230))
  (segment (start 163.563672 57.1) (end 166 57.1) (width 0.16) (layer "In2.Cu") (net 230))
  (segment (start 186.141828 84.546) (end 183.846 84.546) (width 0.1) (layer "In2.Cu") (net 230))
  (segment (start 169.3 64) (end 175.5 64) (width 0.16) (layer "In2.Cu") (net 230))
  (segment (start 183.102 81.232) (end 183.102 79.882) (width 0.1) (layer "In2.Cu") (net 230))
  (segment (start 181.497 78.565) (end 181.187 78.255) (width 0.1) (layer "In2.Cu") (net 230))
  (segment (start 166.8 57.9) (end 166.8 58.64) (width 0.16) (layer "In2.Cu") (net 230))
  (segment (start 166.438107 59.54) (end 166.5 59.54) (width 0.16) (layer "In2.Cu") (net 230))
  (segment (start 182.815 81.519) (end 183.102 81.232) (width 0.1) (layer "In2.Cu") (net 230))
  (segment (start 163.336328 56.872656) (end 163.563672 57.1) (width 0.16) (layer "In2.Cu") (net 230))
  (segment (start 182.56 83.578) (end 182.191 83.209) (width 0.1) (layer "In2.Cu") (net 230))
  (segment (start 182.773 79.553) (end 182.37535 79.553) (width 0.1) (layer "In2.Cu") (net 230))
  (segment (start 181.89529 78.565) (end 181.497 78.565) (width 0.1) (layer "In2.Cu") (net 230))
  (segment (start 182.878 83.578) (end 182.56 83.578) (width 0.1) (layer "In2.Cu") (net 230))
  (segment (start 182.544 81.519) (end 182.815 81.519) (width 0.1) (layer "In2.Cu") (net 230))
  (segment (start 163.336328 56.360008) (end 163.336328 56.872656) (width 0.16) (layer "In2.Cu") (net 230))
  (segment (start 181.187 78.255) (end 181.187 77.748) (width 0.1) (layer "In2.Cu") (net 230))
  (segment (start 182.153 79.33065) (end 182.153 78.82271) (width 0.1) (layer "In2.Cu") (net 230))
  (segment (start 166.5 59.54) (end 167.161893 59.54) (width 0.16) (layer "In2.Cu") (net 230))
  (arc (start 167.461893 59.84) (mid 167.374025 60.052132) (end 167.161893 60.14) (width 0.16) (layer "In2.Cu") (net 230))
  (arc (start 166.8 58.64) (mid 166.712132 58.852132) (end 166.5 58.94) (width 0.16) (layer "In2.Cu") (net 230))
  (arc (start 166.138107 59.24) (mid 166.225975 59.452132) (end 166.438107 59.54) (width 0.16) (layer "In2.Cu") (net 230))
  (arc (start 167.1 60.14) (mid 166.887868 60.227868) (end 166.8 60.44) (width 0.16) (layer "In2.Cu") (net 230))
  (arc (start 166.438107 58.94) (mid 166.225975 59.027868) (end 166.138107 59.24) (width 0.16) (layer "In2.Cu") (net 230))
  (arc (start 167.161893 59.54) (mid 167.374025 59.627868) (end 167.461893 59.84) (width 0.16) (layer "In2.Cu") (net 230))
  (segment (start 188.136328 84.560008) (end 188.636328 84.060008) (width 0.127) (layer "F.Cu") (net 231))
  (segment (start 188.636328 84.060008) (end 188.655836 84.060008) (width 0.127) (layer "F.Cu") (net 231))
  (segment (start 165.036328 55.060008) (end 165.036328 56.360008) (width 0.2) (layer "F.Cu") (net 231))
  (via (at 165.036328 56.360008) (size 0.5) (drill 0.2) (layers "F.Cu" "B.Cu") (net 231))
  (via blind (at 188.655836 84.060008) (size 0.5) (drill 0.2) (layers "F.Cu" "In5.Cu") (net 231))
  (segment (start 185.87 75.56) (end 185.87 76.41) (width 0.09) (layer "In5.Cu") (net 231))
  (segment (start 166.07632 57.4) (end 168.1 57.4) (width 0.146) (layer "In5.Cu") (net 231))
  (segment (start 179.858553 61.104999) (end 179.858554 61.105001) (width 0.146) (layer "In5.Cu") (net 231))
  (segment (start 178.925 60.525) (end 179.505 61.105) (width 0.146) (layer "In5.Cu") (net 231))
  (segment (start 185.65 81.3) (end 186.175 81.825) (width 0.09) (layer "In5.Cu") (net 231))
  (segment (start 188.270828 83.675) (end 188.655836 84.060008) (width 0.09) (layer "In5.Cu") (net 231))
  (segment (start 180.348388 61.32227) (end 180.212106 61.458553) (width 0.146) (layer "In5.Cu") (net 231))
  (segment (start 185.87 76.41) (end 185.65 76.63) (width 0.09) (layer "In5.Cu") (net 231))
  (segment (start 165.036328 56.360008) (end 166.07632 57.4) (width 0.146) (layer "In5.Cu") (net 231))
  (segment (start 180.212105 61.812105) (end 185.87 67.47) (width 0.146) (layer "In5.Cu") (net 231))
  (segment (start 185.65 76.63) (end 185.65 81.3) (width 0.09) (layer "In5.Cu") (net 231))
  (segment (start 180.212107 61.812106) (end 180.212105 61.812105) (width 0.146) (layer "In5.Cu") (net 231))
  (segment (start 187.838219 83.675) (end 188.270828 83.675) (width 0.09) (layer "In5.Cu") (net 231))
  (segment (start 179.858554 61.105001) (end 179.994835 60.968717) (width 0.146) (layer "In5.Cu") (net 231))
  (segment (start 174.225 60.525) (end 178.925 60.525) (width 0.146) (layer "In5.Cu") (net 231))
  (segment (start 172.9 59.2) (end 174.225 60.525) (width 0.146) (layer "In5.Cu") (net 231))
  (segment (start 185.87 67.47) (end 185.87 75.56) (width 0.146) (layer "In5.Cu") (net 231))
  (segment (start 186.175 81.825) (end 186.175 82.275) (width 0.09) (layer "In5.Cu") (net 231))
  (segment (start 169.9 59.2) (end 172.9 59.2) (width 0.146) (layer "In5.Cu") (net 231))
  (segment (start 180.348388 61.322271) (end 180.348388 61.32227) (width 0.146) (layer "In5.Cu") (net 231))
  (segment (start 180.348388 60.968718) (end 180.348389 60.968718) (width 0.146) (layer "In5.Cu") (net 231))
  (segment (start 168.1 57.4) (end 169.9 59.2) (width 0.146) (layer "In5.Cu") (net 231))
  (segment (start 186.175 82.275) (end 186.5 82.6) (width 0.09) (layer "In5.Cu") (net 231))
  (segment (start 186.5 82.6) (end 186.763219 82.6) (width 0.09) (layer "In5.Cu") (net 231))
  (segment (start 186.763219 82.6) (end 187.838219 83.675) (width 0.09) (layer "In5.Cu") (net 231))
  (arc (start 180.212106 61.458553) (mid 180.138883 61.63533) (end 180.212107 61.812106) (width 0.146) (layer "In5.Cu") (net 231))
  (arc (start 180.348389 60.968718) (mid 180.421612 61.145495) (end 180.348388 61.322271) (width 0.146) (layer "In5.Cu") (net 231))
  (arc (start 179.505 61.105) (mid 179.681777 61.178223) (end 179.858553 61.104999) (width 0.146) (layer "In5.Cu") (net 231))
  (arc (start 179.994835 60.968717) (mid 180.171612 60.895494) (end 180.348388 60.968718) (width 0.146) (layer "In5.Cu") (net 231))
  (segment (start 181.736 77.012) (end 181.736 77.15968) (width 0.127) (layer "F.Cu") (net 232))
  (segment (start 159.936328 55.060008) (end 159.936328 56.360008) (width 0.2) (layer "F.Cu") (net 232))
  (segment (start 181.736 77.15968) (end 182.136328 77.560008) (width 0.127) (layer "F.Cu") (net 232))
  (via blind (at 159.936328 56.360008) (size 0.5) (drill 0.2) (layers "F.Cu" "In5.Cu") (net 232))
  (via blind (at 181.736 77.012) (size 0.5) (drill 0.2) (layers "F.Cu" "In5.Cu") (net 232))
  (segment (start 181.71 75.56) (end 181.71 73.11) (width 0.146) (layer "In5.Cu") (net 232))
  (segment (start 159.524006 59.463672) (end 160.34865 59.463672) (width 0.146) (layer "In5.Cu") (net 232))
  (segment (start 160.136328 60.263672) (end 159.524006 60.263672) (width 0.146) (layer "In5.Cu") (net 232))
  (segment (start 159.936328 61.636328) (end 159.936328 60.863672) (width 0.146) (layer "In5.Cu") (net 232))
  (segment (start 181.736 77.012) (end 181.71 76.986) (width 0.09) (layer "In5.Cu") (net 232))
  (segment (start 164.9 63.3) (end 161.6 63.3) (width 0.146) (layer "In5.Cu") (net 232))
  (segment (start 161.6 63.3) (end 159.936328 61.636328) (width 0.146) (layer "In5.Cu") (net 232))
  (segment (start 167.9 66.3) (end 164.9 63.3) (width 0.146) (layer "In5.Cu") (net 232))
  (segment (start 160.24865 60.263672) (end 160.136328 60.263672) (width 0.146) (layer "In5.Cu") (net 232))
  (segment (start 159.524006 59.863672) (end 160.34865 59.863672) (width 0.146) (layer "In5.Cu") (net 232))
  (segment (start 174.9 66.3) (end 167.9 66.3) (width 0.146) (layer "In5.Cu") (net 232))
  (segment (start 160.136328 60.663672) (end 160.24865 60.663672) (width 0.146) (layer "In5.Cu") (net 232))
  (segment (start 159.936328 58.463672) (end 159.936328 56.360008) (width 0.146) (layer "In5.Cu") (net 232))
  (segment (start 159.524006 59.063672) (end 160.34865 59.063672) (width 0.146) (layer "In5.Cu") (net 232))
  (segment (start 160.34865 58.663672) (end 160.136328 58.663672) (width 0.146) (layer "In5.Cu") (net 232))
  (segment (start 181.71 76.986) (end 181.71 75.56) (width 0.09) (layer "In5.Cu") (net 232))
  (segment (start 181.71 73.11) (end 174.9 66.3) (width 0.146) (layer "In5.Cu") (net 232))
  (arc (start 159.524006 60.263672) (mid 159.382585 60.205093) (end 159.324006 60.063672) (width 0.146) (layer "In5.Cu") (net 232))
  (arc (start 159.524006 59.463672) (mid 159.382585 59.405093) (end 159.324006 59.263672) (width 0.146) (layer "In5.Cu") (net 232))
  (arc (start 160.34865 59.063672) (mid 160.490071 59.005093) (end 160.54865 58.863672) (width 0.146) (layer "In5.Cu") (net 232))
  (arc (start 160.136328 58.663672) (mid 159.994907 58.605093) (end 159.936328 58.463672) (width 0.146) (layer "In5.Cu") (net 232))
  (arc (start 159.324006 59.263672) (mid 159.382585 59.122251) (end 159.524006 59.063672) (width 0.146) (layer "In5.Cu") (net 232))
  (arc (start 160.44865 60.463672) (mid 160.390071 60.322251) (end 160.24865 60.263672) (width 0.146) (layer "In5.Cu") (net 232))
  (arc (start 160.54865 59.663672) (mid 160.490071 59.522251) (end 160.34865 59.463672) (width 0.146) (layer "In5.Cu") (net 232))
  (arc (start 159.324006 60.063672) (mid 159.382585 59.922251) (end 159.524006 59.863672) (width 0.146) (layer "In5.Cu") (net 232))
  (arc (start 160.54865 58.863672) (mid 160.490071 58.722251) (end 160.34865 58.663672) (width 0.146) (layer "In5.Cu") (net 232))
  (arc (start 160.34865 59.863672) (mid 160.490071 59.805093) (end 160.54865 59.663672) (width 0.146) (layer "In5.Cu") (net 232))
  (arc (start 159.936328 60.863672) (mid 159.994907 60.722251) (end 160.136328 60.663672) (width 0.146) (layer "In5.Cu") (net 232))
  (arc (start 160.24865 60.663672) (mid 160.390071 60.605093) (end 160.44865 60.463672) (width 0.146) (layer "In5.Cu") (net 232))
  (segment (start 161.636328 55.060008) (end 161.636328 56.360008) (width 0.2) (layer "F.Cu") (net 233))
  (segment (start 183.136328 77.560008) (end 182.636328 77.060008) (width 0.127) (layer "F.Cu") (net 233))
  (segment (start 182.636328 77.060008) (end 182.636328 77.0405) (width 0.127) (layer "F.Cu") (net 233))
  (via blind (at 161.636328 56.360008) (size 0.5) (drill 0.2) (layers "F.Cu" "In5.Cu") (net 233))
  (via blind (at 182.636328 77.0405) (size 0.5) (drill 0.2) (layers "F.Cu" "In5.Cu") (net 233))
  (segment (start 177.611291 67.514172) (end 177.61129 67.514171) (width 0.146) (layer "In5.Cu") (net 233))
  (segment (start 176.197087 65.817124) (end 176.197086 65.817125) (width 0.146) (layer "In5.Cu") (net 233))
  (segment (start 176.899966 65.679929) (end 176.899967 65.679928) (width 0.146) (layer "In5.Cu") (net 233))
  (segment (start 177.465649 66.24561) (end 177.045608 66.665647) (width 0.146) (layer "In5.Cu") (net 233))
  (segment (start 178.031332 66.528451) (end 178.031331 66.52845) (width 0.146) (layer "In5.Cu") (net 233))
  (segment (start 177.894133 67.51417) (end 177.894132 67.514171) (width 0.146) (layer "In5.Cu") (net 233))
  (segment (start 162.5 62.1) (end 165.5 62.1) (width 0.146) (layer "In5.Cu") (net 233))
  (segment (start 175.914245 65.817126) (end 175.914244 65.817125) (width 0.146) (layer "In5.Cu") (net 233))
  (segment (start 176.334283 64.831402) (end 176.334282 64.831402) (width 0.146) (layer "In5.Cu") (net 233))
  (segment (start 178.245572 67.445573) (end 182.636328 71.836328) (width 0.146) (layer "In5.Cu") (net 233))
  (segment (start 175.982842 64.9) (end 176.05144 64.831403) (width 0.146) (layer "In5.Cu") (net 233))
  (segment (start 176.479927 66.382808) (end 176.479926 66.382807) (width 0.146) (layer "In5.Cu") (net 233))
  (segment (start 175.3 64.5) (end 175.7 64.9) (width 0.146) (layer "In5.Cu") (net 233))
  (segment (start 161.636328 61.236328) (end 162.5 62.1) (width 0.146) (layer "In5.Cu") (net 233))
  (segment (start 177.894132 67.514171) (end 177.962729 67.445573) (width 0.146) (layer "In5.Cu") (net 233))
  (segment (start 182.636328 77.0405) (end 182.636328 75.56) (width 0.09) (layer "In5.Cu") (net 233))
  (segment (start 176.197086 65.817125) (end 176.617123 65.397084) (width 0.146) (layer "In5.Cu") (net 233))
  (segment (start 176.334282 65.114244) (end 175.914244 65.534283) (width 0.146) (layer "In5.Cu") (net 233))
  (segment (start 177.045609 66.94849) (end 177.045608 66.948489) (width 0.146) (layer "In5.Cu") (net 233))
  (segment (start 177.46565 65.962769) (end 177.465649 65.962768) (width 0.146) (layer "In5.Cu") (net 233))
  (segment (start 178.245572 67.445572) (end 178.245572 67.445573) (width 0.146) (layer "In5.Cu") (net 233))
  (segment (start 176.899967 65.679928) (end 176.479926 66.099965) (width 0.146) (layer "In5.Cu") (net 233))
  (segment (start 161.636328 56.360008) (end 161.636328 61.236328) (width 0.146) (layer "In5.Cu") (net 233))
  (segment (start 176.899968 65.397087) (end 176.899967 65.397086) (width 0.146) (layer "In5.Cu") (net 233))
  (segment (start 167.9 64.5) (end 175.3 64.5) (width 0.146) (layer "In5.Cu") (net 233))
  (segment (start 177.465648 66.245611) (end 177.465649 66.24561) (width 0.146) (layer "In5.Cu") (net 233))
  (segment (start 178.03133 66.811293) (end 178.031331 66.811292) (width 0.146) (layer "In5.Cu") (net 233))
  (segment (start 176.762768 66.382807) (end 177.182805 65.962766) (width 0.146) (layer "In5.Cu") (net 233))
  (segment (start 176.762769 66.382806) (end 176.762768 66.382807) (width 0.146) (layer "In5.Cu") (net 233))
  (segment (start 182.636328 71.836328) (end 182.636328 75.56) (width 0.146) (layer "In5.Cu") (net 233))
  (segment (start 175.982843 64.899999) (end 175.982842 64.9) (width 0.146) (layer "In5.Cu") (net 233))
  (segment (start 176.334281 65.114245) (end 176.334282 65.114244) (width 0.146) (layer "In5.Cu") (net 233))
  (segment (start 178.031331 66.811292) (end 177.61129 67.231329) (width 0.146) (layer "In5.Cu") (net 233))
  (segment (start 177.328451 66.948488) (end 177.32845 66.948489) (width 0.146) (layer "In5.Cu") (net 233))
  (segment (start 165.5 62.1) (end 167.9 64.5) (width 0.146) (layer "In5.Cu") (net 233))
  (segment (start 177.32845 66.948489) (end 177.748487 66.528448) (width 0.146) (layer "In5.Cu") (net 233))
  (arc (start 177.182805 65.962766) (mid 177.324229 65.90419) (end 177.46565 65.962769) (width 0.146) (layer "In5.Cu") (net 233))
  (arc (start 176.899967 65.397086) (mid 176.958545 65.538508) (end 176.899966 65.679929) (width 0.146) (layer "In5.Cu") (net 233))
  (arc (start 176.334282 64.831402) (mid 176.39286 64.972824) (end 176.334281 65.114245) (width 0.146) (layer "In5.Cu") (net 233))
  (arc (start 175.7 64.9) (mid 175.841422 64.958578) (end 175.982843 64.899999) (width 0.146) (layer "In5.Cu") (net 233))
  (arc (start 177.045608 66.665647) (mid 176.98703 66.807069) (end 177.045609 66.94849) (width 0.146) (layer "In5.Cu") (net 233))
  (arc (start 176.479926 66.099965) (mid 176.421348 66.241387) (end 176.479927 66.382808) (width 0.146) (layer "In5.Cu") (net 233))
  (arc (start 176.617123 65.397084) (mid 176.758547 65.338508) (end 176.899968 65.397087) (width 0.146) (layer "In5.Cu") (net 233))
  (arc (start 175.914244 65.534283) (mid 175.855666 65.675705) (end 175.914245 65.817126) (width 0.146) (layer "In5.Cu") (net 233))
  (arc (start 177.61129 67.231329) (mid 177.552712 67.372751) (end 177.611291 67.514172) (width 0.146) (layer "In5.Cu") (net 233))
  (arc (start 176.05144 64.831403) (mid 176.192861 64.772824) (end 176.334283 64.831402) (width 0.146) (layer "In5.Cu") (net 233))
  (arc (start 177.045608 66.948489) (mid 177.18703 67.007067) (end 177.328451 66.948488) (width 0.146) (layer "In5.Cu") (net 233))
  (arc (start 176.479926 66.382807) (mid 176.621348 66.441385) (end 176.762769 66.382806) (width 0.146) (layer "In5.Cu") (net 233))
  (arc (start 177.962729 67.445573) (mid 178.10415 67.386994) (end 178.245572 67.445572) (width 0.146) (layer "In5.Cu") (net 233))
  (arc (start 177.748487 66.528448) (mid 177.889911 66.469872) (end 178.031332 66.528451) (width 0.146) (layer "In5.Cu") (net 233))
  (arc (start 178.031331 66.52845) (mid 178.089909 66.669872) (end 178.03133 66.811293) (width 0.146) (layer "In5.Cu") (net 233))
  (arc (start 177.61129 67.514171) (mid 177.752712 67.572749) (end 177.894133 67.51417) (width 0.146) (layer "In5.Cu") (net 233))
  (arc (start 175.914244 65.817125) (mid 176.055666 65.875703) (end 176.197087 65.817124) (width 0.146) (layer "In5.Cu") (net 233))
  (arc (start 177.465649 65.962768) (mid 177.524227 66.10419) (end 177.465648 66.245611) (width 0.146) (layer "In5.Cu") (net 233))
  (segment (start 186.136328 83.560008) (end 186.636328 84.060008) (width 0.127) (layer "F.Cu") (net 234))
  (segment (start 186.636328 84.060008) (end 186.636328 84.079516) (width 0.127) (layer "F.Cu") (net 234))
  (segment (start 166.736328 55.060008) (end 166.736328 56.360008) (width 0.2) (layer "F.Cu") (net 234))
  (via blind (at 166.736328 56.360008) (size 0.5) (drill 0.2) (layers "F.Cu" "In2.Cu") (net 234))
  (via blind (at 186.636328 84.079516) (size 0.5) (drill 0.2) (layers "F.Cu" "In2.Cu") (net 234))
  (segment (start 183.818 79.538) (end 183.428 79.538) (width 0.1) (layer "In2.Cu") (net 234))
  (segment (start 186.176812 83.62) (end 183.569 83.62) (width 0.1) (layer "In2.Cu") (net 234))
  (segment (start 178.4 65.6) (end 182.525 69.725) (width 0.16) (layer "In2.Cu") (net 234))
  (segment (start 182.53 76.552858) (end 182.53 75.55) (width 0.1) (layer "In2.Cu") (net 234))
  (segment (start 177.1 64.3) (end 177.1 64.9) (width 0.16) (layer "In2.Cu") (net 234))
  (segment (start 169.725 63.2) (end 176 63.2) (width 0.16) (layer "In2.Cu") (net 234))
  (segment (start 182.78 78.55) (end 182.551858 78.55) (width 0.1) (layer "In2.Cu") (net 234))
  (segment (start 183.428 79.538) (end 183.15 79.26) (width 0.1) (layer "In2.Cu") (net 234))
  (segment (start 183.7095 81.6205) (end 184.14 81.19) (width 0.1) (layer "In2.Cu") (net 234))
  (segment (start 176 63.2) (end 177.1 64.3) (width 0.16) (layer "In2.Cu") (net 234))
  (segment (start 177.8 65.6) (end 178.4 65.6) (width 0.16) (layer "In2.Cu") (net 234))
  (segment (start 183.569 83.62) (end 183.216328 83.267328) (width 0.1) (layer "In2.Cu") (net 234))
  (segment (start 177.1 64.9) (end 177.8 65.6) (width 0.16) (layer "In2.Cu") (net 234))
  (segment (start 183.216328 81.933672) (end 183.5295 81.6205) (width 0.1) (layer "In2.Cu") (net 234))
  (segment (start 183.15 79.26) (end 183.15 78.92) (width 0.1) (layer "In2.Cu") (net 234))
  (segment (start 166.736328 56.360008) (end 168.1 57.72368) (width 0.16) (layer "In2.Cu") (net 234))
  (segment (start 184.14 79.86) (end 183.818 79.538) (width 0.1) (layer "In2.Cu") (net 234))
  (segment (start 168.1 57.72368) (end 168.1 61.575) (width 0.16) (layer "In2.Cu") (net 234))
  (segment (start 168.1 61.575) (end 169.725 63.2) (width 0.16) (layer "In2.Cu") (net 234))
  (segment (start 182.216328 76.86653) (end 182.53 76.552858) (width 0.1) (layer "In2.Cu") (net 234))
  (segment (start 186.636328 84.079516) (end 186.176812 83.62) (width 0.1) (layer "In2.Cu") (net 234))
  (segment (start 182.216328 78.21447) (end 182.216328 76.86653) (width 0.1) (layer "In2.Cu") (net 234))
  (segment (start 182.525 69.725) (end 182.525 75.545) (width 0.16) (layer "In2.Cu") (net 234))
  (segment (start 183.5295 81.6205) (end 183.7095 81.6205) (width 0.1) (layer "In2.Cu") (net 234))
  (segment (start 182.525 75.545) (end 182.53 75.55) (width 0.16) (layer "In2.Cu") (net 234))
  (segment (start 182.551858 78.55) (end 182.216328 78.21447) (width 0.1) (layer "In2.Cu") (net 234))
  (segment (start 183.216328 83.267328) (end 183.216328 81.933672) (width 0.1) (layer "In2.Cu") (net 234))
  (segment (start 184.14 81.19) (end 184.14 79.86) (width 0.1) (layer "In2.Cu") (net 234))
  (segment (start 183.15 78.92) (end 182.78 78.55) (width 0.1) (layer "In2.Cu") (net 234))
  (segment (start 168.436328 55.060008) (end 168.436328 56.360008) (width 0.2) (layer "F.Cu") (net 235))
  (segment (start 184.136328 83.560008) (end 183.636328 83.060008) (width 0.127) (layer "F.Cu") (net 235))
  (via (at 183.636328 83.060008) (size 0.5) (drill 0.2) (layers "F.Cu" "B.Cu") (net 235))
  (via blind (at 168.436328 56.360008) (size 0.5) (drill 0.2) (layers "F.Cu" "In2.Cu") (net 235))
  (segment (start 184.121 79.189) (end 184.121 78.691) (width 0.1) (layer "In2.Cu") (net 235))
  (segment (start 168.8 60.31) (end 168.8 61.110077) (width 0.16) (layer "In2.Cu") (net 235))
  (segment (start 183.2 77.77) (end 183.2 75.6) (width 0.1) (layer "In2.Cu") (net 235))
  (segment (start 168.8 57.3) (end 168.8 59.06) (width 0.16) (layer "In2.Cu") (net 235))
  (segment (start 184.5 81.5) (end 184.5 79.568) (width 0.1) (layer "In2.Cu") (net 235))
  (segment (start 184.5 79.568) (end 184.121 79.189) (width 0.1) (layer "In2.Cu") (net 235))
  (segment (start 170.089923 62.4) (end 176.8 62.4) (width 0.16) (layer "In2.Cu") (net 235))
  (segment (start 177.8 63.4) (end 177.8 64.523199) (width 0.16) (layer "In2.Cu") (net 235))
  (segment (start 168.436328 56.936328) (end 168.8 57.3) (width 0.16) (layer "In2.Cu") (net 235))
  (segment (start 168.8 61.110077) (end 170.089923 62.4) (width 0.16) (layer "In2.Cu") (net 235))
  (segment (start 178.8 64.9) (end 183.2 69.3) (width 0.16) (layer "In2.Cu") (net 235))
  (segment (start 183.636328 82.363672) (end 184.5 81.5) (width 0.1) (layer "In2.Cu") (net 235))
  (segment (start 183.2 69.3) (end 183.2 75.6) (width 0.16) (layer "In2.Cu") (net 235))
  (segment (start 184.121 78.691) (end 183.2 77.77) (width 0.1) (layer "In2.Cu") (net 235))
  (segment (start 168.436328 56.360008) (end 168.436328 56.936328) (width 0.16) (layer "In2.Cu") (net 235))
  (segment (start 171.191489 59.96) (end 169.1 59.96) (width 0.16) (layer "In2.Cu") (net 235))
  (segment (start 178.176801 64.9) (end 178.8 64.9) (width 0.16) (layer "In2.Cu") (net 235))
  (segment (start 177.8 64.523199) (end 178.176801 64.9) (width 0.16) (layer "In2.Cu") (net 235))
  (segment (start 183.636328 83.060008) (end 183.636328 82.363672) (width 0.1) (layer "In2.Cu") (net 235))
  (segment (start 168.8 60.26) (end 168.8 60.31) (width 0.16) (layer "In2.Cu") (net 235))
  (segment (start 176.8 62.4) (end 177.8 63.4) (width 0.16) (layer "In2.Cu") (net 235))
  (segment (start 169.1 59.36) (end 171.191489 59.36) (width 0.16) (layer "In2.Cu") (net 235))
  (arc (start 171.191489 59.36) (mid 171.403621 59.447868) (end 171.491489 59.66) (width 0.16) (layer "In2.Cu") (net 235))
  (arc (start 169.1 59.96) (mid 168.887868 60.047868) (end 168.8 60.26) (width 0.16) (layer "In2.Cu") (net 235))
  (arc (start 168.8 59.06) (mid 168.887868 59.272132) (end 169.1 59.36) (width 0.16) (layer "In2.Cu") (net 235))
  (arc (start 171.491489 59.66) (mid 171.403621 59.872132) (end 171.191489 59.96) (width 0.16) (layer "In2.Cu") (net 235))
  (segment (start 184.136328 77.560008) (end 183.636328 77.060008) (width 0.127) (layer "F.Cu") (net 236))
  (segment (start 183.636328 77.060008) (end 183.636328 77.0405) (width 0.127) (layer "F.Cu") (net 236))
  (segment (start 169.286328 55.060008) (end 169.286328 56.360008) (width 0.2) (layer "F.Cu") (net 236))
  (via (at 183.636328 77.0405) (size 0.5) (drill 0.2) (layers "F.Cu" "B.Cu") (net 236))
  (via (at 169.286328 56.360008) (size 0.5) (drill 0.2) (layers "F.Cu" "B.Cu") (net 236))
  (segment (start 174.15 63.55) (end 172.8 62.2) (width 0.16) (layer "In9.Cu") (net 236))
  (segment (start 170.723672 60.223672) (end 169.286328 58.786328) (width 0.16) (layer "In9.Cu") (net 236))
  (segment (start 184.653781 74.225) (end 184.675 74.225) (width 0.16) (layer "In9.Cu") (net 236))
  (segment (start 179.9 63.55) (end 174.15 63.55) (width 0.16) (layer "In9.Cu") (net 236))
  (segment (start 184.02603 75.98) (end 183.636328 76.369702) (width 0.1) (layer "In9.Cu") (net 236))
  (segment (start 169.286328 58.786328) (end 169.286328 56.360008) (width 0.16) (layer "In9.Cu") (net 236))
  (segment (start 184.675 74.225) (end 185.146219 74.225) (width 0.16) (layer "In9.Cu") (net 236))
  (segment (start 183.636328 76.369702) (end 183.636328 77.0405) (width 0.1) (layer "In9.Cu") (net 236))
  (segment (start 180.15 64.15) (end 180.15 63.8) (width 0.16) (layer "In9.Cu") (net 236))
  (segment (start 172.8 61.1) (end 171.923672 60.223672) (width 0.16) (layer "In9.Cu") (net 236))
  (segment (start 184.653781 73.775) (end 185.146219 73.775) (width 0.16) (layer "In9.Cu") (net 236))
  (segment (start 184.9 72.65) (end 184.9 68.9) (width 0.16) (layer "In9.Cu") (net 236))
  (segment (start 185.146219 72.875) (end 185.125 72.875) (width 0.16) (layer "In9.Cu") (net 236))
  (segment (start 184.675 74.675) (end 184.653781 74.675) (width 0.16) (layer "In9.Cu") (net 236))
  (segment (start 180.15 63.8) (end 179.9 63.55) (width 0.16) (layer "In9.Cu") (net 236))
  (segment (start 184.9 68.9) (end 180.15 64.15) (width 0.16) (layer "In9.Cu") (net 236))
  (segment (start 184.9 75.8) (end 184.72 75.98) (width 0.1) (layer "In9.Cu") (net 236))
  (segment (start 172.8 62.2) (end 172.8 61.1) (width 0.16) (layer "In9.Cu") (net 236))
  (segment (start 171.923672 60.223672) (end 170.723672 60.223672) (width 0.16) (layer "In9.Cu") (net 236))
  (segment (start 184.653781 73.325) (end 185.146219 73.325) (width 0.16) (layer "In9.Cu") (net 236))
  (segment (start 184.9 75.5) (end 184.9 74.9) (width 0.16) (layer "In9.Cu") (net 236))
  (segment (start 184.9 75.5) (end 184.9 75.8) (width 0.1) (layer "In9.Cu") (net 236))
  (segment (start 184.72 75.98) (end 184.02603 75.98) (width 0.1) (layer "In9.Cu") (net 236))
  (arc (start 184.653781 73.775) (mid 184.494682 73.709099) (end 184.428781 73.55) (width 0.16) (layer "In9.Cu") (net 236))
  (arc (start 184.428781 74.45) (mid 184.494682 74.290901) (end 184.653781 74.225) (width 0.16) (layer "In9.Cu") (net 236))
  (arc (start 185.371219 73.1) (mid 185.305318 72.940901) (end 185.146219 72.875) (width 0.16) (layer "In9.Cu") (net 236))
  (arc (start 185.146219 74.225) (mid 185.305318 74.159099) (end 185.371219 74) (width 0.16) (layer "In9.Cu") (net 236))
  (arc (start 184.9 74.9) (mid 184.834099 74.740901) (end 184.675 74.675) (width 0.16) (layer "In9.Cu") (net 236))
  (arc (start 185.146219 73.325) (mid 185.305318 73.259099) (end 185.371219 73.1) (width 0.16) (layer "In9.Cu") (net 236))
  (arc (start 184.653781 74.675) (mid 184.494682 74.609099) (end 184.428781 74.45) (width 0.16) (layer "In9.Cu") (net 236))
  (arc (start 184.428781 73.55) (mid 184.494682 73.390901) (end 184.653781 73.325) (width 0.16) (layer "In9.Cu") (net 236))
  (arc (start 185.125 72.875) (mid 184.965901 72.809099) (end 184.9 72.65) (width 0.16) (layer "In9.Cu") (net 236))
  (arc (start 185.371219 74) (mid 185.305318 73.840901) (end 185.146219 73.775) (width 0.16) (layer "In9.Cu") (net 236))
  (segment (start 188.136328 85.560008) (end 188.636328 85.060008) (width 0.127) (layer "F.Cu") (net 237))
  (segment (start 188.636328 85.060008) (end 188.655836 85.060008) (width 0.127) (layer "F.Cu") (net 237))
  (segment (start 170.986328 55.060008) (end 170.986328 56.360008) (width 0.2) (layer "F.Cu") (net 237))
  (via (at 170.986328 56.360008) (size 0.5) (drill 0.2) (layers "F.Cu" "B.Cu") (net 237))
  (via blind (at 188.655836 85.060008) (size 0.5) (drill 0.2) (layers "F.Cu" "In5.Cu") (net 237))
  (segment (start 188.775008 83.475008) (end 188.475008 83.475008) (width 0.09) (layer "In5.Cu") (net 237))
  (segment (start 182.693627 62.359313) (end 182.410784 62.642155) (width 0.146) (layer "In5.Cu") (net 237))
  (segment (start 181.303553 60.049999) (end 181.303554 60.050001) (width 0.146) (layer "In5.Cu") (net 237))
  (segment (start 181.437676 61.330087) (end 182.159374 60.608385) (width 0.146) (layer "In5.Cu") (net 237))
  (segment (start 186.57 76.51) (end 186.57 75.56) (width 0.09) (layer "In5.Cu") (net 237))
  (segment (start 181.303554 60.050001) (end 181.45227 59.901282) (width 0.146) (layer "In5.Cu") (net 237))
  (segment (start 182.512929 60.961939) (end 182.364212 61.110657) (width 0.146) (layer "In5.Cu") (net 237))
  (segment (start 187.06 81.6) (end 186.5 81.6) (width 0.09) (layer "In5.Cu") (net 237))
  (segment (start 183.825 62.925) (end 184 63.1) (width 0.146) (layer "In5.Cu") (net 237))
  (segment (start 181.805825 60.254836) (end 181.084123 60.976534) (width 0.146) (layer "In5.Cu") (net 237))
  (segment (start 186.2095 76.8705) (end 186.57 76.51) (width 0.09) (layer "In5.Cu") (net 237))
  (segment (start 188.655836 85.060008) (end 189.15 84.565844) (width 0.09) (layer "In5.Cu") (net 237))
  (segment (start 187.445 81.985) (end 187.06 81.6) (width 0.09) (layer "In5.Cu") (net 237))
  (segment (start 189.15 83.85) (end 188.775008 83.475008) (width 0.09) (layer "In5.Cu") (net 237))
  (segment (start 186.2095 81.3095) (end 186.2095 76.8705) (width 0.09) (layer "In5.Cu") (net 237))
  (segment (start 182.410784 62.642155) (end 182.410783 62.642156) (width 0.146) (layer "In5.Cu") (net 237))
  (segment (start 182.364211 61.46421) (end 182.364212 61.464211) (width 0.146) (layer "In5.Cu") (net 237))
  (segment (start 170.986328 56.386328) (end 171.7 57.1) (width 0.146) (layer "In5.Cu") (net 237))
  (segment (start 180.85 59.95) (end 180.95 60.05) (width 0.146) (layer "In5.Cu") (net 237))
  (segment (start 181.084123 61.330088) (end 181.084123 61.330087) (width 0.146) (layer "In5.Cu") (net 237))
  (segment (start 184 63.1) (end 184 63.6) (width 0.146) (layer "In5.Cu") (net 237))
  (segment (start 172.8 57.5) (end 172.8 58.1) (width 0.146) (layer "In5.Cu") (net 237))
  (segment (start 181.437676 61.330086) (end 181.437676 61.330087) (width 0.146) (layer "In5.Cu") (net 237))
  (segment (start 188.475008 83.475008) (end 187.445 82.445) (width 0.09) (layer "In5.Cu") (net 237))
  (segment (start 187.445 82.445) (end 187.445 81.985) (width 0.09) (layer "In5.Cu") (net 237))
  (segment (start 186.57 66.17) (end 186.57 75.56) (width 0.146) (layer "In5.Cu") (net 237))
  (segment (start 181.805823 60.254835) (end 181.805825 60.254836) (width 0.146) (layer "In5.Cu") (net 237))
  (segment (start 170.986328 56.360008) (end 170.986328 56.386328) (width 0.146) (layer "In5.Cu") (net 237))
  (segment (start 182.97647 63.207841) (end 183.259314 62.925) (width 0.146) (layer "In5.Cu") (net 237))
  (segment (start 184 63.6) (end 186.57 66.17) (width 0.146) (layer "In5.Cu") (net 237))
  (segment (start 183.259314 62.925) (end 183.259315 62.924999) (width 0.146) (layer "In5.Cu") (net 237))
  (segment (start 172.8 58.1) (end 174.65 59.95) (width 0.146) (layer "In5.Cu") (net 237))
  (segment (start 182.364212 61.464211) (end 182.693628 61.793628) (width 0.146) (layer "In5.Cu") (net 237))
  (segment (start 181.805823 59.901281) (end 181.805824 59.901282) (width 0.146) (layer "In5.Cu") (net 237))
  (segment (start 171.7 57.1) (end 172.4 57.1) (width 0.146) (layer "In5.Cu") (net 237))
  (segment (start 182.512929 60.96194) (end 182.512929 60.961939) (width 0.146) (layer "In5.Cu") (net 237))
  (segment (start 189.15 84.565844) (end 189.15 83.85) (width 0.09) (layer "In5.Cu") (net 237))
  (segment (start 186.5 81.6) (end 186.2095 81.3095) (width 0.09) (layer "In5.Cu") (net 237))
  (segment (start 172.4 57.1) (end 172.8 57.5) (width 0.146) (layer "In5.Cu") (net 237))
  (segment (start 182.410784 63.207841) (end 182.410785 63.207842) (width 0.146) (layer "In5.Cu") (net 237))
  (segment (start 174.65 59.95) (end 180.85 59.95) (width 0.146) (layer "In5.Cu") (net 237))
  (arc (start 181.084123 60.976534) (mid 181.0109 61.153311) (end 181.084123 61.330088) (width 0.146) (layer "In5.Cu") (net 237))
  (arc (start 181.45227 59.901282) (mid 181.629046 59.828058) (end 181.805823 59.901281) (width 0.146) (layer "In5.Cu") (net 237))
  (arc (start 182.159374 60.608385) (mid 182.336153 60.535164) (end 182.51293 60.608387) (width 0.146) (layer "In5.Cu") (net 237))
  (arc (start 181.805824 59.901282) (mid 181.879047 60.078059) (end 181.805823 60.254835) (width 0.146) (layer "In5.Cu") (net 237))
  (arc (start 182.410783 62.642156) (mid 182.293626 62.924999) (end 182.410784 63.207841) (width 0.146) (layer "In5.Cu") (net 237))
  (arc (start 182.364212 61.110657) (mid 182.290988 61.287433) (end 182.364211 61.46421) (width 0.146) (layer "In5.Cu") (net 237))
  (arc (start 183.259315 62.924999) (mid 183.542158 62.807842) (end 183.825 62.925) (width 0.146) (layer "In5.Cu") (net 237))
  (arc (start 180.95 60.05) (mid 181.126777 60.123223) (end 181.303553 60.049999) (width 0.146) (layer "In5.Cu") (net 237))
  (arc (start 182.693628 61.793628) (mid 182.810785 62.076471) (end 182.693627 62.359313) (width 0.146) (layer "In5.Cu") (net 237))
  (arc (start 182.51293 60.608387) (mid 182.586153 60.785164) (end 182.512929 60.96194) (width 0.146) (layer "In5.Cu") (net 237))
  (arc (start 182.410785 63.207842) (mid 182.693628 63.324999) (end 182.97647 63.207841) (width 0.146) (layer "In5.Cu") (net 237))
  (arc (start 181.084123 61.330087) (mid 181.2609 61.40331) (end 181.437676 61.330086) (width 0.146) (layer "In5.Cu") (net 237))
  (segment (start 185.136328 82.560008) (end 185.636328 82.060008) (width 0.127) (layer "F.Cu") (net 238))
  (segment (start 185.636328 82.060008) (end 185.655836 82.060008) (width 0.127) (layer "F.Cu") (net 238))
  (segment (start 172.686328 55.060008) (end 172.686328 56.360008) (width 0.2) (layer "F.Cu") (net 238))
  (via (at 172.686328 56.360008) (size 0.5) (drill 0.2) (layers "F.Cu" "B.Cu") (net 238))
  (via (at 185.655836 82.060008) (size 0.5) (drill 0.2) (layers "F.Cu" "B.Cu") (net 238))
  (segment (start 187.2 71.8) (end 187.2 68.6) (width 0.16) (layer "In9.Cu") (net 238))
  (segment (start 184.782296 66.581101) (end 184.782298 66.581102) (width 0.16) (layer "In9.Cu") (net 238))
  (segment (start 185.7 77.4) (end 185.7 79.8) (width 0.1) (layer "In9.Cu") (net 238))
  (segment (start 185.499302 66.500498) (end 185.100495 66.8993) (width 0.16) (layer "In9.Cu") (net 238))
  (segment (start 185.4 80.1) (end 185.4 81.1) (width 0.1) (layer "In9.Cu") (net 238))
  (segment (start 184.782298 66.581102) (end 184.8226 66.540797) (width 0.16) (layer "In9.Cu") (net 238))
  (segment (start 185.655836 81.355836) (end 185.655836 82.060008) (width 0.1) (layer "In9.Cu") (net 238))
  (segment (start 186.6 76.5) (end 185.7 77.4) (width 0.1) (layer "In9.Cu") (net 238))
  (segment (start 187.2 68.6) (end 187.05 68.45) (width 0.16) (layer "In9.Cu") (net 238))
  (segment (start 181.9 61.25) (end 175.97 61.25) (width 0.16) (layer "In9.Cu") (net 238))
  (segment (start 186.055098 67.853903) (end 186.0551 67.853904) (width 0.16) (layer "In9.Cu") (net 238))
  (segment (start 185.7 79.8) (end 185.4 80.1) (width 0.1) (layer "In9.Cu") (net 238))
  (segment (start 185.4 81.1) (end 185.655836 81.355836) (width 0.1) (layer "In9.Cu") (net 238))
  (segment (start 185.418697 67.217502) (end 185.418699 67.217503) (width 0.16) (layer "In9.Cu") (net 238))
  (segment (start 184.8226 66.222599) (end 182.25 63.65) (width 0.16) (layer "In9.Cu") (net 238))
  (segment (start 172.68 57.96) (end 172.68 56.366336) (width 0.16) (layer "In9.Cu") (net 238))
  (segment (start 182.25 63.65) (end 182.25 61.6) (width 0.16) (layer "In9.Cu") (net 238))
  (segment (start 186.6 75.5) (end 186.6 72.4) (width 0.16) (layer "In9.Cu") (net 238))
  (segment (start 186.6 72.4) (end 187.2 71.8) (width 0.16) (layer "In9.Cu") (net 238))
  (segment (start 187.05 68.131801) (end 187.090303 68.091497) (width 0.16) (layer "In9.Cu") (net 238))
  (segment (start 186.0551 67.853904) (end 186.453902 67.455097) (width 0.16) (layer "In9.Cu") (net 238))
  (segment (start 186.135703 67.136898) (end 186.135703 67.136899) (width 0.16) (layer "In9.Cu") (net 238))
  (segment (start 182.25 61.6) (end 181.9 61.25) (width 0.16) (layer "In9.Cu") (net 238))
  (segment (start 172.68 56.366336) (end 172.686328 56.360008) (width 0.16) (layer "In9.Cu") (net 238))
  (segment (start 186.135703 67.136899) (end 185.736896 67.535701) (width 0.16) (layer "In9.Cu") (net 238))
  (segment (start 175.97 61.25) (end 172.68 57.96) (width 0.16) (layer "In9.Cu") (net 238))
  (segment (start 186.772104 67.773299) (end 186.373297 68.172102) (width 0.16) (layer "In9.Cu") (net 238))
  (segment (start 186.772104 67.773298) (end 186.772104 67.773299) (width 0.16) (layer "In9.Cu") (net 238))
  (segment (start 185.499302 66.500497) (end 185.499302 66.500498) (width 0.16) (layer "In9.Cu") (net 238))
  (segment (start 186.6 75.5) (end 186.6 76.5) (width 0.1) (layer "In9.Cu") (net 238))
  (segment (start 187.049999 68.131801) (end 187.05 68.131801) (width 0.16) (layer "In9.Cu") (net 238))
  (segment (start 185.418699 67.217503) (end 185.817501 66.818696) (width 0.16) (layer "In9.Cu") (net 238))
  (arc (start 185.736896 67.535701) (mid 185.577797 67.601602) (end 185.418698 67.535701) (width 0.16) (layer "In9.Cu") (net 238))
  (arc (start 186.055099 68.172102) (mid 185.989198 68.013004) (end 186.055098 67.853903) (width 0.16) (layer "In9.Cu") (net 238))
  (arc (start 186.453902 67.136899) (mid 186.294803 67.070997) (end 186.135703 67.136898) (width 0.16) (layer "In9.Cu") (net 238))
  (arc (start 185.817501 66.500498) (mid 185.658402 66.434596) (end 185.499302 66.500497) (width 0.16) (layer "In9.Cu") (net 238))
  (arc (start 186.373297 68.172102) (mid 186.214198 68.238003) (end 186.055099 68.172102) (width 0.16) (layer "In9.Cu") (net 238))
  (arc (start 187.090303 68.091497) (mid 187.156204 67.932398) (end 187.090303 67.773299) (width 0.16) (layer "In9.Cu") (net 238))
  (arc (start 187.090303 67.773299) (mid 186.931204 67.707397) (end 186.772104 67.773298) (width 0.16) (layer "In9.Cu") (net 238))
  (arc (start 185.100495 66.8993) (mid 184.941396 66.965201) (end 184.782297 66.8993) (width 0.16) (layer "In9.Cu") (net 238))
  (arc (start 185.418698 67.535701) (mid 185.352797 67.376603) (end 185.418697 67.217502) (width 0.16) (layer "In9.Cu") (net 238))
  (arc (start 185.817501 66.818696) (mid 185.883402 66.659597) (end 185.817501 66.500498) (width 0.16) (layer "In9.Cu") (net 238))
  (arc (start 187.05 68.45) (mid 186.984098 68.290901) (end 187.049999 68.131801) (width 0.16) (layer "In9.Cu") (net 238))
  (arc (start 186.453902 67.455097) (mid 186.519803 67.295998) (end 186.453902 67.136899) (width 0.16) (layer "In9.Cu") (net 238))
  (arc (start 184.782297 66.8993) (mid 184.716396 66.740202) (end 184.782296 66.581101) (width 0.16) (layer "In9.Cu") (net 238))
  (arc (start 184.8226 66.540797) (mid 184.888501 66.381698) (end 184.8226 66.222599) (width 0.16) (layer "In9.Cu") (net 238))
  (segment (start 186.136328 81.560008) (end 186.63732 81.059016) (width 0.127) (layer "F.Cu") (net 239))
  (segment (start 173.536328 55.060008) (end 173.536328 56.360008) (width 0.2) (layer "F.Cu") (net 239))
  (segment (start 186.63732 81.059016) (end 186.656328 81.059016) (width 0.127) (layer "F.Cu") (net 239))
  (via (at 173.536328 56.360008) (size 0.5) (drill 0.2) (layers "F.Cu" "B.Cu") (net 239))
  (via (at 186.656328 81.059016) (size 0.5) (drill 0.2) (layers "F.Cu" "B.Cu") (net 239))
  (segment (start 186.298729 62.675484) (end 186.298728 62.675482) (width 0.146) (layer "In5.Cu") (net 239))
  (segment (start 185.952587 64.082279) (end 185.952587 64.08228) (width 0.146) (layer "In5.Cu") (net 239))
  (segment (start 185.599035 64.08228) (end 185.599034 64.08228) (width 0.146) (layer "In5.Cu") (net 239))
  (segment (start 176.55132 59.375) (end 181.945 59.375) (width 0.146) (layer "In5.Cu") (net 239))
  (segment (start 186.832763 64.262762) (end 187.27 64.7) (width 0.146) (layer "In5.Cu") (net 239))
  (segment (start 186.298727 63.029035) (end 186.298729 63.029036) (width 0.146) (layer "In5.Cu") (net 239))
  (segment (start 185.245483 63.375174) (end 185.245483 63.375175) (width 0.146) (layer "In5.Cu") (net 239))
  (segment (start 187.225 80.490344) (end 187.225 77.65) (width 0.09) (layer "In5.Cu") (net 239))
  (segment (start 184.89193 63.375176) (end 184.89193 63.375175) (width 0.146) (layer "In5.Cu") (net 239))
  (segment (start 187.52 76.745) (end 187.27 76.495) (width 0.09) (layer "In5.Cu") (net 239))
  (segment (start 187.005833 63.382588) (end 187.005832 63.382586) (width 0.146) (layer "In5.Cu") (net 239))
  (segment (start 185.064999 62.848553) (end 185.065 62.848553) (width 0.146) (layer "In5.Cu") (net 239))
  (segment (start 187.27 76.495) (end 187.27 75.56) (width 0.09) (layer "In5.Cu") (net 239))
  (segment (start 185.245483 63.375175) (end 185.945174 62.675481) (width 0.146) (layer "In5.Cu") (net 239))
  (segment (start 187.225 77.65) (end 187.52 77.355) (width 0.09) (layer "In5.Cu") (net 239))
  (segment (start 185.065 62.848553) (end 184.89193 63.021622) (width 0.146) (layer "In5.Cu") (net 239))
  (segment (start 187.005833 63.73614) (end 186.832762 63.909208) (width 0.146) (layer "In5.Cu") (net 239))
  (segment (start 187.27 64.7) (end 187.27 75.56) (width 0.146) (layer "In5.Cu") (net 239))
  (segment (start 181.945 59.375) (end 185.065 62.495) (width 0.146) (layer "In5.Cu") (net 239))
  (segment (start 186.656328 81.059016) (end 187.225 80.490344) (width 0.09) (layer "In5.Cu") (net 239))
  (segment (start 185.952587 64.08228) (end 186.652278 63.382585) (width 0.146) (layer "In5.Cu") (net 239))
  (segment (start 186.832762 64.262762) (end 186.832763 64.262762) (width 0.146) (layer "In5.Cu") (net 239))
  (segment (start 187.005831 63.736139) (end 187.005833 63.73614) (width 0.146) (layer "In5.Cu") (net 239))
  (segment (start 173.536328 56.360008) (end 176.55132 59.375) (width 0.146) (layer "In5.Cu") (net 239))
  (segment (start 186.298729 63.029036) (end 185.599034 63.728727) (width 0.146) (layer "In5.Cu") (net 239))
  (segment (start 187.52 77.355) (end 187.52 76.745) (width 0.09) (layer "In5.Cu") (net 239))
  (arc (start 186.652278 63.382585) (mid 186.829057 63.309364) (end 187.005833 63.382588) (width 0.146) (layer "In5.Cu") (net 239))
  (arc (start 187.005832 63.382586) (mid 187.079055 63.559363) (end 187.005831 63.736139) (width 0.146) (layer "In5.Cu") (net 239))
  (arc (start 186.298728 62.675482) (mid 186.371951 62.852259) (end 186.298727 63.029035) (width 0.146) (layer "In5.Cu") (net 239))
  (arc (start 184.89193 63.021622) (mid 184.818707 63.198399) (end 184.89193 63.375176) (width 0.146) (layer "In5.Cu") (net 239))
  (arc (start 185.945174 62.675481) (mid 186.121953 62.60226) (end 186.298729 62.675484) (width 0.146) (layer "In5.Cu") (net 239))
  (arc (start 185.599034 64.08228) (mid 185.775811 64.155503) (end 185.952587 64.082279) (width 0.146) (layer "In5.Cu") (net 239))
  (arc (start 185.599034 63.728727) (mid 185.525811 63.905504) (end 185.599035 64.08228) (width 0.146) (layer "In5.Cu") (net 239))
  (arc (start 184.89193 63.375175) (mid 185.068707 63.448398) (end 185.245483 63.375174) (width 0.146) (layer "In5.Cu") (net 239))
  (arc (start 185.065 62.495) (mid 185.138223 62.671777) (end 185.064999 62.848553) (width 0.146) (layer "In5.Cu") (net 239))
  (arc (start 186.832762 63.909208) (mid 186.759539 64.085985) (end 186.832762 64.262762) (width 0.146) (layer "In5.Cu") (net 239))
  (segment (start 186.89251 77.31619) (end 187.136328 77.560008) (width 0.127) (layer "F.Cu") (net 240))
  (segment (start 175.236328 55.060008) (end 175.236328 56.296336) (width 0.2) (layer "F.Cu") (net 240))
  (segment (start 175.236328 56.296336) (end 175.3 56.360008) (width 0.2) (layer "F.Cu") (net 240))
  (segment (start 186.89251 77.04251) (end 186.89251 77.31619) (width 0.127) (layer "F.Cu") (net 240))
  (via (at 175.3 56.360008) (size 0.5) (drill 0.2) (layers "F.Cu" "B.Cu") (net 240))
  (via (at 186.89251 77.04251) (size 0.5) (drill 0.2) (layers "F.Cu" "B.Cu") (net 240))
  (segment (start 187.2 76.2) (end 187.2 76.73502) (width 0.1) (layer "In9.Cu") (net 240))
  (segment (start 188.5 71.7) (end 188.5 71.47) (width 0.16) (layer "In9.Cu") (net 240))
  (segment (start 175.3 58.35) (end 175.3 56.360008) (width 0.16) (layer "In9.Cu") (net 240))
  (segment (start 187.5 75.55) (end 187.5 75.9) (width 0.1) (layer "In9.Cu") (net 240))
  (segment (start 187.5 73.3) (end 187.5 72.7) (width 0.16) (layer "In9.Cu") (net 240))
  (segment (start 188.984597 70.345) (end 188.015403 70.345) (width 0.16) (layer "In9.Cu") (net 240))
  (segment (start 188.015403 70.795) (end 188.984597 70.795) (width 0.16) (layer "In9.Cu") (net 240))
  (segment (start 187.5 75.55) (end 187.5 75.1) (width 0.16) (layer "In9.Cu") (net 240))
  (segment (start 187.125 73.525) (end 187.275 73.525) (width 0.16) (layer "In9.Cu") (net 240))
  (segment (start 188.984597 69.445) (end 188.725 69.445) (width 0.16) (layer "In9.Cu") (net 240))
  (segment (start 182.4 60.2) (end 177.15 60.2) (width 0.16) (layer "In9.Cu") (net 240))
  (segment (start 183 60.8) (end 182.4 60.2) (width 0.16) (layer "In9.Cu") (net 240))
  (segment (start 187.775 73.975) (end 187.125 73.975) (width 0.16) (layer "In9.Cu") (net 240))
  (segment (start 187.2 76.73502) (end 186.89251 77.04251) (width 0.1) (layer "In9.Cu") (net 240))
  (segment (start 183 63.2) (end 183 60.8) (width 0.16) (layer "In9.Cu") (net 240))
  (segment (start 188.5 68.7) (end 183 63.2) (width 0.16) (layer "In9.Cu") (net 240))
  (segment (start 187.125 74.425) (end 187.775 74.425) (width 0.16) (layer "In9.Cu") (net 240))
  (segment (start 188.5 69.22) (end 188.5 68.7) (width 0.16) (layer "In9.Cu") (net 240))
  (segment (start 188.275 71.245) (end 188.015403 71.245) (width 0.16) (layer "In9.Cu") (net 240))
  (segment (start 188.015403 69.895) (end 188.984597 69.895) (width 0.16) (layer "In9.Cu") (net 240))
  (segment (start 187.5 75.9) (end 187.2 76.2) (width 0.1) (layer "In9.Cu") (net 240))
  (segment (start 187.275 74.875) (end 187.125 74.875) (width 0.16) (layer "In9.Cu") (net 240))
  (segment (start 177.15 60.2) (end 175.3 58.35) (width 0.16) (layer "In9.Cu") (net 240))
  (segment (start 187.5 72.7) (end 188.5 71.7) (width 0.16) (layer "In9.Cu") (net 240))
  (arc (start 188.5 71.47) (mid 188.434099 71.310901) (end 188.275 71.245) (width 0.16) (layer "In9.Cu") (net 240))
  (arc (start 189.209597 69.67) (mid 189.143696 69.510901) (end 188.984597 69.445) (width 0.16) (layer "In9.Cu") (net 240))
  (arc (start 187.790403 70.12) (mid 187.856304 69.960901) (end 188.015403 69.895) (width 0.16) (layer "In9.Cu") (net 240))
  (arc (start 187.125 74.875) (mid 186.965901 74.809099) (end 186.9 74.65) (width 0.16) (layer "In9.Cu") (net 240))
  (arc (start 188.984597 69.895) (mid 189.143696 69.829099) (end 189.209597 69.67) (width 0.16) (layer "In9.Cu") (net 240))
  (arc (start 187.790403 71.02) (mid 187.856304 70.860901) (end 188.015403 70.795) (width 0.16) (layer "In9.Cu") (net 240))
  (arc (start 188.015403 71.245) (mid 187.856304 71.179099) (end 187.790403 71.02) (width 0.16) (layer "In9.Cu") (net 240))
  (arc (start 189.209597 70.57) (mid 189.143696 70.410901) (end 188.984597 70.345) (width 0.16) (layer "In9.Cu") (net 240))
  (arc (start 186.9 73.75) (mid 186.965901 73.590901) (end 187.125 73.525) (width 0.16) (layer "In9.Cu") (net 240))
  (arc (start 188.725 69.445) (mid 188.565901 69.379099) (end 188.5 69.22) (width 0.16) (layer "In9.Cu") (net 240))
  (arc (start 186.9 74.65) (mid 186.965901 74.490901) (end 187.125 74.425) (width 0.16) (layer "In9.Cu") (net 240))
  (arc (start 187.5 75.1) (mid 187.434099 74.940901) (end 187.275 74.875) (width 0.16) (layer "In9.Cu") (net 240))
  (arc (start 187.775 74.425) (mid 187.934099 74.359099) (end 188 74.2) (width 0.16) (layer "In9.Cu") (net 240))
  (arc (start 188 74.2) (mid 187.934099 74.040901) (end 187.775 73.975) (width 0.16) (layer "In9.Cu") (net 240))
  (arc (start 188.015403 70.345) (mid 187.856304 70.279099) (end 187.790403 70.12) (width 0.16) (layer "In9.Cu") (net 240))
  (arc (start 187.125 73.975) (mid 186.965901 73.909099) (end 186.9 73.75) (width 0.16) (layer "In9.Cu") (net 240))
  (arc (start 188.984597 70.795) (mid 189.143696 70.729099) (end 189.209597 70.57) (width 0.16) (layer "In9.Cu") (net 240))
  (arc (start 187.275 73.525) (mid 187.434099 73.459099) (end 187.5 73.3) (width 0.16) (layer "In9.Cu") (net 240))
  (segment (start 244.936328 55.060008) (end 244.936328 56.360008) (width 0.2) (layer "F.Cu") (net 241))
  (segment (start 190.636328 86.060008) (end 190.655836 86.060008) (width 0.127) (layer "F.Cu") (net 241))
  (segment (start 190.136328 86.560008) (end 190.636328 86.060008) (width 0.127) (layer "F.Cu") (net 241))
  (via (at 244.936328 56.360008) (size 0.5) (drill 0.2) (layers "F.Cu" "B.Cu") (net 241))
  (via (at 190.655836 86.060008) (size 0.5) (drill 0.2) (layers "F.Cu" "B.Cu") (net 241))
  (segment (start 222.5 77.5) (end 238.1 77.5) (width 0.16) (layer "In9.Cu") (net 241))
  (segment (start 191.495828 86.9) (end 196.35 86.9) (width 0.1) (layer "In9.Cu") (net 241))
  (segment (start 202.8 88.2) (end 211.8 88.2) (width 0.16) (layer "In9.Cu") (net 241))
  (segment (start 238.1 77.5) (end 244.936328 70.663672) (width 0.16) (layer "In9.Cu") (net 241))
  (segment (start 191.335828 86.74) (end 191.495828 86.9) (width 0.1) (layer "In9.Cu") (net 241))
  (segment (start 196.75 86.5) (end 198.1 86.5) (width 0.1) (layer "In9.Cu") (net 241))
  (segment (start 190.655836 86.060008) (end 191.335828 86.74) (width 0.127) (layer "In9.Cu") (net 241))
  (segment (start 198.1 86.5) (end 201.1 86.5) (width 0.16) (layer "In9.Cu") (net 241))
  (segment (start 201.1 86.5) (end 202.8 88.2) (width 0.16) (layer "In9.Cu") (net 241))
  (segment locked (start 211.8 88.2) (end 222.5 77.5) (width 0.16) (layer "In9.Cu") (net 241))
  (segment (start 196.35 86.9) (end 196.75 86.5) (width 0.1) (layer "In9.Cu") (net 241))
  (segment (start 244.936328 70.663672) (end 244.936328 56.360008) (width 0.16) (layer "In9.Cu") (net 241))
  (segment (start 192.136328 86.560008) (end 192.636328 86.060008) (width 0.127) (layer "F.Cu") (net 242))
  (segment (start 192.636328 86.060008) (end 192.655836 86.060008) (width 0.127) (layer "F.Cu") (net 242))
  (segment (start 243.236328 55.060008) (end 243.236328 56.360008) (width 0.2) (layer "F.Cu") (net 242))
  (via (at 243.236328 56.360008) (size 0.5) (drill 0.2) (layers "F.Cu" "B.Cu") (net 242))
  (via (at 192.655836 86.060008) (size 0.5) (drill 0.2) (layers "F.Cu" "B.Cu") (net 242))
  (segment (start 213.133355 82.366645) (end 221 74.5) (width 0.16) (layer "In9.Cu") (net 242))
  (segment (start 210.907261 83.907404) (end 211.037798 84.037941) (width 0.16) (layer "In9.Cu") (net 242))
  (segment (start 209.5 86) (end 209.765 85.735) (width 0.16) (layer "In9.Cu") (net 242))
  (segment (start 211.16833 85.017004) (end 211.16833 85.017005) (width 0.16) (layer "In9.Cu") (net 242))
  (segment (start 208.625 85.625) (end 208.625 85.725) (width 0.16) (layer "In9.Cu") (net 242))
  (segment (start 203.72 86) (end 207.8 86) (width 0.16) (layer "In9.Cu") (net 242))
  (segment (start 209.175 86.375) (end 209.175 86.275) (width 0.16) (layer "In9.Cu") (net 242))
  (segment (start 210.05873 84.755936) (end 210.05873 84.755935) (width 0.16) (layer "In9.Cu") (net 242))
  (segment (start 198.2 85.4) (end 203.12 85.4) (width 0.16) (layer "In9.Cu") (net 242))
  (segment (start 194.59 85.4) (end 193.929992 86.060008) (width 0.1) (layer "In9.Cu") (net 242))
  (segment (start 243.236328 68.563672) (end 243.236328 56.360008) (width 0.16) (layer "In9.Cu") (net 242))
  (segment (start 198.2 85.4) (end 194.59 85.4) (width 0.1) (layer "In9.Cu") (net 242))
  (segment (start 211.16833 85.017005) (end 210.482995 84.331669) (width 0.16) (layer "In9.Cu") (net 242))
  (segment (start 221 74.5) (end 237.3 74.5) (width 0.16) (layer "In9.Cu") (net 242))
  (segment (start 208.625 85.725) (end 208.625 86.375) (width 0.16) (layer "In9.Cu") (net 242))
  (segment (start 209.765 85.310736) (end 209.634464 85.1802) (width 0.16) (layer "In9.Cu") (net 242))
  (segment (start 237.3 74.5) (end 243.236328 68.563672) (width 0.16) (layer "In9.Cu") (net 242))
  (segment (start 209.45 86) (end 209.5 86) (width 0.16) (layer "In9.Cu") (net 242))
  (segment (start 211.462062 84.037941) (end 213.133355 82.366645) (width 0.16) (layer "In9.Cu") (net 242))
  (segment (start 208.075 85.725) (end 208.075 85.625) (width 0.16) (layer "In9.Cu") (net 242))
  (segment (start 203.12 85.4) (end 203.72 86) (width 0.16) (layer "In9.Cu") (net 242))
  (segment (start 210.05873 84.755935) (end 210.744066 85.44127) (width 0.16) (layer "In9.Cu") (net 242))
  (segment (start 193.929992 86.060008) (end 192.655836 86.060008) (width 0.1) (layer "In9.Cu") (net 242))
  (segment (start 210.907261 83.907405) (end 210.907261 83.907404) (width 0.16) (layer "In9.Cu") (net 242))
  (arc (start 207.8 86) (mid 207.994454 85.919454) (end 208.075 85.725) (width 0.16) (layer "In9.Cu") (net 242))
  (arc (start 210.744066 85.44127) (mid 210.956198 85.529138) (end 211.16833 85.44127) (width 0.16) (layer "In9.Cu") (net 242))
  (arc (start 208.9 86.65) (mid 209.094454 86.569454) (end 209.175 86.375) (width 0.16) (layer "In9.Cu") (net 242))
  (arc (start 210.482995 83.907405) (mid 210.695129 83.819536) (end 210.907261 83.907405) (width 0.16) (layer "In9.Cu") (net 242))
  (arc (start 208.625 86.375) (mid 208.705546 86.569454) (end 208.9 86.65) (width 0.16) (layer "In9.Cu") (net 242))
  (arc (start 209.175 86.275) (mid 209.255546 86.080546) (end 209.45 86) (width 0.16) (layer "In9.Cu") (net 242))
  (arc (start 208.075 85.625) (mid 208.155546 85.430546) (end 208.35 85.35) (width 0.16) (layer "In9.Cu") (net 242))
  (arc (start 211.037798 84.037941) (mid 211.24993 84.125809) (end 211.462062 84.037941) (width 0.16) (layer "In9.Cu") (net 242))
  (arc (start 209.634464 85.1802) (mid 209.546596 84.968068) (end 209.634464 84.755936) (width 0.16) (layer "In9.Cu") (net 242))
  (arc (start 210.482995 84.331669) (mid 210.395127 84.119537) (end 210.482995 83.907405) (width 0.16) (layer "In9.Cu") (net 242))
  (arc (start 209.634464 84.755936) (mid 209.846598 84.668067) (end 210.05873 84.755936) (width 0.16) (layer "In9.Cu") (net 242))
  (arc (start 209.765 85.735) (mid 209.852868 85.522868) (end 209.765 85.310736) (width 0.16) (layer "In9.Cu") (net 242))
  (arc (start 211.16833 85.44127) (mid 211.256198 85.229137) (end 211.16833 85.017004) (width 0.16) (layer "In9.Cu") (net 242))
  (arc (start 208.35 85.35) (mid 208.544454 85.430546) (end 208.625 85.625) (width 0.16) (layer "In9.Cu") (net 242))
  (segment (start 191.636328 81.060008) (end 191.655836 81.060008) (width 0.127) (layer "F.Cu") (net 243))
  (segment (start 237.286328 55.060008) (end 237.286328 56.360008) (width 0.2) (layer "F.Cu") (net 243))
  (segment (start 191.136328 81.560008) (end 191.636328 81.060008) (width 0.127) (layer "F.Cu") (net 243))
  (via (at 191.655836 81.060008) (size 0.5) (drill 0.2) (layers "F.Cu" "B.Cu") (net 243))
  (via (at 237.286328 56.360008) (size 0.5) (drill 0.2) (layers "F.Cu" "B.Cu") (net 243))
  (segment (start 208.166459 73.066278) (end 208.166459 73.066279) (width 0.16) (layer "In9.Cu") (net 243))
  (segment (start 237.286328 62.513672) (end 234.8 65) (width 0.16) (layer "In9.Cu") (net 243))
  (segment (start 209.722094 71.899552) (end 209.722095 71.899552) (width 0.16) (layer "In9.Cu") (net 243))
  (segment (start 210.499913 70.732825) (end 210.377997 70.610909) (width 0.16) (layer "In9.Cu") (net 243))
  (segment (start 209.478268 70.488995) (end 209.478266 70.488996) (width 0.16) (layer "In9.Cu") (net 243))
  (segment (start 208.311539 71.266815) (end 208.31154 71.266813) (width 0.16) (layer "In9.Cu") (net 243))
  (segment (start 207.38864 74.233006) (end 207.388641 74.233006) (width 0.16) (layer "In9.Cu") (net 243))
  (segment (start 208.166459 73.066279) (end 207.533721 72.433541) (width 0.16) (layer "In9.Cu") (net 243))
  (segment (start 205.978086 73.600268) (end 205.978085 73.600269) (width 0.16) (layer "In9.Cu") (net 243))
  (segment (start 209.722095 71.510642) (end 209.722095 71.510643) (width 0.16) (layer "In9.Cu") (net 243))
  (segment (start 207.388641 73.844096) (end 207.388641 73.844097) (width 0.16) (layer "In9.Cu") (net 243))
  (segment (start 208.944276 72.67737) (end 208.944277 72.67737) (width 0.16) (layer "In9.Cu") (net 243))
  (segment (start 191.655836 81.060008) (end 192.145844 80.57) (width 0.1) (layer "In9.Cu") (net 243))
  (segment (start 209.089357 70.488997) (end 209.089358 70.488995) (width 0.16) (layer "In9.Cu") (net 243))
  (segment (start 209.722095 71.510643) (end 209.089357 70.877905) (width 0.16) (layer "In9.Cu") (net 243))
  (segment (start 192.145844 80.57) (end 195.73 80.57) (width 0.1) (layer "In9.Cu") (net 243))
  (segment (start 210.499912 71.121734) (end 210.499913 71.121734) (width 0.16) (layer "In9.Cu") (net 243))
  (segment (start 207.92263 72.044632) (end 208.555368 72.67737) (width 0.16) (layer "In9.Cu") (net 243))
  (segment (start 207.144814 72.822449) (end 207.144812 72.82245) (width 0.16) (layer "In9.Cu") (net 243))
  (segment (start 209.478266 70.488996) (end 210.111004 71.121734) (width 0.16) (layer "In9.Cu") (net 243))
  (segment (start 207.533721 72.044633) (end 207.533722 72.044631) (width 0.16) (layer "In9.Cu") (net 243))
  (segment (start 210.499913 70.732824) (end 210.499913 70.732825) (width 0.16) (layer "In9.Cu") (net 243))
  (segment (start 206.366995 73.600269) (end 206.366995 73.600268) (width 0.16) (layer "In9.Cu") (net 243))
  (segment (start 207.388641 73.844097) (end 206.755903 73.211359) (width 0.16) (layer "In9.Cu") (net 243))
  (segment (start 210.377998 70.222) (end 210.377997 70.222001) (width 0.16) (layer "In9.Cu") (net 243))
  (segment (start 207.922632 72.044631) (end 207.92263 72.044632) (width 0.16) (layer "In9.Cu") (net 243))
  (segment (start 195.9 80.4) (end 198.2 80.4) (width 0.1) (layer "In9.Cu") (net 243))
  (segment (start 198.2 80.4) (end 200.2 80.4) (width 0.16) (layer "In9.Cu") (net 243))
  (segment (start 195.73 80.57) (end 195.9 80.4) (width 0.1) (layer "In9.Cu") (net 243))
  (segment (start 210.377997 70.222001) (end 215.6 65) (width 0.16) (layer "In9.Cu") (net 243))
  (segment (start 208.70045 71.266813) (end 208.700448 71.266814) (width 0.16) (layer "In9.Cu") (net 243))
  (segment (start 208.944277 72.288461) (end 208.311539 71.655723) (width 0.16) (layer "In9.Cu") (net 243))
  (segment (start 208.700448 71.266814) (end 209.333186 71.899552) (width 0.16) (layer "In9.Cu") (net 243))
  (segment (start 200.2 80.4) (end 206.1 74.5) (width 0.16) (layer "In9.Cu") (net 243))
  (segment (start 207.144812 72.82245) (end 207.77755 73.455188) (width 0.16) (layer "In9.Cu") (net 243))
  (segment (start 208.944277 72.28846) (end 208.944277 72.288461) (width 0.16) (layer "In9.Cu") (net 243))
  (segment (start 237.286328 56.360008) (end 237.286328 62.513672) (width 0.16) (layer "In9.Cu") (net 243))
  (segment (start 206.755903 72.822451) (end 206.755904 72.822449) (width 0.16) (layer "In9.Cu") (net 243))
  (segment (start 206.1 74.111092) (end 205.978085 73.989177) (width 0.16) (layer "In9.Cu") (net 243))
  (segment (start 206.366995 73.600268) (end 206.999732 74.233006) (width 0.16) (layer "In9.Cu") (net 243))
  (segment (start 208.166458 73.455188) (end 208.166459 73.455188) (width 0.16) (layer "In9.Cu") (net 243))
  (segment locked (start 234.8 65) (end 215.6 65) (width 0.16) (layer "In9.Cu") (net 243))
  (arc (start 205.978085 73.600269) (mid 206.172541 73.519722) (end 206.366995 73.600269) (width 0.16) (layer "In9.Cu") (net 243))
  (arc (start 205.978085 73.989177) (mid 205.89754 73.794722) (end 205.978086 73.600268) (width 0.16) (layer "In9.Cu") (net 243))
  (arc (start 209.089358 70.488995) (mid 209.283812 70.40845) (end 209.478268 70.488995) (width 0.16) (layer "In9.Cu") (net 243))
  (arc (start 208.166459 73.455188) (mid 208.247005 73.260733) (end 208.166459 73.066278) (width 0.16) (layer "In9.Cu") (net 243))
  (arc (start 206.1 74.5) (mid 206.180546 74.305545) (end 206.1 74.111092) (width 0.16) (layer "In9.Cu") (net 243))
  (arc (start 209.333186 71.899552) (mid 209.52764 71.980097) (end 209.722094 71.899552) (width 0.16) (layer "In9.Cu") (net 243))
  (arc (start 210.111004 71.121734) (mid 210.305458 71.202279) (end 210.499912 71.121734) (width 0.16) (layer "In9.Cu") (net 243))
  (arc (start 207.533722 72.044631) (mid 207.728176 71.964086) (end 207.922632 72.044631) (width 0.16) (layer "In9.Cu") (net 243))
  (arc (start 208.311539 71.655723) (mid 208.230995 71.461268) (end 208.311539 71.266815) (width 0.16) (layer "In9.Cu") (net 243))
  (arc (start 209.089357 70.877905) (mid 209.008813 70.68345) (end 209.089357 70.488997) (width 0.16) (layer "In9.Cu") (net 243))
  (arc (start 208.555368 72.67737) (mid 208.749822 72.757915) (end 208.944276 72.67737) (width 0.16) (layer "In9.Cu") (net 243))
  (arc (start 207.388641 74.233006) (mid 207.469187 74.038551) (end 207.388641 73.844096) (width 0.16) (layer "In9.Cu") (net 243))
  (arc (start 207.533721 72.433541) (mid 207.453177 72.239086) (end 207.533721 72.044633) (width 0.16) (layer "In9.Cu") (net 243))
  (arc (start 206.755904 72.822449) (mid 206.950358 72.741904) (end 207.144814 72.822449) (width 0.16) (layer "In9.Cu") (net 243))
  (arc (start 209.722095 71.899552) (mid 209.802641 71.705097) (end 209.722095 71.510642) (width 0.16) (layer "In9.Cu") (net 243))
  (arc (start 207.77755 73.455188) (mid 207.972004 73.535733) (end 208.166458 73.455188) (width 0.16) (layer "In9.Cu") (net 243))
  (arc (start 210.499913 71.121734) (mid 210.580459 70.927279) (end 210.499913 70.732824) (width 0.16) (layer "In9.Cu") (net 243))
  (arc (start 206.755903 73.211359) (mid 206.675359 73.016904) (end 206.755903 72.822451) (width 0.16) (layer "In9.Cu") (net 243))
  (arc (start 206.999732 74.233006) (mid 207.194186 74.313551) (end 207.38864 74.233006) (width 0.16) (layer "In9.Cu") (net 243))
  (arc (start 208.944277 72.67737) (mid 209.024823 72.482915) (end 208.944277 72.28846) (width 0.16) (layer "In9.Cu") (net 243))
  (arc (start 210.377997 70.610909) (mid 210.297452 70.416454) (end 210.377998 70.222) (width 0.16) (layer "In9.Cu") (net 243))
  (arc (start 208.31154 71.266813) (mid 208.505994 71.186268) (end 208.70045 71.266813) (width 0.16) (layer "In9.Cu") (net 243))
  (segment (start 238.986328 55.060008) (end 238.986328 56.360008) (width 0.2) (layer "F.Cu") (net 244))
  (segment (start 192.136328 82.560008) (end 192.636328 82.060008) (width 0.127) (layer "F.Cu") (net 244))
  (segment (start 192.636328 82.060008) (end 192.655836 82.060008) (width 0.127) (layer "F.Cu") (net 244))
  (via (at 238.986328 56.360008) (size 0.5) (drill 0.2) (layers "F.Cu" "B.Cu") (net 244))
  (via (at 192.655836 82.060008) (size 0.5) (drill 0.2) (layers "F.Cu" "B.Cu") (net 244))
  (segment (start 192.655836 82.060008) (end 192.915844 81.8) (width 0.1) (layer "In9.Cu") (net 244))
  (segment (start 209.610518 74.400096) (end 209.999903 74.789482) (width 0.16) (layer "In9.Cu") (net 244))
  (segment (start 238.986328 64.413672) (end 235.4 68) (width 0.16) (layer "In9.Cu") (net 244))
  (segment (start 202.7 81.7) (end 206.8 77.6) (width 0.16) (layer "In9.Cu") (net 244))
  (segment (start 210.671182 73.339433) (end 211.060568 73.728818) (width 0.16) (layer "In9.Cu") (net 244))
  (segment (start 192.915844 81.8) (end 196.1 81.8) (width 0.1) (layer "In9.Cu") (net 244))
  (segment (start 196.1 81.8) (end 196.2 81.7) (width 0.1) (layer "In9.Cu") (net 244))
  (segment (start 209.256964 74.753651) (end 209.64635 75.143036) (width 0.16) (layer "In9.Cu") (net 244))
  (segment (start 209.999904 75.143036) (end 209.999903 75.143036) (width 0.16) (layer "In9.Cu") (net 244))
  (segment (start 207.842746 76.167869) (end 208.232132 76.557254) (width 0.16) (layer "In9.Cu") (net 244))
  (segment (start 210.317627 73.692987) (end 210.707012 74.082373) (width 0.16) (layer "In9.Cu") (net 244))
  (segment (start 207.33033 77.06967) (end 207.525023 77.264363) (width 0.16) (layer "In9.Cu") (net 244))
  (segment (start 208.1963 75.814314) (end 208.585685 76.2037) (width 0.16) (layer "In9.Cu") (net 244))
  (segment (start 211.414121 73.375264) (end 211.396204 73.357347) (width 0.16) (layer "In9.Cu") (net 244))
  (segment (start 209.610518 74.046542) (end 209.610519 74.046542) (width 0.16) (layer "In9.Cu") (net 244))
  (segment (start 207.489191 76.521423) (end 207.878576 76.910809) (width 0.16) (layer "In9.Cu") (net 244))
  (segment (start 206.800001 77.246446) (end 206.782085 77.22853) (width 0.16) (layer "In9.Cu") (net 244))
  (segment (start 207.153556 76.892893) (end 207.330333 77.06967) (width 0.16) (layer "In9.Cu") (net 244))
  (segment (start 196.2 81.7) (end 198.2 81.7) (width 0.1) (layer "In9.Cu") (net 244))
  (segment (start 209.964073 74.046542) (end 210.353459 74.435927) (width 0.16) (layer "In9.Cu") (net 244))
  (segment (start 208.903409 75.107205) (end 209.292794 75.496591) (width 0.16) (layer "In9.Cu") (net 244))
  (segment (start 207.878577 77.264363) (end 207.878576 77.264363) (width 0.16) (layer "In9.Cu") (net 244))
  (segment (start 207.330333 77.06967) (end 207.33033 77.06967) (width 0.16) (layer "In9.Cu") (net 244))
  (segment (start 211.396204 73.003793) (end 216.4 68) (width 0.16) (layer "In9.Cu") (net 244))
  (segment (start 208.549855 75.46076) (end 208.939241 75.850145) (width 0.16) (layer "In9.Cu") (net 244))
  (segment locked (start 235.4 68) (end 216.4 68) (width 0.16) (layer "In9.Cu") (net 244))
  (segment (start 208.1963 75.46076) (end 208.196301 75.46076) (width 0.16) (layer "In9.Cu") (net 244))
  (segment (start 238.986328 56.360008) (end 238.986328 64.413672) (width 0.16) (layer "In9.Cu") (net 244))
  (segment (start 211.414122 73.728818) (end 211.414121 73.728818) (width 0.16) (layer "In9.Cu") (net 244))
  (segment (start 206.8 77.246448) (end 206.800001 77.246446) (width 0.16) (layer "In9.Cu") (net 244))
  (segment (start 208.585686 76.557254) (end 208.585685 76.557254) (width 0.16) (layer "In9.Cu") (net 244))
  (segment (start 207.135639 76.874976) (end 207.153556 76.892893) (width 0.16) (layer "In9.Cu") (net 244))
  (segment (start 207.489191 76.167869) (end 207.489192 76.167869) (width 0.16) (layer "In9.Cu") (net 244))
  (segment (start 198.2 81.7) (end 202.7 81.7) (width 0.16) (layer "In9.Cu") (net 244))
  (segment (start 208.903409 74.753651) (end 208.90341 74.753651) (width 0.16) (layer "In9.Cu") (net 244))
  (segment (start 209.292795 75.850145) (end 209.292794 75.850145) (width 0.16) (layer "In9.Cu") (net 244))
  (segment (start 210.317627 73.339433) (end 210.317628 73.339433) (width 0.16) (layer "In9.Cu") (net 244))
  (segment (start 210.707013 74.435927) (end 210.707012 74.435927) (width 0.16) (layer "In9.Cu") (net 244))
  (arc (start 209.292794 75.850145) (mid 209.366017 75.673368) (end 209.292794 75.496591) (width 0.16) (layer "In9.Cu") (net 244))
  (arc (start 207.489191 76.521423) (mid 207.415968 76.344646) (end 207.489191 76.167869) (width 0.16) (layer "In9.Cu") (net 244))
  (arc (start 208.196301 75.46076) (mid 208.373078 75.387537) (end 208.549855 75.46076) (width 0.16) (layer "In9.Cu") (net 244))
  (arc (start 208.90341 74.753651) (mid 209.080187 74.680428) (end 209.256964 74.753651) (width 0.16) (layer "In9.Cu") (net 244))
  (arc (start 208.1963 75.814314) (mid 208.123077 75.637537) (end 208.1963 75.46076) (width 0.16) (layer "In9.Cu") (net 244))
  (arc (start 209.999903 75.143036) (mid 210.073126 74.966259) (end 209.999903 74.789482) (width 0.16) (layer "In9.Cu") (net 244))
  (arc (start 210.317627 73.692987) (mid 210.244404 73.51621) (end 210.317627 73.339433) (width 0.16) (layer "In9.Cu") (net 244))
  (arc (start 209.610518 74.400096) (mid 209.537295 74.223319) (end 209.610518 74.046542) (width 0.16) (layer "In9.Cu") (net 244))
  (arc (start 211.060568 73.728818) (mid 211.237345 73.802041) (end 211.414122 73.728818) (width 0.16) (layer "In9.Cu") (net 244))
  (arc (start 206.782085 77.22853) (mid 206.708862 77.051753) (end 206.782085 76.874976) (width 0.16) (layer "In9.Cu") (net 244))
  (arc (start 208.939241 75.850145) (mid 209.116018 75.923368) (end 209.292795 75.850145) (width 0.16) (layer "In9.Cu") (net 244))
  (arc (start 209.64635 75.143036) (mid 209.823127 75.216259) (end 209.999904 75.143036) (width 0.16) (layer "In9.Cu") (net 244))
  (arc (start 206.782085 76.874976) (mid 206.958862 76.801753) (end 207.135639 76.874976) (width 0.16) (layer "In9.Cu") (net 244))
  (arc (start 211.414121 73.728818) (mid 211.487344 73.552041) (end 211.414121 73.375264) (width 0.16) (layer "In9.Cu") (net 244))
  (arc (start 211.396204 73.357347) (mid 211.322981 73.18057) (end 211.396204 73.003793) (width 0.16) (layer "In9.Cu") (net 244))
  (arc (start 208.903409 75.107205) (mid 208.830186 74.930428) (end 208.903409 74.753651) (width 0.16) (layer "In9.Cu") (net 244))
  (arc (start 208.232132 76.557254) (mid 208.408909 76.630477) (end 208.585686 76.557254) (width 0.16) (layer "In9.Cu") (net 244))
  (arc (start 210.707012 74.435927) (mid 210.780235 74.25915) (end 210.707012 74.082373) (width 0.16) (layer "In9.Cu") (net 244))
  (arc (start 210.317628 73.339433) (mid 210.494405 73.26621) (end 210.671182 73.339433) (width 0.16) (layer "In9.Cu") (net 244))
  (arc (start 207.489192 76.167869) (mid 207.665969 76.094646) (end 207.842746 76.167869) (width 0.16) (layer "In9.Cu") (net 244))
  (arc (start 208.585685 76.557254) (mid 208.658908 76.380477) (end 208.585685 76.2037) (width 0.16) (layer "In9.Cu") (net 244))
  (arc (start 209.610519 74.046542) (mid 209.787296 73.973319) (end 209.964073 74.046542) (width 0.16) (layer "In9.Cu") (net 244))
  (arc (start 207.878576 77.264363) (mid 207.951799 77.087586) (end 207.878576 76.910809) (width 0.16) (layer "In9.Cu") (net 244))
  (arc (start 210.353459 74.435927) (mid 210.530236 74.50915) (end 210.707013 74.435927) (width 0.16) (layer "In9.Cu") (net 244))
  (arc (start 207.525023 77.264363) (mid 207.7018 77.337586) (end 207.878577 77.264363) (width 0.16) (layer "In9.Cu") (net 244))
  (arc (start 206.8 77.6) (mid 206.873224 77.423223) (end 206.8 77.246448) (width 0.16) (layer "In9.Cu") (net 244))
  (segment (start 193.136328 84.560008) (end 193.636328 84.060008) (width 0.127) (layer "F.Cu") (net 245))
  (segment (start 235.586328 55.060008) (end 235.586328 56.360008) (width 0.2) (layer "F.Cu") (net 245))
  (segment (start 193.636328 84.060008) (end 193.655836 84.060008) (width 0.127) (layer "F.Cu") (net 245))
  (via blind (at 235.586328 56.360008) (size 0.5) (drill 0.2) (layers "F.Cu" "In5.Cu") (net 245))
  (via blind (at 193.655836 84.060008) (size 0.5) (drill 0.2) (layers "F.Cu" "In5.Cu") (net 245))
  (segment (start 235.586328 67.013672) (end 215.91 86.69) (width 0.146) (layer "In5.Cu") (net 245))
  (segment (start 215.91 86.69) (end 198.14 86.69) (width 0.146) (layer "In5.Cu") (net 245))
  (segment (start 194.31 86.86) (end 197.76 86.86) (width 0.09) (layer "In5.Cu") (net 245))
  (segment (start 197.76 86.86) (end 197.93 86.69) (width 0.09) (layer "In5.Cu") (net 245))
  (segment (start 193.240836 84.475008) (end 193.240836 85.790836) (width 0.09) (layer "In5.Cu") (net 245))
  (segment (start 235.586328 56.360008) (end 235.586328 67.013672) (width 0.146) (layer "In5.Cu") (net 245))
  (segment (start 193.240836 85.790836) (end 194.31 86.86) (width 0.09) (layer "In5.Cu") (net 245))
  (segment (start 197.93 86.69) (end 198.14 86.69) (width 0.09) (layer "In5.Cu") (net 245))
  (segment (start 193.655836 84.060008) (end 193.240836 84.475008) (width 0.09) (layer "In5.Cu") (net 245))
  (segment (start 195.636328 86.060008) (end 195.655836 86.060008) (width 0.127) (layer "F.Cu") (net 246))
  (segment (start 233.886328 55.060008) (end 233.886328 56.360008) (width 0.2) (layer "F.Cu") (net 246))
  (segment (start 195.136328 86.560008) (end 195.636328 86.060008) (width 0.127) (layer "F.Cu") (net 246))
  (via blind (at 233.886328 56.360008) (size 0.5) (drill 0.2) (layers "F.Cu" "In5.Cu") (net 246))
  (via blind (at 195.655836 86.060008) (size 0.5) (drill 0.2) (layers "F.Cu" "In5.Cu") (net 246))
  (segment (start 213.69 85.05) (end 213.69 84.95) (width 0.146) (layer "In5.Cu") (net 246))
  (segment (start 213.94 84.7) (end 214.6 84.7) (width 0.146) (layer "In5.Cu") (net 246))
  (segment (start 211.69 85.05) (end 211.69 84.35) (width 0.146) (layer "In5.Cu") (net 246))
  (segment (start 215.450304 83.405757) (end 215.450302 83.405758) (width 0.146) (layer "In5.Cu") (net 246))
  (segment (start 212.19 84.35) (end 212.19 85.05) (width 0.146) (layer "In5.Cu") (net 246))
  (segment (start 216.228123 82.627938) (end 216.228121 82.627939) (width 0.146) (layer "In5.Cu") (net 246))
  (segment (start 210.19 84.95) (end 210.19 85.05) (width 0.146) (layer "In5.Cu") (net 246))
  (segment (start 212.69 85.05) (end 212.69 84.35) (width 0.146) (layer "In5.Cu") (net 246))
  (segment (start 215.505333 84.238606) (end 215.505333 84.238607) (width 0.146) (layer "In5.Cu") (net 246))
  (segment (start 211.19 84.35) (end 211.19 85.05) (width 0.146) (layer "In5.Cu") (net 246))
  (segment (start 215.450302 83.405758) (end 215.894243 83.849697) (width 0.146) (layer "In5.Cu") (net 246))
  (segment (start 215.505333 84.238607) (end 215.061393 83.794667) (width 0.146) (layer "In5.Cu") (net 246))
  (segment (start 215.088908 84.6) (end 215.116424 84.627516) (width 0.146) (layer "In5.Cu") (net 246))
  (segment (start 195.655836 86.060008) (end 197.119992 86.060008) (width 0.09) (layer "In5.Cu") (net 246))
  (segment (start 216.228121 82.627939) (end 216.255638 82.655456) (width 0.146) (layer "In5.Cu") (net 246))
  (segment (start 217.794074 81.505926) (end 233.886328 65.413672) (width 0.146) (layer "In5.Cu") (net 246))
  (segment (start 210.69 85.05) (end 210.69 84.95) (width 0.146) (layer "In5.Cu") (net 246))
  (segment (start 216.283152 83.460788) (end 215.839212 83.016848) (width 0.146) (layer "In5.Cu") (net 246))
  (segment (start 216.644547 82.655455) (end 216.644548 82.655455) (width 0.146) (layer "In5.Cu") (net 246))
  (segment (start 214.6 84.7) (end 214.7 84.6) (width 0.146) (layer "In5.Cu") (net 246))
  (segment (start 215.505333 84.627515) (end 215.505333 84.627516) (width 0.146) (layer "In5.Cu") (net 246))
  (segment (start 210.69 84.95) (end 210.69 84.35) (width 0.146) (layer "In5.Cu") (net 246))
  (segment (start 202.66 85.64) (end 203.6 84.7) (width 0.146) (layer "In5.Cu") (net 246))
  (segment (start 197.119992 86.060008) (end 197.54 85.64) (width 0.09) (layer "In5.Cu") (net 246))
  (segment (start 213.19 84.35) (end 213.19 85.05) (width 0.146) (layer "In5.Cu") (net 246))
  (segment (start 215.061392 83.405758) (end 215.061394 83.405757) (width 0.146) (layer "In5.Cu") (net 246))
  (segment (start 197.54 85.64) (end 198.13 85.64) (width 0.09) (layer "In5.Cu") (net 246))
  (segment (start 216.283152 83.849698) (end 216.283152 83.849697) (width 0.146) (layer "In5.Cu") (net 246))
  (segment (start 215.839211 82.627939) (end 215.839213 82.627938) (width 0.146) (layer "In5.Cu") (net 246))
  (segment (start 198.13 85.64) (end 202.66 85.64) (width 0.146) (layer "In5.Cu") (net 246))
  (segment (start 233.886328 65.413672) (end 233.886328 56.360008) (width 0.146) (layer "In5.Cu") (net 246))
  (segment (start 216.644548 82.655455) (end 217.794074 81.505926) (width 0.146) (layer "In5.Cu") (net 246))
  (segment (start 216.283152 83.460787) (end 216.283152 83.460788) (width 0.146) (layer "In5.Cu") (net 246))
  (segment (start 203.6 84.7) (end 209.94 84.7) (width 0.146) (layer "In5.Cu") (net 246))
  (arc (start 213.44 85.3) (mid 213.616777 85.226777) (end 213.69 85.05) (width 0.146) (layer "In5.Cu") (net 246))
  (arc (start 209.94 84.7) (mid 210.116777 84.773223) (end 210.19 84.95) (width 0.146) (layer "In5.Cu") (net 246))
  (arc (start 211.69 84.35) (mid 211.763223 84.173223) (end 211.94 84.1) (width 0.146) (layer "In5.Cu") (net 246))
  (arc (start 213.19 85.05) (mid 213.263223 85.226777) (end 213.44 85.3) (width 0.146) (layer "In5.Cu") (net 246))
  (arc (start 216.255638 82.655456) (mid 216.450093 82.736001) (end 216.644547 82.655455) (width 0.146) (layer "In5.Cu") (net 246))
  (arc (start 215.894243 83.849697) (mid 216.088697 83.930243) (end 216.283152 83.849698) (width 0.146) (layer "In5.Cu") (net 246))
  (arc (start 211.19 85.05) (mid 211.263223 85.226777) (end 211.44 85.3) (width 0.146) (layer "In5.Cu") (net 246))
  (arc (start 214.7 84.6) (mid 214.894454 84.519455) (end 215.088908 84.6) (width 0.146) (layer "In5.Cu") (net 246))
  (arc (start 215.061393 83.794667) (mid 214.980847 83.600213) (end 215.061392 83.405758) (width 0.146) (layer "In5.Cu") (net 246))
  (arc (start 212.19 85.05) (mid 212.263223 85.226777) (end 212.44 85.3) (width 0.146) (layer "In5.Cu") (net 246))
  (arc (start 215.116424 84.627516) (mid 215.310879 84.708061) (end 215.505333 84.627515) (width 0.146) (layer "In5.Cu") (net 246))
  (arc (start 212.69 84.35) (mid 212.763223 84.173223) (end 212.94 84.1) (width 0.146) (layer "In5.Cu") (net 246))
  (arc (start 215.839212 83.016848) (mid 215.758666 82.822394) (end 215.839211 82.627939) (width 0.146) (layer "In5.Cu") (net 246))
  (arc (start 211.44 85.3) (mid 211.616777 85.226777) (end 211.69 85.05) (width 0.146) (layer "In5.Cu") (net 246))
  (arc (start 212.94 84.1) (mid 213.116777 84.173223) (end 213.19 84.35) (width 0.146) (layer "In5.Cu") (net 246))
  (arc (start 210.19 85.05) (mid 210.263223 85.226777) (end 210.44 85.3) (width 0.146) (layer "In5.Cu") (net 246))
  (arc (start 212.44 85.3) (mid 212.616777 85.226777) (end 212.69 85.05) (width 0.146) (layer "In5.Cu") (net 246))
  (arc (start 210.69 84.35) (mid 210.763223 84.173223) (end 210.94 84.1) (width 0.146) (layer "In5.Cu") (net 246))
  (arc (start 211.94 84.1) (mid 212.116777 84.173223) (end 212.19 84.35) (width 0.146) (layer "In5.Cu") (net 246))
  (arc (start 210.44 85.3) (mid 210.616777 85.226777) (end 210.69 85.05) (width 0.146) (layer "In5.Cu") (net 246))
  (arc (start 213.69 84.95) (mid 213.763223 84.773223) (end 213.94 84.7) (width 0.146) (layer "In5.Cu") (net 246))
  (arc (start 215.839213 82.627938) (mid 216.033667 82.547393) (end 216.228123 82.627938) (width 0.146) (layer "In5.Cu") (net 246))
  (arc (start 210.94 84.1) (mid 211.116777 84.173223) (end 211.19 84.35) (width 0.146) (layer "In5.Cu") (net 246))
  (arc (start 215.061394 83.405757) (mid 215.255848 83.325212) (end 215.450304 83.405757) (width 0.146) (layer "In5.Cu") (net 246))
  (arc (start 215.505333 84.627516) (mid 215.585879 84.433061) (end 215.505333 84.238606) (width 0.146) (layer "In5.Cu") (net 246))
  (arc (start 216.283152 83.849697) (mid 216.363698 83.655242) (end 216.283152 83.460787) (width 0.146) (layer "In5.Cu") (net 246))
  (segment (start 193.136328 82.560008) (end 193.636328 82.060008) (width 0.127) (layer "F.Cu") (net 247))
  (segment (start 193.636328 82.060008) (end 193.655836 82.060008) (width 0.127) (layer "F.Cu") (net 247))
  (segment (start 229.636328 55.060008) (end 229.636328 56.360008) (width 0.2) (layer "F.Cu") (net 247))
  (via blind (at 193.655836 82.060008) (size 0.5) (drill 0.2) (layers "F.Cu" "In5.Cu") (net 247))
  (via blind (at 229.636328 56.360008) (size 0.5) (drill 0.2) (layers "F.Cu" "In5.Cu") (net 247))
  (segment (start 219.369187 71.676777) (end 219.369188 71.676775) (width 0.146) (layer "In5.Cu") (net 247))
  (segment (start 214.672348 77.501688) (end 214.672349 77.501688) (width 0.146) (layer "In5.Cu") (net 247))
  (segment (start 220.352655 71.539363) (end 220.352654 71.539362) (width 0.146) (layer "In5.Cu") (net 247))
  (segment (start 220.53213 71.14) (end 220.86 71.14) (width 0.146) (layer "In5.Cu") (net 247))
  (segment (start 217.615562 73.71242) (end 217.89758 73.994438) (width 0.146) (layer "In5.Cu") (net 247))
  (segment (start 216.075248 76.098788) (end 216.075249 76.098788) (width 0.146) (layer "In5.Cu") (net 247))
  (segment (start 216.776699 75.397338) (end 216.845405 75.328631) (width 0.146) (layer "In5.Cu") (net 247))
  (segment (start 214.039605 77.852413) (end 213.757587 77.570395) (width 0.146) (layer "In5.Cu") (net 247))
  (segment (start 220.283948 71.890088) (end 220.283949 71.890088) (width 0.146) (layer "In5.Cu") (net 247))
  (segment (start 218.179599 73.994438) (end 218.248305 73.925731) (width 0.146) (layer "In5.Cu") (net 247))
  (segment (start 218.667737 72.378227) (end 218.667738 72.378225) (width 0.146) (layer "In5.Cu") (net 247))
  (segment (start 213.196732 78.413265) (end 213.197146 78.412854) (width 0.146) (layer "In5.Cu") (net 247))
  (segment (start 219.719912 71.60807) (end 220.00193 71.890088) (width 0.146) (layer "In5.Cu") (net 247))
  (segment (start 218.949755 72.942263) (end 218.667737 72.660245) (width 0.146) (layer "In5.Cu") (net 247))
  (segment (start 213.056137 77.989827) (end 213.056138 77.989825) (width 0.146) (layer "In5.Cu") (net 247))
  (segment (start 215.511212 75.81677) (end 215.79323 76.098788) (width 0.146) (layer "In5.Cu") (net 247))
  (segment (start 212.653934 78.956066) (end 212.705 78.905) (width 0.146) (layer "In5.Cu") (net 247))
  (segment (start 220.283949 71.890088) (end 220.352655 71.821381) (width 0.146) (layer "In5.Cu") (net 247))
  (segment (start 213.056138 77.989825) (end 213.124844 77.92112) (width 0.146) (layer "In5.Cu") (net 247))
  (segment (start 229.636328 62.363672) (end 229.636328 56.360008) (width 0.146) (layer "In5.Cu") (net 247))
  (segment (start 214.459037 76.586927) (end 214.459038 76.586925) (width 0.146) (layer "In5.Cu") (net 247))
  (segment (start 215.373799 76.800238) (end 215.442505 76.731531) (width 0.146) (layer "In5.Cu") (net 247))
  (segment (start 217.264837 73.781127) (end 217.264838 73.781125) (width 0.146) (layer "In5.Cu") (net 247))
  (segment (start 216.075249 76.098788) (end 216.143955 76.030081) (width 0.146) (layer "In5.Cu") (net 247))
  (segment (start 198.12 80.49) (end 197.11 80.49) (width 0.09) (layer "In5.Cu") (net 247))
  (segment (start 214.741055 77.150963) (end 214.459037 76.868945) (width 0.146) (layer "In5.Cu") (net 247))
  (segment (start 217.966287 73.079677) (end 217.966288 73.079675) (width 0.146) (layer "In5.Cu") (net 247))
  (segment (start 213.970898 78.203138) (end 213.970899 78.203138) (width 0.146) (layer "In5.Cu") (net 247))
  (segment (start 213.970899 78.203138) (end 214.039605 78.134431) (width 0.146) (layer "In5.Cu") (net 247))
  (segment (start 215.861937 75.184027) (end 215.861938 75.184025) (width 0.146) (layer "In5.Cu") (net 247))
  (segment (start 217.264838 73.781125) (end 217.333544 73.71242) (width 0.146) (layer "In5.Cu") (net 247))
  (segment (start 215.160487 75.885477) (end 215.160488 75.885475) (width 0.146) (layer "In5.Cu") (net 247))
  (segment (start 217.546855 74.345163) (end 217.264837 74.063145) (width 0.146) (layer "In5.Cu") (net 247))
  (segment (start 214.459038 76.586925) (end 214.527744 76.51822) (width 0.146) (layer "In5.Cu") (net 247))
  (segment (start 217.478149 74.695888) (end 217.546855 74.627181) (width 0.146) (layer "In5.Cu") (net 247))
  (segment (start 216.212662 75.11532) (end 216.49468 75.397338) (width 0.146) (layer "In5.Cu") (net 247))
  (segment (start 215.442505 76.449513) (end 215.160487 76.167495) (width 0.146) (layer "In5.Cu") (net 247))
  (segment (start 216.563387 74.482577) (end 216.563388 74.482575) (width 0.146) (layer "In5.Cu") (net 247))
  (segment (start 216.143955 75.748063) (end 215.861937 75.466045) (width 0.146) (layer "In5.Cu") (net 247))
  (segment (start 197.11 80.49) (end 196.73 80.87) (width 0.09) (layer "In5.Cu") (net 247))
  (segment (start 218.881048 73.292988) (end 218.881049 73.292988) (width 0.146) (layer "In5.Cu") (net 247))
  (segment (start 194.827735 81.475008) (end 194.240836 81.475008) (width 0.09) (layer "In5.Cu") (net 247))
  (segment (start 216.845405 75.046613) (end 216.563387 74.764595) (width 0.146) (layer "In5.Cu") (net 247))
  (segment (start 218.317012 73.01097) (end 218.59903 73.292988) (width 0.146) (layer "In5.Cu") (net 247))
  (segment (start 213.757587 77.288377) (end 213.757588 77.288375) (width 0.146) (layer "In5.Cu") (net 247))
  (segment (start 218.881049 73.292988) (end 218.949755 73.224281) (width 0.146) (layer "In5.Cu") (net 247))
  (segment (start 196.73 80.87) (end 195.200836 80.87) (width 0.09) (layer "In5.Cu") (net 247))
  (segment (start 217.478148 74.695888) (end 217.478149 74.695888) (width 0.146) (layer "In5.Cu") (net 247))
  (segment (start 214.809762 76.51822) (end 215.09178 76.800238) (width 0.146) (layer "In5.Cu") (net 247))
  (segment (start 219.582498 72.591538) (end 219.582499 72.591538) (width 0.146) (layer "In5.Cu") (net 247))
  (segment (start 213.757588 77.288375) (end 213.826294 77.21967) (width 0.146) (layer "In5.Cu") (net 247))
  (segment (start 201.8 79) (end 212.547868 79) (width 0.146) (layer "In5.Cu") (net 247))
  (segment (start 217.966288 73.079675) (end 218.034994 73.01097) (width 0.146) (layer "In5.Cu") (net 247))
  (segment (start 195.200836 80.87) (end 195.070836 81) (width 0.09) (layer "In5.Cu") (net 247))
  (segment (start 195.070836 81.231907) (end 194.827735 81.475008) (width 0.09) (layer "In5.Cu") (net 247))
  (segment (start 214.108312 77.21967) (end 214.39033 77.501688) (width 0.146) (layer "In5.Cu") (net 247))
  (segment (start 219.582499 72.591538) (end 219.651205 72.522831) (width 0.146) (layer "In5.Cu") (net 247))
  (segment (start 220.86 71.14) (end 229.636328 62.363672) (width 0.146) (layer "In5.Cu") (net 247))
  (segment (start 195.070836 81) (end 195.070836 81.231907) (width 0.09) (layer "In5.Cu") (net 247))
  (segment (start 216.914112 74.41387) (end 217.19613 74.695888) (width 0.146) (layer "In5.Cu") (net 247))
  (segment (start 219.651205 72.240813) (end 219.369187 71.958795) (width 0.146) (layer "In5.Cu") (net 247))
  (segment (start 216.776698 75.397338) (end 216.776699 75.397338) (width 0.146) (layer "In5.Cu") (net 247))
  (segment (start 216.563388 74.482575) (end 216.632094 74.41387) (width 0.146) (layer "In5.Cu") (net 247))
  (segment (start 218.667738 72.378225) (end 218.736444 72.30952) (width 0.146) (layer "In5.Cu") (net 247))
  (segment (start 219.369188 71.676775) (end 219.437894 71.60807) (width 0.146) (layer "In5.Cu") (net 247))
  (segment (start 198.12 80.49) (end 200.31 80.49) (width 0.146) (layer "In5.Cu") (net 247))
  (segment (start 213.197146 78.412854) (end 213.056137 78.271845) (width 0.146) (layer "In5.Cu") (net 247))
  (segment (start 220.352654 71.257344) (end 220.426064 71.183934) (width 0.146) (layer "In5.Cu") (net 247))
  (segment (start 213.269036 78.905) (end 213.337742 78.836293) (width 0.146) (layer "In5.Cu") (net 247))
  (segment (start 218.179598 73.994438) (end 218.179599 73.994438) (width 0.146) (layer "In5.Cu") (net 247))
  (segment (start 215.861938 75.184025) (end 215.930644 75.11532) (width 0.146) (layer "In5.Cu") (net 247))
  (segment (start 215.373798 76.800238) (end 215.373799 76.800238) (width 0.146) (layer "In5.Cu") (net 247))
  (segment (start 218.248305 73.643713) (end 217.966287 73.361695) (width 0.146) (layer "In5.Cu") (net 247))
  (segment (start 219.018462 72.30952) (end 219.30048 72.591538) (width 0.146) (layer "In5.Cu") (net 247))
  (segment (start 214.672349 77.501688) (end 214.741055 77.432981) (width 0.146) (layer "In5.Cu") (net 247))
  (segment (start 200.31 80.49) (end 201.8 79) (width 0.146) (layer "In5.Cu") (net 247))
  (segment (start 213.406862 77.92112) (end 213.68888 78.203138) (width 0.146) (layer "In5.Cu") (net 247))
  (segment (start 194.240836 81.475008) (end 193.655836 82.060008) (width 0.09) (layer "In5.Cu") (net 247))
  (segment (start 215.160488 75.885475) (end 215.229194 75.81677) (width 0.146) (layer "In5.Cu") (net 247))
  (segment (start 213.337742 78.554275) (end 213.196732 78.413265) (width 0.146) (layer "In5.Cu") (net 247))
  (arc (start 220.00193 71.890088) (mid 220.142939 71.948496) (end 220.283948 71.890088) (width 0.146) (layer "In5.Cu") (net 247))
  (arc (start 216.563387 74.764595) (mid 216.50498 74.623585) (end 216.563387 74.482577) (width 0.146) (layer "In5.Cu") (net 247))
  (arc (start 212.705 78.905) (mid 212.846009 78.846592) (end 212.987018 78.905) (width 0.146) (layer "In5.Cu") (net 247))
  (arc (start 218.949755 73.224281) (mid 219.008163 73.083272) (end 218.949755 72.942263) (width 0.146) (layer "In5.Cu") (net 247))
  (arc (start 213.826294 77.21967) (mid 213.967304 77.161261) (end 214.108312 77.21967) (width 0.146) (layer "In5.Cu") (net 247))
  (arc (start 220.426064 71.183934) (mid 220.474727 71.151418) (end 220.53213 71.14) (width 0.146) (layer "In5.Cu") (net 247))
  (arc (start 217.264837 74.063145) (mid 217.20643 73.922135) (end 217.264837 73.781127) (width 0.146) (layer "In5.Cu") (net 247))
  (arc (start 215.09178 76.800238) (mid 215.232789 76.858646) (end 215.373798 76.800238) (width 0.146) (layer "In5.Cu") (net 247))
  (arc (start 216.49468 75.397338) (mid 216.635689 75.455746) (end 216.776698 75.397338) (width 0.146) (layer "In5.Cu") (net 247))
  (arc (start 214.741055 77.432981) (mid 214.799463 77.291972) (end 214.741055 77.150963) (width 0.146) (layer "In5.Cu") (net 247))
  (arc (start 214.459037 76.868945) (mid 214.40063 76.727935) (end 214.459037 76.586927) (width 0.146) (layer "In5.Cu") (net 247))
  (arc (start 217.333544 73.71242) (mid 217.474554 73.654011) (end 217.615562 73.71242) (width 0.146) (layer "In5.Cu") (net 247))
  (arc (start 212.987018 78.905) (mid 213.128027 78.963408) (end 213.269036 78.905) (width 0.146) (layer "In5.Cu") (net 247))
  (arc (start 215.442505 76.731531) (mid 215.500913 76.590522) (end 215.442505 76.449513) (width 0.146) (layer "In5.Cu") (net 247))
  (arc (start 219.437894 71.60807) (mid 219.578904 71.549661) (end 219.719912 71.60807) (width 0.146) (layer "In5.Cu") (net 247))
  (arc (start 220.352654 71.539362) (mid 220.294246 71.398353) (end 220.352654 71.257344) (width 0.146) (layer "In5.Cu") (net 247))
  (arc (start 220.352655 71.821381) (mid 220.411063 71.680372) (end 220.352655 71.539363) (width 0.146) (layer "In5.Cu") (net 247))
  (arc (start 213.68888 78.203138) (mid 213.829889 78.261546) (end 213.970898 78.203138) (width 0.146) (layer "In5.Cu") (net 247))
  (arc (start 213.757587 77.570395) (mid 213.69918 77.429385) (end 213.757587 77.288377) (width 0.146) (layer "In5.Cu") (net 247))
  (arc (start 219.651205 72.522831) (mid 219.709613 72.381822) (end 219.651205 72.240813) (width 0.146) (layer "In5.Cu") (net 247))
  (arc (start 218.034994 73.01097) (mid 218.176004 72.952561) (end 218.317012 73.01097) (width 0.146) (layer "In5.Cu") (net 247))
  (arc (start 215.861937 75.466045) (mid 215.80353 75.325035) (end 215.861937 75.184027) (width 0.146) (layer "In5.Cu") (net 247))
  (arc (start 216.632094 74.41387) (mid 216.773104 74.355461) (end 216.914112 74.41387) (width 0.146) (layer "In5.Cu") (net 247))
  (arc (start 214.527744 76.51822) (mid 214.668754 76.459811) (end 214.809762 76.51822) (width 0.146) (layer "In5.Cu") (net 247))
  (arc (start 219.30048 72.591538) (mid 219.441489 72.649946) (end 219.582498 72.591538) (width 0.146) (layer "In5.Cu") (net 247))
  (arc (start 214.39033 77.501688) (mid 214.531339 77.560096) (end 214.672348 77.501688) (width 0.146) (layer "In5.Cu") (net 247))
  (arc (start 217.966287 73.361695) (mid 217.90788 73.220685) (end 217.966287 73.079677) (width 0.146) (layer "In5.Cu") (net 247))
  (arc (start 218.59903 73.292988) (mid 218.740039 73.351396) (end 218.881048 73.292988) (width 0.146) (layer "In5.Cu") (net 247))
  (arc (start 216.845405 75.328631) (mid 216.903813 75.187622) (end 216.845405 75.046613) (width 0.146) (layer "In5.Cu") (net 247))
  (arc (start 218.667737 72.660245) (mid 218.60933 72.519235) (end 218.667737 72.378227) (width 0.146) (layer "In5.Cu") (net 247))
  (arc (start 214.039605 78.134431) (mid 214.098013 77.993422) (end 214.039605 77.852413) (width 0.146) (layer "In5.Cu") (net 247))
  (arc (start 213.124844 77.92112) (mid 213.265854 77.862711) (end 213.406862 77.92112) (width 0.146) (layer "In5.Cu") (net 247))
  (arc (start 217.19613 74.695888) (mid 217.337139 74.754296) (end 217.478148 74.695888) (width 0.146) (layer "In5.Cu") (net 247))
  (arc (start 215.79323 76.098788) (mid 215.934239 76.157196) (end 216.075248 76.098788) (width 0.146) (layer "In5.Cu") (net 247))
  (arc (start 215.160487 76.167495) (mid 215.10208 76.026485) (end 215.160487 75.885477) (width 0.146) (layer "In5.Cu") (net 247))
  (arc (start 215.229194 75.81677) (mid 215.370204 75.758361) (end 215.511212 75.81677) (width 0.146) (layer "In5.Cu") (net 247))
  (arc (start 213.337742 78.836293) (mid 213.39615 78.695284) (end 213.337742 78.554275) (width 0.146) (layer "In5.Cu") (net 247))
  (arc (start 215.930644 75.11532) (mid 216.071654 75.056911) (end 216.212662 75.11532) (width 0.146) (layer "In5.Cu") (net 247))
  (arc (start 213.056137 78.271845) (mid 212.99773 78.130835) (end 213.056137 77.989827) (width 0.146) (layer "In5.Cu") (net 247))
  (arc (start 216.143955 76.030081) (mid 216.202363 75.889072) (end 216.143955 75.748063) (width 0.146) (layer "In5.Cu") (net 247))
  (arc (start 217.546855 74.627181) (mid 217.605263 74.486172) (end 217.546855 74.345163) (width 0.146) (layer "In5.Cu") (net 247))
  (arc (start 217.89758 73.994438) (mid 218.038589 74.052846) (end 218.179598 73.994438) (width 0.146) (layer "In5.Cu") (net 247))
  (arc (start 218.248305 73.925731) (mid 218.306713 73.784722) (end 218.248305 73.643713) (width 0.146) (layer "In5.Cu") (net 247))
  (arc (start 219.369187 71.958795) (mid 219.31078 71.817785) (end 219.369187 71.676777) (width 0.146) (layer "In5.Cu") (net 247))
  (arc (start 212.653934 78.956066) (mid 212.605271 78.988582) (end 212.547868 79) (width 0.146) (layer "In5.Cu") (net 247))
  (arc (start 218.736444 72.30952) (mid 218.877454 72.251111) (end 219.018462 72.30952) (width 0.146) (layer "In5.Cu") (net 247))
  (segment (start 227.936328 55.060008) (end 227.936328 56.360008) (width 0.2) (layer "F.Cu") (net 248))
  (segment (start 194.136328 80.560008) (end 194.636328 80.060008) (width 0.127) (layer "F.Cu") (net 248))
  (segment (start 194.636328 80.060008) (end 194.655836 80.060008) (width 0.127) (layer "F.Cu") (net 248))
  (via blind (at 194.655836 80.060008) (size 0.5) (drill 0.2) (layers "F.Cu" "In5.Cu") (net 248))
  (via blind (at 227.936328 56.360008) (size 0.5) (drill 0.2) (layers "F.Cu" "In5.Cu") (net 248))
  (segment (start 201.6 76.9) (end 211.9 76.9) (width 0.146) (layer "In5.Cu") (net 248))
  (segment (start 213.102627 76.684811) (end 213.102628 76.684811) (width 0.146) (layer "In5.Cu") (net 248))
  (segment (start 216.991718 72.406811) (end 216.991718 72.406812) (width 0.146) (layer "In5.Cu") (net 248))
  (segment (start 217.559917 70.641554) (end 217.559915 70.641555) (width 0.146) (layer "In5.Cu") (net 248))
  (segment (start 215.436082 74.351358) (end 215.436082 74.351357) (width 0.146) (layer "In5.Cu") (net 248))
  (segment (start 217.559915 70.641555) (end 217.664727 70.746367) (width 0.146) (layer "In5.Cu") (net 248))
  (segment (start 211.9 76.9) (end 212.22 76.58) (width 0.146) (layer "In5.Cu") (net 248))
  (segment (start 213.880446 75.518084) (end 213.281916 74.919554) (width 0.146) (layer "In5.Cu") (net 248))
  (segment (start 213.102628 76.295902) (end 212.504098 75.697372) (width 0.146) (layer "In5.Cu") (net 248))
  (segment (start 217.769536 72.017904) (end 217.769536 72.017903) (width 0.146) (layer "In5.Cu") (net 248))
  (segment (start 213.880446 75.906994) (end 213.880446 75.906993) (width 0.146) (layer "In5.Cu") (net 248))
  (segment (start 212.504097 75.308463) (end 212.504099 75.308462) (width 0.146) (layer "In5.Cu") (net 248))
  (segment (start 216.2139 73.57354) (end 216.2139 73.573539) (width 0.146) (layer "In5.Cu") (net 248))
  (segment (start 214.448643 73.752827) (end 215.047173 74.351357) (width 0.146) (layer "In5.Cu") (net 248))
  (segment (start 216.004281 72.19719) (end 216.004279 72.197191) (width 0.146) (layer "In5.Cu") (net 248))
  (segment (start 214.658264 75.129176) (end 214.658264 75.129175) (width 0.146) (layer "In5.Cu") (net 248))
  (segment (start 214.658264 74.740266) (end 214.059734 74.141736) (width 0.146) (layer "In5.Cu") (net 248))
  (segment (start 213.102628 76.295901) (end 213.102628 76.295902) (width 0.146) (layer "In5.Cu") (net 248))
  (segment (start 214.658264 74.740265) (end 214.658264 74.740266) (width 0.146) (layer "In5.Cu") (net 248))
  (segment (start 213.670825 74.530645) (end 214.269355 75.129175) (width 0.146) (layer "In5.Cu") (net 248))
  (segment (start 213.670827 74.530644) (end 213.670825 74.530645) (width 0.146) (layer "In5.Cu") (net 248))
  (segment (start 216.2139 73.18463) (end 215.61537 72.5861) (width 0.146) (layer "In5.Cu") (net 248))
  (segment (start 215.226461 72.975009) (end 215.824991 73.573539) (width 0.146) (layer "In5.Cu") (net 248))
  (segment (start 199.25 79.25) (end 201.6 76.9) (width 0.146) (layer "In5.Cu") (net 248))
  (segment (start 217.769536 71.628994) (end 217.171006 71.030464) (width 0.146) (layer "In5.Cu") (net 248))
  (segment (start 214.059733 73.752827) (end 214.059735 73.752826) (width 0.146) (layer "In5.Cu") (net 248))
  (segment (start 212.608908 76.58) (end 212.713719 76.684811) (width 0.146) (layer "In5.Cu") (net 248))
  (segment (start 218.053635 70.746367) (end 218.053637 70.746366) (width 0.146) (layer "In5.Cu") (net 248))
  (segment (start 216.991718 72.795722) (end 216.991718 72.795721) (width 0.146) (layer "In5.Cu") (net 248))
  (segment (start 215.615369 72.197191) (end 215.615371 72.19719) (width 0.146) (layer "In5.Cu") (net 248))
  (segment (start 213.281915 74.530645) (end 213.281917 74.530644) (width 0.146) (layer "In5.Cu") (net 248))
  (segment (start 196.97 79.23) (end 198.11 79.23) (width 0.09) (layer "In5.Cu") (net 248))
  (segment (start 218.053637 70.746366) (end 227.936328 60.863672) (width 0.146) (layer "In5.Cu") (net 248))
  (segment (start 216.782099 71.419372) (end 216.782097 71.419373) (width 0.146) (layer "In5.Cu") (net 248))
  (segment (start 196.139992 80.060008) (end 196.97 79.23) (width 0.09) (layer "In5.Cu") (net 248))
  (segment (start 227.936328 60.863672) (end 227.936328 56.360008) (width 0.146) (layer "In5.Cu") (net 248))
  (segment (start 216.393187 71.419373) (end 216.393189 71.419372) (width 0.146) (layer "In5.Cu") (net 248))
  (segment (start 216.004279 72.197191) (end 216.602809 72.795721) (width 0.146) (layer "In5.Cu") (net 248))
  (segment (start 217.769536 71.628993) (end 217.769536 71.628994) (width 0.146) (layer "In5.Cu") (net 248))
  (segment (start 216.991718 72.406812) (end 216.393188 71.808282) (width 0.146) (layer "In5.Cu") (net 248))
  (segment (start 215.436082 73.962447) (end 215.436082 73.962448) (width 0.146) (layer "In5.Cu") (net 248))
  (segment (start 214.837551 72.975009) (end 214.837553 72.975008) (width 0.146) (layer "In5.Cu") (net 248))
  (segment (start 216.782097 71.419373) (end 217.380627 72.017903) (width 0.146) (layer "In5.Cu") (net 248))
  (segment (start 217.171005 70.641555) (end 217.171007 70.641554) (width 0.146) (layer "In5.Cu") (net 248))
  (segment (start 215.436082 73.962448) (end 214.837552 73.363918) (width 0.146) (layer "In5.Cu") (net 248))
  (segment (start 212.893009 75.308462) (end 212.893007 75.308463) (width 0.146) (layer "In5.Cu") (net 248))
  (segment (start 198.13 79.25) (end 199.25 79.25) (width 0.146) (layer "In5.Cu") (net 248))
  (segment (start 216.2139 73.184629) (end 216.2139 73.18463) (width 0.146) (layer "In5.Cu") (net 248))
  (segment (start 212.893007 75.308463) (end 213.491537 75.906993) (width 0.146) (layer "In5.Cu") (net 248))
  (segment (start 215.226463 72.975008) (end 215.226461 72.975009) (width 0.146) (layer "In5.Cu") (net 248))
  (segment (start 194.655836 80.060008) (end 196.139992 80.060008) (width 0.09) (layer "In5.Cu") (net 248))
  (segment (start 214.448645 73.752826) (end 214.448643 73.752827) (width 0.146) (layer "In5.Cu") (net 248))
  (segment (start 213.880446 75.518083) (end 213.880446 75.518084) (width 0.146) (layer "In5.Cu") (net 248))
  (segment (start 198.11 79.23) (end 198.13 79.25) (width 0.09) (layer "In5.Cu") (net 248))
  (arc (start 212.713719 76.684811) (mid 212.908173 76.765356) (end 213.102627 76.684811) (width 0.146) (layer "In5.Cu") (net 248))
  (arc (start 213.281917 74.530644) (mid 213.476371 74.450099) (end 213.670827 74.530644) (width 0.146) (layer "In5.Cu") (net 248))
  (arc (start 214.837553 72.975008) (mid 215.032007 72.894463) (end 215.226463 72.975008) (width 0.146) (layer "In5.Cu") (net 248))
  (arc (start 215.615371 72.19719) (mid 215.809825 72.116645) (end 216.004281 72.19719) (width 0.146) (layer "In5.Cu") (net 248))
  (arc (start 215.824991 73.573539) (mid 216.019445 73.654085) (end 216.2139 73.57354) (width 0.146) (layer "In5.Cu") (net 248))
  (arc (start 216.393189 71.419372) (mid 216.587643 71.338827) (end 216.782099 71.419372) (width 0.146) (layer "In5.Cu") (net 248))
  (arc (start 214.269355 75.129175) (mid 214.463809 75.209721) (end 214.658264 75.129176) (width 0.146) (layer "In5.Cu") (net 248))
  (arc (start 212.504098 75.697372) (mid 212.423552 75.502918) (end 212.504097 75.308463) (width 0.146) (layer "In5.Cu") (net 248))
  (arc (start 213.102628 76.684811) (mid 213.183174 76.490356) (end 213.102628 76.295901) (width 0.146) (layer "In5.Cu") (net 248))
  (arc (start 217.380627 72.017903) (mid 217.575081 72.098449) (end 217.769536 72.017904) (width 0.146) (layer "In5.Cu") (net 248))
  (arc (start 217.664727 70.746367) (mid 217.859182 70.826911) (end 218.053635 70.746367) (width 0.146) (layer "In5.Cu") (net 248))
  (arc (start 212.504099 75.308462) (mid 212.698553 75.227917) (end 212.893009 75.308462) (width 0.146) (layer "In5.Cu") (net 248))
  (arc (start 217.769536 72.017903) (mid 217.850082 71.823448) (end 217.769536 71.628993) (width 0.146) (layer "In5.Cu") (net 248))
  (arc (start 216.991718 72.795721) (mid 217.072264 72.601266) (end 216.991718 72.406811) (width 0.146) (layer "In5.Cu") (net 248))
  (arc (start 213.281916 74.919554) (mid 213.20137 74.7251) (end 213.281915 74.530645) (width 0.146) (layer "In5.Cu") (net 248))
  (arc (start 216.2139 73.573539) (mid 216.294446 73.379084) (end 216.2139 73.184629) (width 0.146) (layer "In5.Cu") (net 248))
  (arc (start 216.393188 71.808282) (mid 216.312642 71.613828) (end 216.393187 71.419373) (width 0.146) (layer "In5.Cu") (net 248))
  (arc (start 213.491537 75.906993) (mid 213.685991 75.987539) (end 213.880446 75.906994) (width 0.146) (layer "In5.Cu") (net 248))
  (arc (start 214.059734 74.141736) (mid 213.979188 73.947282) (end 214.059733 73.752827) (width 0.146) (layer "In5.Cu") (net 248))
  (arc (start 215.436082 74.351357) (mid 215.516628 74.156902) (end 215.436082 73.962447) (width 0.146) (layer "In5.Cu") (net 248))
  (arc (start 217.171007 70.641554) (mid 217.365461 70.561009) (end 217.559917 70.641554) (width 0.146) (layer "In5.Cu") (net 248))
  (arc (start 215.61537 72.5861) (mid 215.534824 72.391646) (end 215.615369 72.197191) (width 0.146) (layer "In5.Cu") (net 248))
  (arc (start 216.602809 72.795721) (mid 216.797263 72.876267) (end 216.991718 72.795722) (width 0.146) (layer "In5.Cu") (net 248))
  (arc (start 214.837552 73.363918) (mid 214.757006 73.169464) (end 214.837551 72.975009) (width 0.146) (layer "In5.Cu") (net 248))
  (arc (start 214.658264 75.129175) (mid 214.73881 74.93472) (end 214.658264 74.740265) (width 0.146) (layer "In5.Cu") (net 248))
  (arc (start 214.059735 73.752826) (mid 214.254189 73.672281) (end 214.448645 73.752826) (width 0.146) (layer "In5.Cu") (net 248))
  (arc (start 217.171006 71.030464) (mid 217.09046 70.83601) (end 217.171005 70.641555) (width 0.146) (layer "In5.Cu") (net 248))
  (arc (start 212.22 76.58) (mid 212.414454 76.499455) (end 212.608908 76.58) (width 0.146) (layer "In5.Cu") (net 248))
  (arc (start 213.880446 75.906993) (mid 213.960992 75.712538) (end 213.880446 75.518083) (width 0.146) (layer "In5.Cu") (net 248))
  (arc (start 215.047173 74.351357) (mid 215.241627 74.431903) (end 215.436082 74.351358) (width 0.146) (layer "In5.Cu") (net 248))
  (segment (start 196.636328 86.060008) (end 196.655836 86.060008) (width 0.127) (layer "F.Cu") (net 249))
  (segment (start 196.136328 86.560008) (end 196.636328 86.060008) (width 0.127) (layer "F.Cu") (net 249))
  (segment (start 226.236328 55.060008) (end 226.236328 56.360008) (width 0.2) (layer "F.Cu") (net 249))
  (via blind (at 226.236328 56.360008) (size 0.5) (drill 0.2) (layers "F.Cu" "In2.Cu") (net 249))
  (via blind (at 196.655836 86.060008) (size 0.5) (drill 0.2) (layers "F.Cu" "In2.Cu") (net 249))
  (segment (start 196.655836 86.060008) (end 197.599992 86.060008) (width 0.1) (layer "In2.Cu") (net 249))
  (segment (start 200.15 85.55) (end 198.11 85.55) (width 0.16) (layer "In2.Cu") (net 249))
  (segment (start 201.1 84.6) (end 200.15 85.55) (width 0.16) (layer "In2.Cu") (net 249))
  (segment (start 212.6 84.6) (end 201.1 84.6) (width 0.16) (layer "In2.Cu") (net 249))
  (segment (start 226.236328 70.963672) (end 212.6 84.6) (width 0.16) (layer "In2.Cu") (net 249))
  (segment (start 226.236328 56.360008) (end 226.236328 70.963672) (width 0.16) (layer "In2.Cu") (net 249))
  (segment (start 197.599992 86.060008) (end 198.11 85.55) (width 0.1) (layer "In2.Cu") (net 249))
  (segment (start 224.536328 55.060008) (end 224.536328 56.360008) (width 0.2) (layer "F.Cu") (net 250))
  (segment (start 196.136328 85.560008) (end 196.636328 85.060008) (width 0.127) (layer "F.Cu") (net 250))
  (segment (start 196.636328 85.060008) (end 196.655836 85.060008) (width 0.127) (layer "F.Cu") (net 250))
  (via blind (at 196.655836 85.060008) (size 0.5) (drill 0.2) (layers "F.Cu" "In2.Cu") (net 250))
  (via blind (at 224.536328 56.360008) (size 0.5) (drill 0.2) (layers "F.Cu" "In2.Cu") (net 250))
  (segment (start 199.01 84.33) (end 200.34 83) (width 0.16) (layer "In2.Cu") (net 250))
  (segment (start 196.655836 85.060008) (end 197.319992 85.060008) (width 0.1) (layer "In2.Cu") (net 250))
  (segment (start 200.34 83) (end 210.8 83) (width 0.16) (layer "In2.Cu") (net 250))
  (segment (start 214.801181 79.531326) (end 214.747058 79.477203) (width 0.16) (layer "In2.Cu") (net 250))
  (segment (start 216.306209 77.493791) (end 224.536328 69.263672) (width 0.16) (layer "In2.Cu") (net 250))
  (segment (start 210.8 83) (end 213.05 80.75) (width 0.16) (layer "In2.Cu") (net 250))
  (segment (start 213.474264 80.75) (end 213.528386 80.804122) (width 0.16) (layer "In2.Cu") (net 250))
  (segment (start 224.536328 69.263672) (end 224.536328 56.360008) (width 0.16) (layer "In2.Cu") (net 250))
  (segment (start 213.809053 79.387728) (end 214.376917 79.955591) (width 0.16) (layer "In2.Cu") (net 250))
  (segment (start 213.95265 80.379856) (end 213.95265 80.379857) (width 0.16) (layer "In2.Cu") (net 250))
  (segment (start 213.809053 79.387729) (end 213.809053 79.387728) (width 0.16) (layer "In2.Cu") (net 250))
  (segment (start 197.319992 85.060008) (end 198.05 84.33) (width 0.1) (layer "In2.Cu") (net 250))
  (segment (start 213.384788 79.387728) (end 213.384787 79.387729) (width 0.16) (layer "In2.Cu") (net 250))
  (segment (start 213.95265 80.379857) (end 213.384787 79.811993) (width 0.16) (layer "In2.Cu") (net 250))
  (segment (start 198.05 84.33) (end 199.01 84.33) (width 0.16) (layer "In2.Cu") (net 250))
  (segment (start 214.801181 79.531325) (end 214.801181 79.531326) (width 0.16) (layer "In2.Cu") (net 250))
  (segment (start 214.747058 79.052939) (end 216.306209 77.493791) (width 0.16) (layer "In2.Cu") (net 250))
  (arc (start 213.384787 79.811993) (mid 213.29692 79.599859) (end 213.384788 79.387728) (width 0.16) (layer "In2.Cu") (net 250))
  (arc (start 213.95265 80.804122) (mid 214.040518 80.591989) (end 213.95265 80.379856) (width 0.16) (layer "In2.Cu") (net 250))
  (arc (start 214.801181 79.955591) (mid 214.889049 79.743458) (end 214.801181 79.531325) (width 0.16) (layer "In2.Cu") (net 250))
  (arc (start 213.05 80.75) (mid 213.262132 80.662132) (end 213.474264 80.75) (width 0.16) (layer "In2.Cu") (net 250))
  (arc (start 213.528386 80.804122) (mid 213.740518 80.89199) (end 213.95265 80.804122) (width 0.16) (layer "In2.Cu") (net 250))
  (arc (start 214.376917 79.955591) (mid 214.589049 80.043459) (end 214.801181 79.955591) (width 0.16) (layer "In2.Cu") (net 250))
  (arc (start 213.384787 79.387729) (mid 213.596921 79.29986) (end 213.809053 79.387729) (width 0.16) (layer "In2.Cu") (net 250))
  (arc (start 214.747058 79.477203) (mid 214.65919 79.265071) (end 214.747058 79.052939) (width 0.16) (layer "In2.Cu") (net 250))
  (segment (start 195.52 81.176336) (end 195.136328 81.560008) (width 0.127) (layer "F.Cu") (net 251))
  (segment (start 220.286328 55.060008) (end 220.286328 56.360008) (width 0.2) (layer "F.Cu") (net 251))
  (segment (start 195.52 81.07) (end 195.52 81.176336) (width 0.127) (layer "F.Cu") (net 251))
  (via blind (at 220.286328 56.360008) (size 0.5) (drill 0.2) (layers "F.Cu" "In2.Cu") (net 251))
  (via blind (at 195.52 81.07) (size 0.5) (drill 0.2) (layers "F.Cu" "In2.Cu") (net 251))
  (segment (start 201 79.2) (end 205 79.2) (width 0.16) (layer "In2.Cu") (net 251))
  (segment (start 208.745981 76.268165) (end 208.745982 76.268165) (width 0.16) (layer "In2.Cu") (net 251))
  (segment (start 209.487473 74.28729) (end 209.487471 74.287291) (width 0.16) (layer "In2.Cu") (net 251))
  (segment (start 209.5238 75.490348) (end 209.5238 75.490347) (width 0.16) (layer "In2.Cu") (net 251))
  (segment (start 211.450181 72.749821) (end 211.450183 72.74982) (width 0.16) (layer "In2.Cu") (net 251))
  (segment (start 195.52 80.67) (end 195.52 81.07) (width 0.1) (layer "In2.Cu") (net 251))
  (segment (start 210.265291 73.509472) (end 210.265289 73.509473) (width 0.16) (layer "In2.Cu") (net 251))
  (segment (start 209.5238 75.101437) (end 209.5238 75.101438) (width 0.16) (layer "In2.Cu") (net 251))
  (segment (start 208.745982 75.879255) (end 208.745982 75.879256) (width 0.16) (layer "In2.Cu") (net 251))
  (segment (start 209.098561 74.287291) (end 209.098563 74.28729) (width 0.16) (layer "In2.Cu") (net 251))
  (segment (start 208.709655 75.065108) (end 208.709653 75.065109) (width 0.16) (layer "In2.Cu") (net 251))
  (segment (start 211.079436 73.934712) (end 211.079436 73.934711) (width 0.16) (layer "In2.Cu") (net 251))
  (segment (start 211.043107 72.731655) (end 211.061273 72.749821) (width 0.16) (layer "In2.Cu") (net 251))
  (segment (start 211.079436 73.545802) (end 210.654198 73.120564) (width 0.16) (layer "In2.Cu") (net 251))
  (segment (start 211.450183 72.74982) (end 220.286328 63.913672) (width 0.16) (layer "In2.Cu") (net 251))
  (segment (start 200.66 79.54) (end 201 79.2) (width 0.16) (layer "In2.Cu") (net 251))
  (segment (start 198.2 79.54) (end 196.581874 79.54) (width 0.1) (layer "In2.Cu") (net 251))
  (segment (start 210.265289 73.509473) (end 210.690527 73.934711) (width 0.16) (layer "In2.Cu") (net 251))
  (segment (start 210.301618 74.71253) (end 210.301618 74.712529) (width 0.16) (layer "In2.Cu") (net 251))
  (segment (start 208.709653 75.065109) (end 209.134891 75.490347) (width 0.16) (layer "In2.Cu") (net 251))
  (segment (start 208.320743 75.065109) (end 208.320745 75.065108) (width 0.16) (layer "In2.Cu") (net 251))
  (segment (start 209.487471 74.287291) (end 209.912709 74.712529) (width 0.16) (layer "In2.Cu") (net 251))
  (segment (start 210.654197 72.731655) (end 210.654199 72.731654) (width 0.16) (layer "In2.Cu") (net 251))
  (segment (start 209.876379 73.509473) (end 209.876381 73.509472) (width 0.16) (layer "In2.Cu") (net 251))
  (segment (start 196.581874 79.54) (end 196.235836 79.886038) (width 0.1) (layer "In2.Cu") (net 251))
  (segment (start 210.301618 74.32362) (end 209.87638 73.898382) (width 0.16) (layer "In2.Cu") (net 251))
  (segment (start 196.235836 79.954164) (end 195.52 80.67) (width 0.1) (layer "In2.Cu") (net 251))
  (segment (start 211.043109 72.731654) (end 211.043107 72.731655) (width 0.16) (layer "In2.Cu") (net 251))
  (segment (start 208.745982 75.879256) (end 208.320744 75.454018) (width 0.16) (layer "In2.Cu") (net 251))
  (segment (start 209.5238 75.101438) (end 209.098562 74.6762) (width 0.16) (layer "In2.Cu") (net 251))
  (segment (start 211.079436 73.545801) (end 211.079436 73.545802) (width 0.16) (layer "In2.Cu") (net 251))
  (segment (start 210.301618 74.323619) (end 210.301618 74.32362) (width 0.16) (layer "In2.Cu") (net 251))
  (segment (start 196.235836 79.886038) (end 196.235836 79.954164) (width 0.1) (layer "In2.Cu") (net 251))
  (segment (start 205 79.2) (end 207.95 76.25) (width 0.16) (layer "In2.Cu") (net 251))
  (segment (start 198.2 79.54) (end 200.66 79.54) (width 0.16) (layer "In2.Cu") (net 251))
  (segment (start 220.286328 63.913672) (end 220.286328 56.360008) (width 0.16) (layer "In2.Cu") (net 251))
  (segment (start 208.338908 76.25) (end 208.357073 76.268165) (width 0.16) (layer "In2.Cu") (net 251))
  (arc (start 210.690527 73.934711) (mid 210.884981 74.015257) (end 211.079436 73.934712) (width 0.16) (layer "In2.Cu") (net 251))
  (arc (start 207.95 76.25) (mid 208.144454 76.169455) (end 208.338908 76.25) (width 0.16) (layer "In2.Cu") (net 251))
  (arc (start 211.079436 73.934711) (mid 211.159982 73.740256) (end 211.079436 73.545801) (width 0.16) (layer "In2.Cu") (net 251))
  (arc (start 211.061273 72.749821) (mid 211.255728 72.830365) (end 211.450181 72.749821) (width 0.16) (layer "In2.Cu") (net 251))
  (arc (start 209.098562 74.6762) (mid 209.018016 74.481746) (end 209.098561 74.287291) (width 0.16) (layer "In2.Cu") (net 251))
  (arc (start 208.745982 76.268165) (mid 208.826528 76.07371) (end 208.745982 75.879255) (width 0.16) (layer "In2.Cu") (net 251))
  (arc (start 208.320744 75.454018) (mid 208.240198 75.259564) (end 208.320743 75.065109) (width 0.16) (layer "In2.Cu") (net 251))
  (arc (start 209.87638 73.898382) (mid 209.795834 73.703928) (end 209.876379 73.509473) (width 0.16) (layer "In2.Cu") (net 251))
  (arc (start 210.301618 74.712529) (mid 210.382164 74.518074) (end 210.301618 74.323619) (width 0.16) (layer "In2.Cu") (net 251))
  (arc (start 209.912709 74.712529) (mid 210.107163 74.793075) (end 210.301618 74.71253) (width 0.16) (layer "In2.Cu") (net 251))
  (arc (start 210.654198 73.120564) (mid 210.573652 72.92611) (end 210.654197 72.731655) (width 0.16) (layer "In2.Cu") (net 251))
  (arc (start 209.098563 74.28729) (mid 209.293017 74.206745) (end 209.487473 74.28729) (width 0.16) (layer "In2.Cu") (net 251))
  (arc (start 210.654199 72.731654) (mid 210.848653 72.651109) (end 211.043109 72.731654) (width 0.16) (layer "In2.Cu") (net 251))
  (arc (start 209.134891 75.490347) (mid 209.329345 75.570893) (end 209.5238 75.490348) (width 0.16) (layer "In2.Cu") (net 251))
  (arc (start 208.357073 76.268165) (mid 208.551527 76.34871) (end 208.745981 76.268165) (width 0.16) (layer "In2.Cu") (net 251))
  (arc (start 208.320745 75.065108) (mid 208.515199 74.984563) (end 208.709655 75.065108) (width 0.16) (layer "In2.Cu") (net 251))
  (arc (start 209.876381 73.509472) (mid 210.070835 73.428927) (end 210.265291 73.509472) (width 0.16) (layer "In2.Cu") (net 251))
  (arc (start 209.5238 75.490347) (mid 209.604346 75.295892) (end 209.5238 75.101437) (width 0.16) (layer "In2.Cu") (net 251))
  (segment (start 216.886328 55.060008) (end 216.886328 56.360008) (width 0.2) (layer "F.Cu") (net 252))
  (segment (start 195.136328 78.560008) (end 195.636328 78.060008) (width 0.127) (layer "F.Cu") (net 252))
  (segment (start 195.636328 78.060008) (end 195.655836 78.060008) (width 0.127) (layer "F.Cu") (net 252))
  (via blind (at 195.655836 78.060008) (size 0.5) (drill 0.2) (layers "F.Cu" "In5.Cu") (net 252))
  (via blind (at 216.886328 56.360008) (size 0.5) (drill 0.2) (layers "F.Cu" "In5.Cu") (net 252))
  (segment (start 197.867055 74.768528) (end 197.865683 74.767156) (width 0.146) (layer "In5.Cu") (net 252))
  (segment (start 197.2 75.525) (end 197.2 75.9) (width 0.09) (layer "In5.Cu") (net 252))
  (segment (start 196.187 76.913) (end 196.187 77.528844) (width 0.09) (layer "In5.Cu") (net 252))
  (segment (start 200.15 72.2) (end 209.7 72.2) (width 0.146) (layer "In5.Cu") (net 252))
  (segment (start 197.865684 74.484313) (end 197.865683 74.484314) (width 0.146) (layer "In5.Cu") (net 252))
  (segment (start 197.867055 74.768527) (end 197.867055 74.768528) (width 0.146) (layer "In5.Cu") (net 252))
  (segment (start 197.2 75.9) (end 196.187 76.913) (width 0.09) (layer "In5.Cu") (net 252))
  (segment (start 197.865683 74.484314) (end 200.15 72.2) (width 0.146) (layer "In5.Cu") (net 252))
  (segment (start 197.2 75.15) (end 197.3 75.05) (width 0.146) (layer "In5.Cu") (net 252))
  (segment (start 197.2 75.525) (end 197.2 75.15) (width 0.146) (layer "In5.Cu") (net 252))
  (segment (start 209.7 72.2) (end 216.886328 65.013672) (width 0.146) (layer "In5.Cu") (net 252))
  (segment (start 216.886328 65.013672) (end 216.886328 56.360008) (width 0.146) (layer "In5.Cu") (net 252))
  (segment (start 196.187 77.528844) (end 195.655836 78.060008) (width 0.09) (layer "In5.Cu") (net 252))
  (segment (start 197.867056 75.05137) (end 197.867055 75.051371) (width 0.146) (layer "In5.Cu") (net 252))
  (segment (start 197.582842 75.05) (end 197.584213 75.051371) (width 0.146) (layer "In5.Cu") (net 252))
  (arc (start 197.584213 75.051371) (mid 197.725635 75.109949) (end 197.867056 75.05137) (width 0.146) (layer "In5.Cu") (net 252))
  (arc (start 197.867055 75.051371) (mid 197.925634 74.909949) (end 197.867055 74.768527) (width 0.146) (layer "In5.Cu") (net 252))
  (arc (start 197.865683 74.767156) (mid 197.807105 74.625734) (end 197.865684 74.484313) (width 0.146) (layer "In5.Cu") (net 252))
  (arc (start 197.3 75.05) (mid 197.441421 74.991422) (end 197.582842 75.05) (width 0.146) (layer "In5.Cu") (net 252))
  (segment (start 195.52 80.107) (end 195.136328 80.490672) (width 0.127) (layer "F.Cu") (net 253))
  (segment (start 195.136328 80.490672) (end 195.136328 80.560008) (width 0.127) (layer "F.Cu") (net 253))
  (segment (start 195.52 80.06) (end 195.52 80.107) (width 0.127) (layer "F.Cu") (net 253))
  (segment (start 218.586328 55.060008) (end 218.586328 56.360008) (width 0.2) (layer "F.Cu") (net 253))
  (via blind (at 218.586328 56.360008) (size 0.5) (drill 0.2) (layers "F.Cu" "In2.Cu") (net 253))
  (via blind (at 195.52 80.06) (size 0.5) (drill 0.2) (layers "F.Cu" "In2.Cu") (net 253))
  (segment (start 210.348719 70.551281) (end 212.6 68.3) (width 0.16) (layer "In2.Cu") (net 253))
  (segment (start 208.19099 73.557538) (end 208.19099 73.557537) (width 0.16) (layer "In2.Cu") (net 253))
  (segment (start 213.384386 68.30657) (end 213.384386 68.306569) (width 0.16) (layer "In2.Cu") (net 253))
  (segment (start 208.968808 72.77972) (end 208.968808 72.779719) (width 0.16) (layer "In2.Cu") (net 253))
  (segment (start 207.413172 73.946445) (end 207.413172 73.946446) (width 0.16) (layer "In2.Cu") (net 253))
  (segment (start 208.898099 71.542283) (end 209.357717 72.001901) (width 0.16) (layer "In2.Cu") (net 253))
  (segment (start 208.120283 72.3201) (end 208.120281 72.320101) (width 0.16) (layer "In2.Cu") (net 253))
  (segment (start 212.988908 68.3) (end 212.995477 68.306569) (width 0.16) (layer "In2.Cu") (net 253))
  (segment (start 209.746626 72.001902) (end 209.746626 72.001901) (width 0.16) (layer "In2.Cu") (net 253))
  (segment (start 214.162205 67.528751) (end 214.162204 67.528752) (width 0.16) (layer "In2.Cu") (net 253))
  (segment (start 208.19099 73.168628) (end 207.731372 72.70901) (width 0.16) (layer "In2.Cu") (net 253))
  (segment (start 209.675917 70.764465) (end 209.711273 70.799821) (width 0.16) (layer "In2.Cu") (net 253))
  (segment (start 207.413172 73.946446) (end 206.953554 73.486828) (width 0.16) (layer "In2.Cu") (net 253))
  (segment (start 196.55 78.57) (end 196.152 78.968) (width 0.1) (layer "In2.Cu") (net 253))
  (segment (start 214.162204 67.139843) (end 214.155634 67.133273) (width 0.16) (layer "In2.Cu") (net 253))
  (segment (start 208.968808 72.390809) (end 208.968808 72.39081) (width 0.16) (layer "In2.Cu") (net 253))
  (segment (start 210.100183 70.79982) (end 210.348719 70.551281) (width 0.16) (layer "In2.Cu") (net 253))
  (segment (start 214.155633 66.744364) (end 214.155634 66.744364) (width 0.16) (layer "In2.Cu") (net 253))
  (segment (start 212.98234 67.126704) (end 212.982339 67.126705) (width 0.16) (layer "In2.Cu") (net 253))
  (segment (start 208.19099 73.168627) (end 208.19099 73.168628) (width 0.16) (layer "In2.Cu") (net 253))
  (segment (start 198.2 78.57) (end 196.55 78.57) (width 0.1) (layer "In2.Cu") (net 253))
  (segment (start 218.586328 62.313672) (end 218.586328 56.360008) (width 0.16) (layer "In2.Cu") (net 253))
  (segment (start 208.120281 72.320101) (end 208.579899 72.779719) (width 0.16) (layer "In2.Cu") (net 253))
  (segment (start 213.371249 67.126704) (end 213.773296 67.528752) (width 0.16) (layer "In2.Cu") (net 253))
  (segment (start 214.155634 66.744364) (end 218.586328 62.313672) (width 0.16) (layer "In2.Cu") (net 253))
  (segment (start 210.100182 70.79982) (end 210.100183 70.79982) (width 0.16) (layer "In2.Cu") (net 253))
  (segment (start 213.384386 67.917659) (end 213.384386 67.91766) (width 0.16) (layer "In2.Cu") (net 253))
  (segment (start 213.371249 67.126705) (end 213.371249 67.126704) (width 0.16) (layer "In2.Cu") (net 253))
  (segment (start 200.4 77.5) (end 203.4 77.5) (width 0.16) (layer "In2.Cu") (net 253))
  (segment (start 208.898101 71.542282) (end 208.898099 71.542283) (width 0.16) (layer "In2.Cu") (net 253))
  (segment (start 208.968808 72.39081) (end 208.50919 71.931192) (width 0.16) (layer "In2.Cu") (net 253))
  (segment (start 207.731371 72.320101) (end 207.731373 72.3201) (width 0.16) (layer "In2.Cu") (net 253))
  (segment (start 207.342465 73.097918) (end 207.342463 73.097919) (width 0.16) (layer "In2.Cu") (net 253))
  (segment (start 209.287007 70.764465) (end 209.287009 70.764464) (width 0.16) (layer "In2.Cu") (net 253))
  (segment (start 214.162204 67.139842) (end 214.162204 67.139843) (width 0.16) (layer "In2.Cu") (net 253))
  (segment (start 206.953553 73.097919) (end 206.953555 73.097918) (width 0.16) (layer "In2.Cu") (net 253))
  (segment (start 203.4 77.5) (end 206.6 74.3) (width 0.16) (layer "In2.Cu") (net 253))
  (segment (start 209.746626 71.612992) (end 209.287008 71.153374) (width 0.16) (layer "In2.Cu") (net 253))
  (segment (start 213.384386 67.91766) (end 212.982339 67.515613) (width 0.16) (layer "In2.Cu") (net 253))
  (segment (start 207.413172 74.335354) (end 207.413172 74.335355) (width 0.16) (layer "In2.Cu") (net 253))
  (segment (start 208.509189 71.542283) (end 208.509191 71.542282) (width 0.16) (layer "In2.Cu") (net 253))
  (segment (start 196.152 79.428) (end 195.52 80.06) (width 0.1) (layer "In2.Cu") (net 253))
  (segment (start 209.746626 71.612991) (end 209.746626 71.612992) (width 0.16) (layer "In2.Cu") (net 253))
  (segment (start 199.33 78.57) (end 200.4 77.5) (width 0.16) (layer "In2.Cu") (net 253))
  (segment (start 209.675919 70.764464) (end 209.675917 70.764465) (width 0.16) (layer "In2.Cu") (net 253))
  (segment (start 198.2 78.57) (end 199.33 78.57) (width 0.16) (layer "In2.Cu") (net 253))
  (segment (start 207.342463 73.097919) (end 207.802081 73.557537) (width 0.16) (layer "In2.Cu") (net 253))
  (segment (start 206.988908 74.3) (end 207.024263 74.335355) (width 0.16) (layer "In2.Cu") (net 253))
  (segment (start 196.152 78.968) (end 196.152 79.428) (width 0.1) (layer "In2.Cu") (net 253))
  (arc (start 207.413172 74.335355) (mid 207.493718 74.1409) (end 207.413172 73.946445) (width 0.16) (layer "In2.Cu") (net 253))
  (arc (start 209.287009 70.764464) (mid 209.481463 70.683919) (end 209.675919 70.764464) (width 0.16) (layer "In2.Cu") (net 253))
  (arc (start 208.579899 72.779719) (mid 208.774353 72.860265) (end 208.968808 72.77972) (width 0.16) (layer "In2.Cu") (net 253))
  (arc (start 214.162204 67.528752) (mid 214.24275 67.334297) (end 214.162204 67.139842) (width 0.16) (layer "In2.Cu") (net 253))
  (arc (start 209.711273 70.799821) (mid 209.905728 70.880366) (end 210.100182 70.79982) (width 0.16) (layer "In2.Cu") (net 253))
  (arc (start 214.155634 67.133273) (mid 214.075088 66.938819) (end 214.155633 66.744364) (width 0.16) (layer "In2.Cu") (net 253))
  (arc (start 208.19099 73.557537) (mid 208.271536 73.363082) (end 208.19099 73.168627) (width 0.16) (layer "In2.Cu") (net 253))
  (arc (start 209.357717 72.001901) (mid 209.552171 72.082447) (end 209.746626 72.001902) (width 0.16) (layer "In2.Cu") (net 253))
  (arc (start 208.50919 71.931192) (mid 208.428644 71.736738) (end 208.509189 71.542283) (width 0.16) (layer "In2.Cu") (net 253))
  (arc (start 212.982339 67.515613) (mid 212.901794 67.321158) (end 212.98234 67.126704) (width 0.16) (layer "In2.Cu") (net 253))
  (arc (start 207.731372 72.70901) (mid 207.650826 72.514556) (end 207.731371 72.320101) (width 0.16) (layer "In2.Cu") (net 253))
  (arc (start 213.773296 67.528752) (mid 213.967751 67.609297) (end 214.162205 67.528751) (width 0.16) (layer "In2.Cu") (net 253))
  (arc (start 207.024263 74.335355) (mid 207.218718 74.4159) (end 207.413172 74.335354) (width 0.16) (layer "In2.Cu") (net 253))
  (arc (start 206.953554 73.486828) (mid 206.873008 73.292374) (end 206.953553 73.097919) (width 0.16) (layer "In2.Cu") (net 253))
  (arc (start 208.509191 71.542282) (mid 208.703645 71.461737) (end 208.898101 71.542282) (width 0.16) (layer "In2.Cu") (net 253))
  (arc (start 209.746626 72.001901) (mid 209.827172 71.807446) (end 209.746626 71.612991) (width 0.16) (layer "In2.Cu") (net 253))
  (arc (start 207.802081 73.557537) (mid 207.996535 73.638083) (end 208.19099 73.557538) (width 0.16) (layer "In2.Cu") (net 253))
  (arc (start 213.384386 68.306569) (mid 213.464932 68.112114) (end 213.384386 67.917659) (width 0.16) (layer "In2.Cu") (net 253))
  (arc (start 209.287008 71.153374) (mid 209.206462 70.95892) (end 209.287007 70.764465) (width 0.16) (layer "In2.Cu") (net 253))
  (arc (start 212.995477 68.306569) (mid 213.189931 68.387115) (end 213.384386 68.30657) (width 0.16) (layer "In2.Cu") (net 253))
  (arc (start 208.968808 72.779719) (mid 209.049354 72.585264) (end 208.968808 72.390809) (width 0.16) (layer "In2.Cu") (net 253))
  (arc (start 207.731373 72.3201) (mid 207.925827 72.239555) (end 208.120283 72.3201) (width 0.16) (layer "In2.Cu") (net 253))
  (arc (start 206.6 74.3) (mid 206.794454 74.219455) (end 206.988908 74.3) (width 0.16) (layer "In2.Cu") (net 253))
  (arc (start 212.6 68.3) (mid 212.794454 68.219455) (end 212.988908 68.3) (width 0.16) (layer "In2.Cu") (net 253))
  (arc (start 212.982339 67.126705) (mid 213.176795 67.046158) (end 213.371249 67.126705) (width 0.16) (layer "In2.Cu") (net 253))
  (arc (start 206.953555 73.097918) (mid 207.148009 73.017373) (end 207.342465 73.097918) (width 0.16) (layer "In2.Cu") (net 253))
  (segment (start 194.169508 78.560008) (end 194.669508 78.060008) (width 0.127) (layer "F.Cu") (net 254))
  (segment (start 215.186328 55.060008) (end 215.186328 56.360008) (width 0.2) (layer "F.Cu") (net 254))
  (segment (start 194.136328 78.560008) (end 194.169508 78.560008) (width 0.127) (layer "F.Cu") (net 254))
  (via blind (at 215.186328 56.360008) (size 0.5) (drill 0.2) (layers "F.Cu" "In5.Cu") (net 254))
  (via blind (at 194.669508 78.060008) (size 0.5) (drill 0.2) (layers "F.Cu" "In5.Cu") (net 254))
  (segment (start 200.49 70.4) (end 208.8 70.4) (width 0.146) (layer "In5.Cu") (net 254))
  (segment (start 195.185 77.544516) (end 195.185 76.355836) (width 0.09) (layer "In5.Cu") (net 254))
  (segment (start 208.8 70.4) (end 215.186328 64.013672) (width 0.146) (layer "In5.Cu") (net 254))
  (segment (start 199.89 70.2) (end 199.89 70.625778) (width 0.146) (layer "In5.Cu") (net 254))
  (segment (start 199.89 70.174222) (end 199.89 70.2) (width 0.146) (layer "In5.Cu") (net 254))
  (segment (start 200.29 70.625778) (end 200.29 70.6) (width 0.146) (layer "In5.Cu") (net 254))
  (segment (start 195.185 76.355836) (end 195.725 75.815836) (width 0.09) (layer "In5.Cu") (net 254))
  (segment (start 195.725 75.815836) (end 195.725 75.525) (width 0.09) (layer "In5.Cu") (net 254))
  (segment (start 195.725 73.675) (end 199 70.4) (width 0.146) (layer "In5.Cu") (net 254))
  (segment (start 215.186328 64.013672) (end 215.186328 56.360008) (width 0.146) (layer "In5.Cu") (net 254))
  (segment (start 199 70.4) (end 199.29 70.4) (width 0.146) (layer "In5.Cu") (net 254))
  (segment (start 195.725 75.525) (end 195.725 73.675) (width 0.146) (layer "In5.Cu") (net 254))
  (segment (start 199.49 70.2) (end 199.49 70.174222) (width 0.146) (layer "In5.Cu") (net 254))
  (segment (start 194.669508 78.060008) (end 195.185 77.544516) (width 0.09) (layer "In5.Cu") (net 254))
  (arc (start 200.09 70.825778) (mid 200.231421 70.767199) (end 200.29 70.625778) (width 0.146) (layer "In5.Cu") (net 254))
  (arc (start 199.49 70.174222) (mid 199.548579 70.032801) (end 199.69 69.974222) (width 0.146) (layer "In5.Cu") (net 254))
  (arc (start 200.29 70.6) (mid 200.348579 70.458579) (end 200.49 70.4) (width 0.146) (layer "In5.Cu") (net 254))
  (arc (start 199.69 69.974222) (mid 199.831421 70.032801) (end 199.89 70.174222) (width 0.146) (layer "In5.Cu") (net 254))
  (arc (start 199.89 70.625778) (mid 199.948579 70.767199) (end 200.09 70.825778) (width 0.146) (layer "In5.Cu") (net 254))
  (arc (start 199.29 70.4) (mid 199.431421 70.341421) (end 199.49 70.2) (width 0.146) (layer "In5.Cu") (net 254))
  (segment (start 210.936328 55.060008) (end 210.936328 56.360008) (width 0.2) (layer "F.Cu") (net 255))
  (segment (start 192.136328 78.560008) (end 192.636328 78.060008) (width 0.127) (layer "F.Cu") (net 255))
  (segment (start 192.636328 78.060008) (end 192.655836 78.060008) (width 0.127) (layer "F.Cu") (net 255))
  (via blind (at 192.655836 78.060008) (size 0.5) (drill 0.2) (layers "F.Cu" "In5.Cu") (net 255))
  (via blind (at 210.936328 56.360008) (size 0.5) (drill 0.2) (layers "F.Cu" "In5.Cu") (net 255))
  (segment (start 200.61 65.266463) (end 200.61 65.733537) (width 0.146) (layer "In5.Cu") (net 255))
  (segment (start 199.81 65.266463) (end 199.81 65.3) (width 0.146) (layer "In5.Cu") (net 255))
  (segment (start 192.14 69.98) (end 192.14 69.83) (width 0.146) (layer "In5.Cu") (net 255))
  (segment (start 192.14 75.5) (end 192.14 77.544172) (width 0.09) (layer "In5.Cu") (net 255))
  (segment (start 199.81 65.3) (end 199.81 65.733537) (width 0.146) (layer "In5.Cu") (net 255))
  (segment (start 210.936328 62.103672) (end 210.936328 56.360008) (width 0.146) (layer "In5.Cu") (net 255))
  (segment (start 196.4 65.5) (end 199.21 65.5) (width 0.146) (layer "In5.Cu") (net 255))
  (segment (start 201.41 65.266463) (end 201.41 65.733537) (width 0.146) (layer "In5.Cu") (net 255))
  (segment (start 200.21 65.733537) (end 200.21 65.266463) (width 0.146) (layer "In5.Cu") (net 255))
  (segment (start 192.14 69.76) (end 196.4 65.5) (width 0.146) (layer "In5.Cu") (net 255))
  (segment (start 199.41 65.3) (end 199.41 65.266463) (width 0.146) (layer "In5.Cu") (net 255))
  (segment (start 191.69 70.58) (end 191.69 70.43) (width 0.146) (layer "In5.Cu") (net 255))
  (segment (start 202.41 65.5) (end 207.54 65.5) (width 0.146) (layer "In5.Cu") (net 255))
  (segment (start 201.81 65.733537) (end 201.81 65.266463) (width 0.146) (layer "In5.Cu") (net 255))
  (segment (start 192.14 69.83) (end 192.14 69.76) (width 0.146) (layer "In5.Cu") (net 255))
  (segment (start 192.14 77.544172) (end 192.655836 78.060008) (width 0.09) (layer "In5.Cu") (net 255))
  (segment (start 202.21 65.266463) (end 202.21 65.3) (width 0.146) (layer "In5.Cu") (net 255))
  (segment (start 201.01 65.733537) (end 201.01 65.266463) (width 0.146) (layer "In5.Cu") (net 255))
  (segment (start 192.14 75.5) (end 192.14 71.03) (width 0.146) (layer "In5.Cu") (net 255))
  (segment (start 207.54 65.5) (end 210.936328 62.103672) (width 0.146) (layer "In5.Cu") (net 255))
  (arc (start 200.21 65.266463) (mid 200.268579 65.125042) (end 200.41 65.066463) (width 0.146) (layer "In5.Cu") (net 255))
  (arc (start 199.41 65.266463) (mid 199.468579 65.125042) (end 199.61 65.066463) (width 0.146) (layer "In5.Cu") (net 255))
  (arc (start 201.01 65.266463) (mid 201.068579 65.125042) (end 201.21 65.066463) (width 0.146) (layer "In5.Cu") (net 255))
  (arc (start 200.01 65.933537) (mid 200.151421 65.874958) (end 200.21 65.733537) (width 0.146) (layer "In5.Cu") (net 255))
  (arc (start 201.61 65.933537) (mid 201.751421 65.874958) (end 201.81 65.733537) (width 0.146) (layer "In5.Cu") (net 255))
  (arc (start 192.14 71.03) (mid 192.074099 70.870901) (end 191.915 70.805) (width 0.146) (layer "In5.Cu") (net 255))
  (arc (start 191.915 70.205) (mid 192.074099 70.139099) (end 192.14 69.98) (width 0.146) (layer "In5.Cu") (net 255))
  (arc (start 199.81 65.733537) (mid 199.868579 65.874958) (end 200.01 65.933537) (width 0.146) (layer "In5.Cu") (net 255))
  (arc (start 191.915 70.805) (mid 191.755901 70.739099) (end 191.69 70.58) (width 0.146) (layer "In5.Cu") (net 255))
  (arc (start 191.69 70.43) (mid 191.755901 70.270901) (end 191.915 70.205) (width 0.146) (layer "In5.Cu") (net 255))
  (arc (start 201.81 65.266463) (mid 201.868579 65.125042) (end 202.01 65.066463) (width 0.146) (layer "In5.Cu") (net 255))
  (arc (start 201.41 65.733537) (mid 201.468579 65.874958) (end 201.61 65.933537) (width 0.146) (layer "In5.Cu") (net 255))
  (arc (start 200.41 65.066463) (mid 200.551421 65.125042) (end 200.61 65.266463) (width 0.146) (layer "In5.Cu") (net 255))
  (arc (start 201.21 65.066463) (mid 201.351421 65.125042) (end 201.41 65.266463) (width 0.146) (layer "In5.Cu") (net 255))
  (arc (start 199.61 65.066463) (mid 199.751421 65.125042) (end 199.81 65.266463) (width 0.146) (layer "In5.Cu") (net 255))
  (arc (start 199.21 65.5) (mid 199.351421 65.441421) (end 199.41 65.3) (width 0.146) (layer "In5.Cu") (net 255))
  (arc (start 202.01 65.066463) (mid 202.151421 65.125042) (end 202.21 65.266463) (width 0.146) (layer "In5.Cu") (net 255))
  (arc (start 200.81 65.933537) (mid 200.951421 65.874958) (end 201.01 65.733537) (width 0.146) (layer "In5.Cu") (net 255))
  (arc (start 200.61 65.733537) (mid 200.668579 65.874958) (end 200.81 65.933537) (width 0.146) (layer "In5.Cu") (net 255))
  (arc (start 202.21 65.3) (mid 202.268579 65.441421) (end 202.41 65.5) (width 0.146) (layer "In5.Cu") (net 255))
  (segment (start 209.236328 55.060008) (end 209.236328 56.360008) (width 0.2) (layer "F.Cu") (net 256))
  (segment (start 192.636328 79.060008) (end 192.655836 79.060008) (width 0.127) (layer "F.Cu") (net 256))
  (segment (start 192.136328 79.560008) (end 192.636328 79.060008) (width 0.127) (layer "F.Cu") (net 256))
  (via blind (at 192.655836 79.060008) (size 0.5) (drill 0.2) (layers "F.Cu" "In5.Cu") (net 256))
  (via blind (at 209.236328 56.360008) (size 0.5) (drill 0.2) (layers "F.Cu" "In5.Cu") (net 256))
  (segment (start 190.45 77.55) (end 190.17 77.27) (width 0.09) (layer "In5.Cu") (net 256))
  (segment (start 191.570008 78.645008) (end 191.175 78.25) (width 0.09) (layer "In5.Cu") (net 256))
  (segment (start 190.17 75.5) (end 190.17 71.05) (width 0.146) (layer "In5.Cu") (net 256))
  (segment (start 192.240836 78.645008) (end 191.570008 78.645008) (width 0.09) (layer "In5.Cu") (net 256))
  (segment (start 189.92 70.3) (end 190.485979 70.3) (width 0.146) (layer "In5.Cu") (net 256))
  (segment (start 189.854021 69.8) (end 190.485979 69.8) (width 0.146) (layer "In5.Cu") (net 256))
  (segment (start 190.17 69.05) (end 190.17 68.73) (width 0.146) (layer "In5.Cu") (net 256))
  (segment (start 191.175 77.875) (end 190.85 77.55) (width 0.09) (layer "In5.Cu") (net 256))
  (segment (start 195.2 63.7) (end 207.03 63.7) (width 0.146) (layer "In5.Cu") (net 256))
  (segment (start 189.92 70.8) (end 189.854021 70.8) (width 0.146) (layer "In5.Cu") (net 256))
  (segment (start 189.854021 69.3) (end 189.92 69.3) (width 0.146) (layer "In5.Cu") (net 256))
  (segment (start 190.85 77.55) (end 190.45 77.55) (width 0.09) (layer "In5.Cu") (net 256))
  (segment (start 190.17 77.27) (end 190.17 75.5) (width 0.09) (layer "In5.Cu") (net 256))
  (segment (start 189.854021 70.3) (end 189.92 70.3) (width 0.146) (layer "In5.Cu") (net 256))
  (segment (start 190.17 68.73) (end 195.2 63.7) (width 0.146) (layer "In5.Cu") (net 256))
  (segment (start 209.236328 61.493672) (end 209.236328 56.360008) (width 0.146) (layer "In5.Cu") (net 256))
  (segment (start 207.03 63.7) (end 209.236328 61.493672) (width 0.146) (layer "In5.Cu") (net 256))
  (segment (start 192.655836 79.060008) (end 192.240836 78.645008) (width 0.09) (layer "In5.Cu") (net 256))
  (segment (start 191.175 78.25) (end 191.175 77.875) (width 0.09) (layer "In5.Cu") (net 256))
  (arc (start 189.604021 70.55) (mid 189.677244 70.373223) (end 189.854021 70.3) (width 0.146) (layer "In5.Cu") (net 256))
  (arc (start 190.485979 70.3) (mid 190.662756 70.226777) (end 190.735979 70.05) (width 0.146) (layer "In5.Cu") (net 256))
  (arc (start 189.92 69.3) (mid 190.096777 69.226777) (end 190.17 69.05) (width 0.146) (layer "In5.Cu") (net 256))
  (arc (start 189.604021 69.55) (mid 189.677244 69.373223) (end 189.854021 69.3) (width 0.146) (layer "In5.Cu") (net 256))
  (arc (start 190.17 71.05) (mid 190.096777 70.873223) (end 189.92 70.8) (width 0.146) (layer "In5.Cu") (net 256))
  (arc (start 189.854021 69.8) (mid 189.677244 69.726777) (end 189.604021 69.55) (width 0.146) (layer "In5.Cu") (net 256))
  (arc (start 190.735979 70.05) (mid 190.662756 69.873223) (end 190.485979 69.8) (width 0.146) (layer "In5.Cu") (net 256))
  (arc (start 189.854021 70.8) (mid 189.677244 70.726777) (end 189.604021 70.55) (width 0.146) (layer "In5.Cu") (net 256))
  (segment (start 180.136328 87.560008) (end 180.636328 87.060008) (width 0.127) (layer "F.Cu") (net 257))
  (segment (start 207.536328 55.060008) (end 207.536328 56.360008) (width 0.2) (layer "F.Cu") (net 257))
  (via (at 207.536328 56.360008) (size 0.5) (drill 0.2) (layers "F.Cu" "B.Cu") (net 257))
  (via (at 180.636328 87.060008) (size 0.5) (drill 0.2) (layers "F.Cu" "B.Cu") (net 257))
  (segment (start 183.202828 85.272172) (end 183.202828 76.782828) (width 0.127) (layer "In7.Cu") (net 257))
  (segment (start 182.74 75.56) (end 182.74 74.92) (width 0.196) (layer "In7.Cu") (net 257))
  (segment (start 184.21 74.85) (end 184.21 74.879647) (width 0.196) (layer "In7.Cu") (net 257))
  (segment (start 180.636328 87.060008) (end 181.096336 86.6) (width 0.127) (layer "In7.Cu") (net 257))
  (segment (start 186.46 74.6) (end 201.24 74.6) (width 0.196) (layer "In7.Cu") (net 257))
  (segment (start 182.4 85.6) (end 182.875 85.6) (width 0.127) (layer "In7.Cu") (net 257))
  (segment (start 182.74 74.92) (end 183.06 74.6) (width 0.196) (layer "In7.Cu") (net 257))
  (segment (start 201.24 74.6) (end 207.536328 68.303672) (width 0.196) (layer "In7.Cu") (net 257))
  (segment (start 183.06 74.6) (end 183.96 74.6) (width 0.196) (layer "In7.Cu") (net 257))
  (segment (start 182.875 85.6) (end 183.202828 85.272172) (width 0.127) (layer "In7.Cu") (net 257))
  (segment (start 185.71 74.879647) (end 185.71 74.320353) (width 0.196) (layer "In7.Cu") (net 257))
  (segment (start 186.21 74.320353) (end 186.21 74.35) (width 0.196) (layer "In7.Cu") (net 257))
  (segment (start 207.536328 68.303672) (end 207.536328 56.360008) (width 0.196) (layer "In7.Cu") (net 257))
  (segment (start 182.069828 85.930172) (end 182.4 85.6) (width 0.127) (layer "In7.Cu") (net 257))
  (segment (start 182.74 76.32) (end 182.74 75.56) (width 0.127) (layer "In7.Cu") (net 257))
  (segment (start 184.71 74.85) (end 184.71 74.320353) (width 0.196) (layer "In7.Cu") (net 257))
  (segment (start 185.21 74.320353) (end 185.21 74.879647) (width 0.196) (layer "In7.Cu") (net 257))
  (segment (start 183.202828 76.782828) (end 182.74 76.32) (width 0.127) (layer "In7.Cu") (net 257))
  (segment (start 182.069828 86.23957) (end 182.069828 85.930172) (width 0.127) (layer "In7.Cu") (net 257))
  (segment (start 184.71 74.879647) (end 184.71 74.85) (width 0.196) (layer "In7.Cu") (net 257))
  (segment (start 181.096336 86.6) (end 181.709398 86.6) (width 0.127) (layer "In7.Cu") (net 257))
  (segment (start 181.709398 86.6) (end 182.069828 86.23957) (width 0.127) (layer "In7.Cu") (net 257))
  (arc (start 185.46 75.129647) (mid 185.636777 75.056424) (end 185.71 74.879647) (width 0.196) (layer "In7.Cu") (net 257))
  (arc (start 184.46 75.129647) (mid 184.636777 75.056424) (end 184.71 74.879647) (width 0.196) (layer "In7.Cu") (net 257))
  (arc (start 183.96 74.6) (mid 184.136777 74.673223) (end 184.21 74.85) (width 0.196) (layer "In7.Cu") (net 257))
  (arc (start 184.21 74.879647) (mid 184.283223 75.056424) (end 184.46 75.129647) (width 0.196) (layer "In7.Cu") (net 257))
  (arc (start 185.21 74.879647) (mid 185.283223 75.056424) (end 185.46 75.129647) (width 0.196) (layer "In7.Cu") (net 257))
  (arc (start 184.71 74.320353) (mid 184.783223 74.143576) (end 184.96 74.070353) (width 0.196) (layer "In7.Cu") (net 257))
  (arc (start 186.21 74.35) (mid 186.283223 74.526777) (end 186.46 74.6) (width 0.196) (layer "In7.Cu") (net 257))
  (arc (start 185.96 74.070353) (mid 186.136777 74.143576) (end 186.21 74.320353) (width 0.196) (layer "In7.Cu") (net 257))
  (arc (start 184.96 74.070353) (mid 185.136777 74.143576) (end 185.21 74.320353) (width 0.196) (layer "In7.Cu") (net 257))
  (arc (start 185.71 74.320353) (mid 185.783223 74.143576) (end 185.96 74.070353) (width 0.196) (layer "In7.Cu") (net 257))
  (segment (start 205.836328 55.060008) (end 205.836328 56.360008) (width 0.2) (layer "F.Cu") (net 258))
  (segment (start 179.136328 87.560008) (end 179.636328 87.060008) (width 0.127) (layer "F.Cu") (net 258))
  (via (at 205.836328 56.360008) (size 0.5) (drill 0.2) (layers "F.Cu" "B.Cu") (net 258))
  (via (at 179.636328 87.060008) (size 0.5) (drill 0.2) (layers "F.Cu" "B.Cu") (net 258))
  (segment (start 181.3 77.63) (end 181.3 76.5) (width 0.127) (layer "In7.Cu") (net 258))
  (segment (start 183.86 71.9) (end 183.86 72.504869) (width 0.196) (layer "In7.Cu") (net 258))
  (segment (start 183.86 71.895131) (end 183.86 71.9) (width 0.196) (layer "In7.Cu") (net 258))
  (segment (start 180.191082 86.505254) (end 180.191082 85.828918) (width 0.127) (layer "In7.Cu") (net 258))
  (segment (start 185.66 72.504869) (end 185.66 71.895131) (width 0.196) (layer "In7.Cu") (net 258))
  (segment (start 180.95 73.72) (end 182.47 72.2) (width 0.196) (layer "In7.Cu") (net 258))
  (segment (start 200.49 72.2) (end 205.836328 66.853672) (width 0.196) (layer "In7.Cu") (net 258))
  (segment (start 186.56 72.2) (end 200.49 72.2) (width 0.196) (layer "In7.Cu") (net 258))
  (segment (start 181.15 85.22531) (end 181.15 77.78) (width 0.127) (layer "In7.Cu") (net 258))
  (segment (start 184.46 72.504869) (end 184.46 71.895131) (width 0.196) (layer "In7.Cu") (net 258))
  (segment (start 180.191082 85.828918) (end 180.52 85.5) (width 0.127) (layer "In7.Cu") (net 258))
  (segment (start 182.47 72.2) (end 182.96 72.2) (width 0.196) (layer "In7.Cu") (net 258))
  (segment (start 185.06 71.895131) (end 185.06 72.504869) (width 0.196) (layer "In7.Cu") (net 258))
  (segment (start 180.87531 85.5) (end 181.15 85.22531) (width 0.127) (layer "In7.Cu") (net 258))
  (segment (start 180.52 85.5) (end 180.87531 85.5) (width 0.127) (layer "In7.Cu") (net 258))
  (segment (start 205.836328 66.853672) (end 205.836328 56.360008) (width 0.196) (layer "In7.Cu") (net 258))
  (segment (start 180.95 76.15) (end 180.95 75.58) (width 0.127) (layer "In7.Cu") (net 258))
  (segment (start 180.95 75.58) (end 180.95 73.72) (width 0.196) (layer "In7.Cu") (net 258))
  (segment (start 179.636328 87.060008) (end 180.191082 86.505254) (width 0.127) (layer "In7.Cu") (net 258))
  (segment (start 181.3 76.5) (end 180.95 76.15) (width 0.127) (layer "In7.Cu") (net 258))
  (segment (start 181.15 77.78) (end 181.3 77.63) (width 0.127) (layer "In7.Cu") (net 258))
  (segment (start 183.26 71.9) (end 183.26 71.895131) (width 0.196) (layer "In7.Cu") (net 258))
  (segment (start 186.26 71.895131) (end 186.26 71.9) (width 0.196) (layer "In7.Cu") (net 258))
  (arc (start 184.46 71.895131) (mid 184.547868 71.682999) (end 184.76 71.595131) (width 0.196) (layer "In7.Cu") (net 258))
  (arc (start 186.26 71.9) (mid 186.347868 72.112132) (end 186.56 72.2) (width 0.196) (layer "In7.Cu") (net 258))
  (arc (start 184.76 71.595131) (mid 184.972132 71.682999) (end 185.06 71.895131) (width 0.196) (layer "In7.Cu") (net 258))
  (arc (start 185.06 72.504869) (mid 185.147868 72.717001) (end 185.36 72.804869) (width 0.196) (layer "In7.Cu") (net 258))
  (arc (start 183.86 72.504869) (mid 183.947868 72.717001) (end 184.16 72.804869) (width 0.196) (layer "In7.Cu") (net 258))
  (arc (start 182.96 72.2) (mid 183.172132 72.112132) (end 183.26 71.9) (width 0.196) (layer "In7.Cu") (net 258))
  (arc (start 185.36 72.804869) (mid 185.572132 72.717001) (end 185.66 72.504869) (width 0.196) (layer "In7.Cu") (net 258))
  (arc (start 184.16 72.804869) (mid 184.372132 72.717001) (end 184.46 72.504869) (width 0.196) (layer "In7.Cu") (net 258))
  (arc (start 185.96 71.595131) (mid 186.172132 71.682999) (end 186.26 71.895131) (width 0.196) (layer "In7.Cu") (net 258))
  (arc (start 183.26 71.895131) (mid 183.347868 71.682999) (end 183.56 71.595131) (width 0.196) (layer "In7.Cu") (net 258))
  (arc (start 183.56 71.595131) (mid 183.772132 71.682999) (end 183.86 71.895131) (width 0.196) (layer "In7.Cu") (net 258))
  (arc (start 185.66 71.895131) (mid 185.747868 71.682999) (end 185.96 71.595131) (width 0.196) (layer "In7.Cu") (net 258))
  (segment (start 176.136328 88.560008) (end 175.636328 89.060008) (width 0.127) (layer "F.Cu") (net 259))
  (segment (start 201.586328 55.060008) (end 201.586328 56.360008) (width 0.2) (layer "F.Cu") (net 259))
  (via (at 201.586328 56.360008) (size 0.5) (drill 0.2) (layers "F.Cu" "B.Cu") (net 259))
  (via (at 175.636328 89.060008) (size 0.5) (drill 0.2) (layers "F.Cu" "B.Cu") (net 259))
  (segment (start 190.2 66.4) (end 199.14 66.4) (width 0.196) (layer "In7.Cu") (net 259))
  (segment (start 176.4 85.95) (end 176.02 85.57) (width 0.127) (layer "In7.Cu") (net 259))
  (segment (start 177.43 69.77) (end 180.8 66.4) (width 0.196) (layer "In7.Cu") (net 259))
  (segment (start 175.636328 89.060008) (end 176.4 88.296336) (width 0.127) (layer "In7.Cu") (net 259))
  (segment (start 176.4 88.296336) (end 176.4 85.95) (width 0.127) (layer "In7.Cu") (net 259))
  (segment (start 177.2 75.3) (end 177.43 75.07) (width 0.2) (layer "In7.Cu") (net 259))
  (segment (start 188.95 66.15) (end 188.95 66.671904) (width 0.196) (layer "In7.Cu") (net 259))
  (segment (start 177.202828 81.747172) (end 177.202828 75.552828) (width 0.127) (layer "In7.Cu") (net 259))
  (segment (start 201.586328 63.983672) (end 201.586328 63.953672) (width 0.2) (layer "In7.Cu") (net 259))
  (segment (start 176.02 85.57) (end 176.02 82.93) (width 0.127) (layer "In7.Cu") (net 259))
  (segment (start 199.17 66.4) (end 201.586328 63.983672) (width 0.2) (layer "In7.Cu") (net 259))
  (segment (start 176.02 82.93) (end 177.202828 81.747172) (width 0.127) (layer "In7.Cu") (net 259))
  (segment (start 199.14 66.4) (end 199.17 66.4) (width 0.2) (layer "In7.Cu") (net 259))
  (segment (start 177.43 75.07) (end 177.43 69.77) (width 0.196) (layer "In7.Cu") (net 259))
  (segment (start 177.2 75.3) (end 177.2 75.55) (width 0.196) (layer "In7.Cu") (net 259))
  (segment (start 180.8 66.4) (end 188.2 66.4) (width 0.196) (layer "In7.Cu") (net 259))
  (segment (start 189.45 66.671904) (end 189.45 66.128096) (width 0.196) (layer "In7.Cu") (net 259))
  (segment (start 201.586328 63.953672) (end 201.586328 56.360008) (width 0.196) (layer "In7.Cu") (net 259))
  (segment (start 177.202828 75.552828) (end 177.2 75.55) (width 0.127) (layer "In7.Cu") (net 259))
  (segment (start 188.45 66.15) (end 188.45 66.128096) (width 0.196) (layer "In7.Cu") (net 259))
  (segment (start 189.95 66.128096) (end 189.95 66.15) (width 0.196) (layer "In7.Cu") (net 259))
  (segment (start 188.95 66.128096) (end 188.95 66.15) (width 0.196) (layer "In7.Cu") (net 259))
  (arc (start 189.45 66.128096) (mid 189.523223 65.951319) (end 189.7 65.878096) (width 0.196) (layer "In7.Cu") (net 259))
  (arc (start 188.45 66.128096) (mid 188.523223 65.951319) (end 188.7 65.878096) (width 0.196) (layer "In7.Cu") (net 259))
  (arc (start 188.2 66.4) (mid 188.376777 66.326777) (end 188.45 66.15) (width 0.196) (layer "In7.Cu") (net 259))
  (arc (start 189.95 66.15) (mid 190.023223 66.326777) (end 190.2 66.4) (width 0.196) (layer "In7.Cu") (net 259))
  (arc (start 188.7 65.878096) (mid 188.876777 65.951319) (end 188.95 66.128096) (width 0.196) (layer "In7.Cu") (net 259))
  (arc (start 188.95 66.671904) (mid 189.023223 66.848681) (end 189.2 66.921904) (width 0.196) (layer "In7.Cu") (net 259))
  (arc (start 189.7 65.878096) (mid 189.876777 65.951319) (end 189.95 66.128096) (width 0.196) (layer "In7.Cu") (net 259))
  (arc (start 189.2 66.921904) (mid 189.376777 66.848681) (end 189.45 66.671904) (width 0.196) (layer "In7.Cu") (net 259))
  (segment (start 199.886328 55.060008) (end 199.886328 56.360008) (width 0.2) (layer "F.Cu") (net 260))
  (segment (start 175.136328 88.560008) (end 174.636328 89.060008) (width 0.127) (layer "F.Cu") (net 260))
  (via (at 174.636328 89.060008) (size 0.5) (drill 0.2) (layers "F.Cu" "B.Cu") (net 260))
  (via (at 199.886328 56.360008) (size 0.5) (drill 0.2) (layers "F.Cu" "B.Cu") (net 260))
  (segment (start 175.15 86.25) (end 175.15 88.546336) (width 0.127) (layer "In7.Cu") (net 260))
  (segment (start 174.11 85.21) (end 175.15 86.25) (width 0.127) (layer "In7.Cu") (net 260))
  (segment (start 175.85 77.85) (end 175.85 81.233274) (width 0.127) (layer "In7.Cu") (net 260))
  (segment (start 174.11 82.973274) (end 174.11 85.21) (width 0.127) (layer "In7.Cu") (net 260))
  (segment (start 175.9 75.9) (end 176 76) (width 0.127) (layer "In7.Cu") (net 260))
  (segment (start 198.44 64) (end 199.886328 62.553672) (width 0.196) (layer "In7.Cu") (net 260))
  (segment (start 175.9 75.55) (end 175.9 75.9) (width 0.127) (layer "In7.Cu") (net 260))
  (segment (start 175.9 67.84) (end 179.74 64) (width 0.196) (layer "In7.Cu") (net 260))
  (segment (start 199.886328 62.553672) (end 199.886328 56.360008) (width 0.196) (layer "In7.Cu") (net 260))
  (segment (start 176 76) (end 176 77.7) (width 0.127) (layer "In7.Cu") (net 260))
  (segment (start 175.85 81.233274) (end 174.11 82.973274) (width 0.127) (layer "In7.Cu") (net 260))
  (segment (start 176 77.7) (end 175.85 77.85) (width 0.127) (layer "In7.Cu") (net 260))
  (segment (start 179.74 64) (end 198.44 64) (width 0.196) (layer "In7.Cu") (net 260))
  (segment (start 175.15 88.546336) (end 174.636328 89.060008) (width 0.127) (layer "In7.Cu") (net 260))
  (segment (start 175.9 75.55) (end 175.9 67.84) (width 0.196) (layer "In7.Cu") (net 260))
  (segment (start 196.486328 55.060008) (end 196.486328 56.360008) (width 0.2) (layer "F.Cu") (net 261))
  (segment (start 189.136328 82.560008) (end 188.636328 82.060008) (width 0.127) (layer "F.Cu") (net 261))
  (via (at 196.486328 56.360008) (size 0.5) (drill 0.2) (layers "F.Cu" "B.Cu") (net 261))
  (via blind (at 188.636328 82.060008) (size 0.5) (drill 0.2) (layers "F.Cu" "In2.Cu") (net 261))
  (segment (start 189.3 76.343188) (end 189.3 77.7) (width 0.1) (layer "In2.Cu") (net 261))
  (segment (start 190.2 75.55) (end 190.2 75.7) (width 0.1) (layer "In2.Cu") (net 261))
  (segment (start 195.520172 68.5) (end 196.279828 68.5) (width 0.16) (layer "In2.Cu") (net 261))
  (segment (start 190.2 75.7) (end 190 75.9) (width 0.1) (layer "In2.Cu") (net 261))
  (segment (start 196.279828 66) (end 196.175 66) (width 0.16) (layer "In2.Cu") (net 261))
  (segment (start 196.175 66) (end 195.520172 66) (width 0.16) (layer "In2.Cu") (net 261))
  (segment (start 189.743188 75.9) (end 189.3 76.343188) (width 0.1) (layer "In2.Cu") (net 261))
  (segment (start 195.520172 68) (end 196.279828 68) (width 0.16) (layer "In2.Cu") (net 261))
  (segment (start 196.186328 57.488672) (end 197.236328 57.488672) (width 0.16) (layer "In2.Cu") (net 261))
  (segment (start 194.03 72.97) (end 191.23 72.97) (width 0.16) (layer "In2.Cu") (net 261))
  (segment (start 196.486328 58.238672) (end 196.486328 58.463672) (width 0.16) (layer "In2.Cu") (net 261))
  (segment (start 197.236328 59.213672) (end 196.736328 59.213672) (width 0.16) (layer "In2.Cu") (net 261))
  (segment (start 195.570172 69.5) (end 195.675 69.5) (width 0.16) (layer "In2.Cu") (net 261))
  (segment (start 189.19 81.506336) (end 188.636328 82.060008) (width 0.1) (layer "In2.Cu") (net 261))
  (segment (start 196.736328 56.988672) (end 197.236328 56.988672) (width 0.16) (layer "In2.Cu") (net 261))
  (segment (start 195.570172 69) (end 196.279828 69) (width 0.16) (layer "In2.Cu") (net 261))
  (segment (start 195.520172 67) (end 196.279828 67) (width 0.16) (layer "In2.Cu") (net 261))
  (segment (start 196.486328 59.463672) (end 196.486328 59.513672) (width 0.16) (layer "In2.Cu") (net 261))
  (segment (start 189.3 77.7) (end 189.19 77.81) (width 0.1) (layer "In2.Cu") (net 261))
  (segment (start 195.520172 66.5) (end 196.279828 66.5) (width 0.16) (layer "In2.Cu") (net 261))
  (segment (start 190.2 74) (end 190.2 75.55) (width 0.16) (layer "In2.Cu") (net 261))
  (segment (start 195.520172 67.5) (end 196.279828 67.5) (width 0.16) (layer "In2.Cu") (net 261))
  (segment (start 195.925 69.75) (end 195.925 71.075) (width 0.16) (layer "In2.Cu") (net 261))
  (segment (start 196.486328 59.513672) (end 196.486328 59.813672) (width 0.16) (layer "In2.Cu") (net 261))
  (segment (start 196.186328 57.988672) (end 196.236328 57.988672) (width 0.16) (layer "In2.Cu") (net 261))
  (segment (start 190 75.9) (end 189.743188 75.9) (width 0.1) (layer "In2.Cu") (net 261))
  (segment (start 196.486328 59.813672) (end 195.925 60.375) (width 0.16) (layer "In2.Cu") (net 261))
  (segment (start 189.19 77.81) (end 189.19 81.506336) (width 0.1) (layer "In2.Cu") (net 261))
  (segment (start 195.925 71.075) (end 194.03 72.97) (width 0.16) (layer "In2.Cu") (net 261))
  (segment (start 196.175 65.5) (end 196.279828 65.5) (width 0.16) (layer "In2.Cu") (net 261))
  (segment (start 196.486328 56.360008) (end 196.486328 56.738672) (width 0.16) (layer "In2.Cu") (net 261))
  (segment (start 196.736328 58.713672) (end 197.236328 58.713672) (width 0.16) (layer "In2.Cu") (net 261))
  (segment (start 191.23 72.97) (end 190.2 74) (width 0.16) (layer "In2.Cu") (net 261))
  (segment (start 195.925 60.375) (end 195.925 65.25) (width 0.16) (layer "In2.Cu") (net 261))
  (arc (start 195.570172 69) (mid 195.393395 69.073223) (end 195.320172 69.25) (width 0.16) (layer "In2.Cu") (net 261))
  (arc (start 195.675 69.5) (mid 195.851777 69.573223) (end 195.925 69.75) (width 0.16) (layer "In2.Cu") (net 261))
  (arc (start 195.936328 57.738672) (mid 196.009551 57.915449) (end 196.186328 57.988672) (width 0.16) (layer "In2.Cu") (net 261))
  (arc (start 195.520172 67) (mid 195.343395 67.073223) (end 195.270172 67.25) (width 0.16) (layer "In2.Cu") (net 261))
  (arc (start 195.270172 67.25) (mid 195.343395 67.426777) (end 195.520172 67.5) (width 0.16) (layer "In2.Cu") (net 261))
  (arc (start 196.736328 59.213672) (mid 196.559551 59.286895) (end 196.486328 59.463672) (width 0.16) (layer "In2.Cu") (net 261))
  (arc (start 196.279828 67.5) (mid 196.456605 67.573223) (end 196.529828 67.75) (width 0.16) (layer "In2.Cu") (net 261))
  (arc (start 196.279828 68.5) (mid 196.456605 68.573223) (end 196.529828 68.75) (width 0.16) (layer "In2.Cu") (net 261))
  (arc (start 196.529828 65.75) (mid 196.456605 65.926777) (end 196.279828 66) (width 0.16) (layer "In2.Cu") (net 261))
  (arc (start 196.186328 57.488672) (mid 196.009551 57.561895) (end 195.936328 57.738672) (width 0.16) (layer "In2.Cu") (net 261))
  (arc (start 196.529828 67.75) (mid 196.456605 67.926777) (end 196.279828 68) (width 0.16) (layer "In2.Cu") (net 261))
  (arc (start 195.270172 66.25) (mid 195.343395 66.426777) (end 195.520172 66.5) (width 0.16) (layer "In2.Cu") (net 261))
  (arc (start 195.270172 68.25) (mid 195.343395 68.426777) (end 195.520172 68.5) (width 0.16) (layer "In2.Cu") (net 261))
  (arc (start 197.486328 58.963672) (mid 197.413105 59.140449) (end 197.236328 59.213672) (width 0.16) (layer "In2.Cu") (net 261))
  (arc (start 195.520172 66) (mid 195.343395 66.073223) (end 195.270172 66.25) (width 0.16) (layer "In2.Cu") (net 261))
  (arc (start 197.236328 58.713672) (mid 197.413105 58.786895) (end 197.486328 58.963672) (width 0.16) (layer "In2.Cu") (net 261))
  (arc (start 196.486328 56.738672) (mid 196.559551 56.915449) (end 196.736328 56.988672) (width 0.16) (layer "In2.Cu") (net 261))
  (arc (start 195.925 65.25) (mid 195.998223 65.426777) (end 196.175 65.5) (width 0.16) (layer "In2.Cu") (net 261))
  (arc (start 195.520172 68) (mid 195.343395 68.073223) (end 195.270172 68.25) (width 0.16) (layer "In2.Cu") (net 261))
  (arc (start 196.279828 66.5) (mid 196.456605 66.573223) (end 196.529828 66.75) (width 0.16) (layer "In2.Cu") (net 261))
  (arc (start 196.279828 65.5) (mid 196.456605 65.573223) (end 196.529828 65.75) (width 0.16) (layer "In2.Cu") (net 261))
  (arc (start 196.486328 58.463672) (mid 196.559551 58.640449) (end 196.736328 58.713672) (width 0.16) (layer "In2.Cu") (net 261))
  (arc (start 196.529828 68.75) (mid 196.456605 68.926777) (end 196.279828 69) (width 0.16) (layer "In2.Cu") (net 261))
  (arc (start 196.236328 57.988672) (mid 196.413105 58.061895) (end 196.486328 58.238672) (width 0.16) (layer "In2.Cu") (net 261))
  (arc (start 197.486328 57.238672) (mid 197.413105 57.415449) (end 197.236328 57.488672) (width 0.16) (layer "In2.Cu") (net 261))
  (arc (start 197.236328 56.988672) (mid 197.413105 57.061895) (end 197.486328 57.238672) (width 0.16) (layer "In2.Cu") (net 261))
  (arc (start 196.529828 66.75) (mid 196.456605 66.926777) (end 196.279828 67) (width 0.16) (layer "In2.Cu") (net 261))
  (arc (start 195.320172 69.25) (mid 195.393395 69.426777) (end 195.570172 69.5) (width 0.16) (layer "In2.Cu") (net 261))
  (segment (start 190 76.59) (end 190 76.52) (width 0.127) (layer "F.Cu") (net 262))
  (segment (start 198.186328 55.060008) (end 198.186328 56.360008) (width 0.2) (layer "F.Cu") (net 262))
  (segment (start 189.136328 77.453672) (end 190 76.59) (width 0.127) (layer "F.Cu") (net 262))
  (segment (start 189.136328 77.560008) (end 189.136328 77.453672) (width 0.127) (layer "F.Cu") (net 262))
  (via blind (at 198.186328 56.360008) (size 0.5) (drill 0.2) (layers "F.Cu" "In2.Cu") (net 262))
  (via blind (at 190 76.52) (size 0.5) (drill 0.2) (layers "F.Cu" "In2.Cu") (net 262))
  (segment (start 197.725 61.425) (end 197.725 62.125) (width 0.16) (layer "In2.Cu") (net 262))
  (segment (start 197.975 66.125) (end 198.33724 66.125) (width 0.16) (layer "In2.Cu") (net 262))
  (segment (start 190 76.52) (end 190.02 76.5) (width 0.1) (layer "In2.Cu") (net 262))
  (segment (start 197.46276 67.125) (end 198.33724 67.125) (width 0.16) (layer "In2.Cu") (net 262))
  (segment (start 198.186328 60.963672) (end 197.725 61.425) (width 0.16) (layer "In2.Cu") (net 262))
  (segment (start 197.85 63.025) (end 197.85 64.275) (width 0.16) (layer "In2.Cu") (net 262))
  (segment (start 197.46276 66.625) (end 198.33724 66.625) (width 0.16) (layer "In2.Cu") (net 262))
  (segment (start 197.46276 67.625) (end 198.33724 67.625) (width 0.16) (layer "In2.Cu") (net 262))
  (segment (start 199.111284 62.8) (end 198.075 62.8) (width 0.16) (layer "In2.Cu") (net 262))
  (segment (start 197.95 62.35) (end 199.111284 62.35) (width 0.16) (layer "In2.Cu") (net 262))
  (segment (start 198.475 65.1) (end 198 65.1) (width 0.16) (layer "In2.Cu") (net 262))
  (segment (start 197.725 68.375) (end 197.725 71.95) (width 0.16) (layer "In2.Cu") (net 262))
  (segment (start 197.386328 60.261328) (end 197.886328 60.261328) (width 0.16) (layer "In2.Cu") (net 262))
  (segment (start 190.7 76.5) (end 191.4 75.8) (width 0.1) (layer "In2.Cu") (net 262))
  (segment (start 197.725 71.95) (end 195 74.675) (width 0.16) (layer "In2.Cu") (net 262))
  (segment (start 191.4 75.8) (end 191.4 75.55) (width 0.1) (layer "In2.Cu") (net 262))
  (segment (start 191.4 75.11) (end 191.4 75.55) (width 0.16) (layer "In2.Cu") (net 262))
  (segment (start 191.835 74.675) (end 191.4 75.11) (width 0.16) (layer "In2.Cu") (net 262))
  (segment (start 198.125 64.55) (end 198.475 64.55) (width 0.16) (layer "In2.Cu") (net 262))
  (segment (start 198.186328 56.360008) (end 198.186328 58.761328) (width 0.16) (layer "In2.Cu") (net 262))
  (segment (start 190.02 76.5) (end 190.7 76.5) (width 0.1) (layer "In2.Cu") (net 262))
  (segment (start 195 74.675) (end 191.835 74.675) (width 0.16) (layer "In2.Cu") (net 262))
  (segment (start 197.725 65.375) (end 197.725 65.875) (width 0.16) (layer "In2.Cu") (net 262))
  (segment (start 197.46276 68.125) (end 197.475 68.125) (width 0.16) (layer "In2.Cu") (net 262))
  (segment (start 198.186328 60.561328) (end 198.186328 60.963672) (width 0.16) (layer "In2.Cu") (net 262))
  (segment (start 198.486328 59.061328) (end 198.986328 59.061328) (width 0.16) (layer "In2.Cu") (net 262))
  (segment (start 198.986328 59.661328) (end 197.386328 59.661328) (width 0.16) (layer "In2.Cu") (net 262))
  (arc (start 198 65.1) (mid 197.805546 65.180546) (end 197.725 65.375) (width 0.16) (layer "In2.Cu") (net 262))
  (arc (start 198.075 62.8) (mid 197.915901 62.865901) (end 197.85 63.025) (width 0.16) (layer "In2.Cu") (net 262))
  (arc (start 198.75 64.825) (mid 198.669454 65.019454) (end 198.475 65.1) (width 0.16) (layer "In2.Cu") (net 262))
  (arc (start 198.33724 66.125) (mid 198.514017 66.198223) (end 198.58724 66.375) (width 0.16) (layer "In2.Cu") (net 262))
  (arc (start 198.186328 58.761328) (mid 198.274196 58.97346) (end 198.486328 59.061328) (width 0.16) (layer "In2.Cu") (net 262))
  (arc (start 198.475 64.55) (mid 198.669454 64.630546) (end 198.75 64.825) (width 0.16) (layer "In2.Cu") (net 262))
  (arc (start 197.886328 60.261328) (mid 198.09846 60.349196) (end 198.186328 60.561328) (width 0.16) (layer "In2.Cu") (net 262))
  (arc (start 197.725 62.125) (mid 197.790901 62.284099) (end 197.95 62.35) (width 0.16) (layer "In2.Cu") (net 262))
  (arc (start 197.21276 66.875) (mid 197.285983 67.051777) (end 197.46276 67.125) (width 0.16) (layer "In2.Cu") (net 262))
  (arc (start 197.21276 67.875) (mid 197.285983 68.051777) (end 197.46276 68.125) (width 0.16) (layer "In2.Cu") (net 262))
  (arc (start 199.336284 62.575) (mid 199.270383 62.734099) (end 199.111284 62.8) (width 0.16) (layer "In2.Cu") (net 262))
  (arc (start 197.85 64.275) (mid 197.930546 64.469454) (end 198.125 64.55) (width 0.16) (layer "In2.Cu") (net 262))
  (arc (start 199.111284 62.35) (mid 199.270383 62.415901) (end 199.336284 62.575) (width 0.16) (layer "In2.Cu") (net 262))
  (arc (start 197.086328 59.961328) (mid 197.174196 60.17346) (end 197.386328 60.261328) (width 0.16) (layer "In2.Cu") (net 262))
  (arc (start 197.386328 59.661328) (mid 197.174196 59.749196) (end 197.086328 59.961328) (width 0.16) (layer "In2.Cu") (net 262))
  (arc (start 199.286328 59.361328) (mid 199.19846 59.57346) (end 198.986328 59.661328) (width 0.16) (layer "In2.Cu") (net 262))
  (arc (start 197.475 68.125) (mid 197.651777 68.198223) (end 197.725 68.375) (width 0.16) (layer "In2.Cu") (net 262))
  (arc (start 198.33724 67.125) (mid 198.514017 67.198223) (end 198.58724 67.375) (width 0.16) (layer "In2.Cu") (net 262))
  (arc (start 198.58724 67.375) (mid 198.514017 67.551777) (end 198.33724 67.625) (width 0.16) (layer "In2.Cu") (net 262))
  (arc (start 197.725 65.875) (mid 197.798223 66.051777) (end 197.975 66.125) (width 0.16) (layer "In2.Cu") (net 262))
  (arc (start 198.58724 66.375) (mid 198.514017 66.551777) (end 198.33724 66.625) (width 0.16) (layer "In2.Cu") (net 262))
  (arc (start 197.46276 66.625) (mid 197.285983 66.698223) (end 197.21276 66.875) (width 0.16) (layer "In2.Cu") (net 262))
  (arc (start 198.986328 59.061328) (mid 199.19846 59.149196) (end 199.286328 59.361328) (width 0.16) (layer "In2.Cu") (net 262))
  (arc (start 197.46276 67.625) (mid 197.285983 67.698223) (end 197.21276 67.875) (width 0.16) (layer "In2.Cu") (net 262))
  (segment (start 193.936328 55.060008) (end 193.936328 56.360008) (width 0.2) (layer "F.Cu") (net 263))
  (segment (start 188.136328 82.560008) (end 187.636328 82.060008) (width 0.127) (layer "F.Cu") (net 263))
  (via blind (at 187.636328 82.060008) (size 0.5) (drill 0.2) (layers "F.Cu" "In2.Cu") (net 263))
  (via blind (at 193.936328 56.360008) (size 0.5) (drill 0.2) (layers "F.Cu" "In2.Cu") (net 263))
  (segment (start 188.235836 81.4605) (end 188.235836 77.886038) (width 0.1) (layer "In2.Cu") (net 263))
  (segment (start 195.10738 62.776393) (end 194.489834 62.776393) (width 0.16) (layer "In2.Cu") (net 263))
  (segment (start 193.936328 59.636328) (end 194.025 59.725) (width 0.16) (layer "In2.Cu") (net 263))
  (segment (start 194.8 60.5) (end 194.8 61.2) (width 0.16) (layer "In2.Cu") (net 263))
  (segment (start 188.616038 77.505836) (end 188.945836 77.505836) (width 0.1) (layer "In2.Cu") (net 263))
  (segment (start 194.489834 64.126393) (end 195.10738 64.126393) (width 0.16) (layer "In2.Cu") (net 263))
  (segment (start 188.235836 77.886038) (end 188.616038 77.505836) (width 0.1) (layer "In2.Cu") (net 263))
  (segment (start 195.493775 59.316883) (end 195.493777 59.316884) (width 0.16) (layer "In2.Cu") (net 263))
  (segment (start 194.386328 57.286328) (end 194.386328 57.336328) (width 0.16) (layer "In2.Cu") (net 263))
  (segment (start 195.493775 58.963329) (end 195.493776 58.96333) (width 0.16) (layer "In2.Cu") (net 263))
  (segment (start 189.075836 76.725836) (end 189 76.65) (width 0.1) (layer "In2.Cu") (net 263))
  (segment (start 195.10738 65.476393) (end 195.023607 65.476393) (width 0.16) (layer "In2.Cu") (net 263))
  (segment (start 194.975 70.625) (end 193.25 72.35) (width 0.16) (layer "In2.Cu") (net 263))
  (segment (start 189 76.65) (end 189 76.3) (width 0.1) (layer "In2.Cu") (net 263))
  (segment (start 194.386328 58.286328) (end 194.386328 58.336328) (width 0.16) (layer "In2.Cu") (net 263))
  (segment (start 188.945836 77.505836) (end 189.075836 77.375836) (width 0.1) (layer "In2.Cu") (net 263))
  (segment (start 195.10738 61.876393) (end 194.489834 61.876393) (width 0.16) (layer "In2.Cu") (net 263))
  (segment (start 193.936328 56.360008) (end 193.936328 56.836328) (width 0.16) (layer "In2.Cu") (net 263))
  (segment (start 193.486328 58.786328) (end 193.486328 58.836328) (width 0.16) (layer "In2.Cu") (net 263))
  (segment (start 194.732106 60.432106) (end 194.8 60.5) (width 0.16) (layer "In2.Cu") (net 263))
  (segment (start 194.975 69.125) (end 194.975 70.625) (width 0.16) (layer "In2.Cu") (net 263))
  (segment (start 194.378554 59.725001) (end 195.140222 58.96333) (width 0.16) (layer "In2.Cu") (net 263))
  (segment (start 195.10738 63.676393) (end 194.489834 63.676393) (width 0.16) (layer "In2.Cu") (net 263))
  (segment (start 187.636328 82.060008) (end 188.235836 81.4605) (width 0.1) (layer "In2.Cu") (net 263))
  (segment (start 189.075836 77.375836) (end 189.075836 76.725836) (width 0.1) (layer "In2.Cu") (net 263))
  (segment (start 189.6 73.3) (end 189.6 75.55) (width 0.16) (layer "In2.Cu") (net 263))
  (segment (start 194.161328 58.561328) (end 193.711328 58.561328) (width 0.16) (layer "In2.Cu") (net 263))
  (segment (start 194.378553 59.724999) (end 194.378554 59.725001) (width 0.16) (layer "In2.Cu") (net 263))
  (segment (start 194.798607 65.701393) (end 194.798607 68.948607) (width 0.16) (layer "In2.Cu") (net 263))
  (segment (start 191.8 72.35) (end 191.5 72.05) (width 0.16) (layer "In2.Cu") (net 263))
  (segment (start 194.161328 57.561328) (end 193.711328 57.561328) (width 0.16) (layer "In2.Cu") (net 263))
  (segment (start 189.6 75.7) (end 189.6 75.55) (width 0.1) (layer "In2.Cu") (net 263))
  (segment (start 195.10738 64.576393) (end 194.489834 64.576393) (width 0.16) (layer "In2.Cu") (net 263))
  (segment (start 195.023607 61.426393) (end 195.10738 61.426393) (width 0.16) (layer "In2.Cu") (net 263))
  (segment (start 191.5 72.05) (end 190.85 72.05) (width 0.16) (layer "In2.Cu") (net 263))
  (segment (start 193.711328 58.061328) (end 194.161328 58.061328) (width 0.16) (layer "In2.Cu") (net 263))
  (segment (start 194.798607 68.948607) (end 194.975 69.125) (width 0.16) (layer "In2.Cu") (net 263))
  (segment (start 194.489834 63.226393) (end 195.10738 63.226393) (width 0.16) (layer "In2.Cu") (net 263))
  (segment (start 195.493777 59.316884) (end 194.732106 60.078552) (width 0.16) (layer "In2.Cu") (net 263))
  (segment (start 190.85 72.05) (end 189.6 73.3) (width 0.16) (layer "In2.Cu") (net 263))
  (segment (start 193.25 72.35) (end 191.8 72.35) (width 0.16) (layer "In2.Cu") (net 263))
  (segment (start 194.489834 65.026393) (end 195.10738 65.026393) (width 0.16) (layer "In2.Cu") (net 263))
  (segment (start 194.489834 62.326393) (end 195.10738 62.326393) (width 0.16) (layer "In2.Cu") (net 263))
  (segment (start 193.486328 57.786328) (end 193.486328 57.836328) (width 0.16) (layer "In2.Cu") (net 263))
  (segment (start 193.936328 59.286328) (end 193.936328 59.636328) (width 0.16) (layer "In2.Cu") (net 263))
  (segment (start 189 76.3) (end 189.6 75.7) (width 0.1) (layer "In2.Cu") (net 263))
  (segment (start 194.732105 60.432105) (end 194.732106 60.432106) (width 0.16) (layer "In2.Cu") (net 263))
  (segment (start 194.8 61.2) (end 194.798607 61.201393) (width 0.16) (layer "In2.Cu") (net 263))
  (arc (start 193.711328 58.561328) (mid 193.552229 58.627229) (end 193.486328 58.786328) (width 0.16) (layer "In2.Cu") (net 263))
  (arc (start 195.10738 62.326393) (mid 195.266479 62.392294) (end 195.33238 62.551393) (width 0.16) (layer "In2.Cu") (net 263))
  (arc (start 194.264834 63.901393) (mid 194.330735 64.060492) (end 194.489834 64.126393) (width 0.16) (layer "In2.Cu") (net 263))
  (arc (start 194.264834 64.801393) (mid 194.330735 64.960492) (end 194.489834 65.026393) (width 0.16) (layer "In2.Cu") (net 263))
  (arc (start 195.33238 61.651393) (mid 195.266479 61.810492) (end 195.10738 61.876393) (width 0.16) (layer "In2.Cu") (net 263))
  (arc (start 194.264834 63.001393) (mid 194.330735 63.160492) (end 194.489834 63.226393) (width 0.16) (layer "In2.Cu") (net 263))
  (arc (start 194.264834 62.101393) (mid 194.330735 62.260492) (end 194.489834 62.326393) (width 0.16) (layer "In2.Cu") (net 263))
  (arc (start 194.386328 57.336328) (mid 194.320427 57.495427) (end 194.161328 57.561328) (width 0.16) (layer "In2.Cu") (net 263))
  (arc (start 193.711328 57.561328) (mid 193.552229 57.627229) (end 193.486328 57.786328) (width 0.16) (layer "In2.Cu") (net 263))
  (arc (start 195.140222 58.96333) (mid 195.316998 58.890106) (end 195.493775 58.963329) (width 0.16) (layer "In2.Cu") (net 263))
  (arc (start 195.023607 65.476393) (mid 194.864508 65.542294) (end 194.798607 65.701393) (width 0.16) (layer "In2.Cu") (net 263))
  (arc (start 195.10738 65.026393) (mid 195.266479 65.092294) (end 195.33238 65.251393) (width 0.16) (layer "In2.Cu") (net 263))
  (arc (start 195.10738 63.226393) (mid 195.266479 63.292294) (end 195.33238 63.451393) (width 0.16) (layer "In2.Cu") (net 263))
  (arc (start 195.33238 63.451393) (mid 195.266479 63.610492) (end 195.10738 63.676393) (width 0.16) (layer "In2.Cu") (net 263))
  (arc (start 195.33238 62.551393) (mid 195.266479 62.710492) (end 195.10738 62.776393) (width 0.16) (layer "In2.Cu") (net 263))
  (arc (start 194.489834 64.576393) (mid 194.330735 64.642294) (end 194.264834 64.801393) (width 0.16) (layer "In2.Cu") (net 263))
  (arc (start 195.493776 58.96333) (mid 195.566999 59.140107) (end 195.493775 59.316883) (width 0.16) (layer "In2.Cu") (net 263))
  (arc (start 194.025 59.725) (mid 194.201777 59.798223) (end 194.378553 59.724999) (width 0.16) (layer "In2.Cu") (net 263))
  (arc (start 194.798607 61.201393) (mid 194.864508 61.360492) (end 195.023607 61.426393) (width 0.16) (layer "In2.Cu") (net 263))
  (arc (start 194.489834 63.676393) (mid 194.330735 63.742294) (end 194.264834 63.901393) (width 0.16) (layer "In2.Cu") (net 263))
  (arc (start 195.33238 65.251393) (mid 195.266479 65.410492) (end 195.10738 65.476393) (width 0.16) (layer "In2.Cu") (net 263))
  (arc (start 194.732106 60.078552) (mid 194.658882 60.255328) (end 194.732105 60.432105) (width 0.16) (layer "In2.Cu") (net 263))
  (arc (start 195.33238 64.351393) (mid 195.266479 64.510492) (end 195.10738 64.576393) (width 0.16) (layer "In2.Cu") (net 263))
  (arc (start 193.486328 58.836328) (mid 193.552229 58.995427) (end 193.711328 59.061328) (width 0.16) (layer "In2.Cu") (net 263))
  (arc (start 195.10738 64.126393) (mid 195.266479 64.192294) (end 195.33238 64.351393) (width 0.16) (layer "In2.Cu") (net 263))
  (arc (start 195.10738 61.426393) (mid 195.266479 61.492294) (end 195.33238 61.651393) (width 0.16) (layer "In2.Cu") (net 263))
  (arc (start 194.489834 62.776393) (mid 194.330735 62.842294) (end 194.264834 63.001393) (width 0.16) (layer "In2.Cu") (net 263))
  (arc (start 194.161328 58.061328) (mid 194.320427 58.127229) (end 194.386328 58.286328) (width 0.16) (layer "In2.Cu") (net 263))
  (arc (start 193.936328 56.836328) (mid 194.002229 56.995427) (end 194.161328 57.061328) (width 0.16) (layer "In2.Cu") (net 263))
  (arc (start 193.711328 59.061328) (mid 193.870427 59.127229) (end 193.936328 59.286328) (width 0.16) (layer "In2.Cu") (net 263))
  (arc (start 194.489834 61.876393) (mid 194.330735 61.942294) (end 194.264834 62.101393) (width 0.16) (layer "In2.Cu") (net 263))
  (arc (start 194.161328 57.061328) (mid 194.320427 57.127229) (end 194.386328 57.286328) (width 0.16) (layer "In2.Cu") (net 263))
  (arc (start 194.386328 58.336328) (mid 194.320427 58.495427) (end 194.161328 58.561328) (width 0.16) (layer "In2.Cu") (net 263))
  (arc (start 193.486328 57.836328) (mid 193.552229 57.995427) (end 193.711328 58.061328) (width 0.16) (layer "In2.Cu") (net 263))
  (segment (start 194.786328 55.060008) (end 194.786328 56.360008) (width 0.2) (layer "F.Cu") (net 264))
  (segment (start 189.136328 83.560008) (end 189.636328 83.060008) (width 0.127) (layer "F.Cu") (net 264))
  (segment (start 189.636328 83.060008) (end 189.655836 83.060008) (width 0.127) (layer "F.Cu") (net 264))
  (via blind (at 189.655836 83.060008) (size 0.5) (drill 0.2) (layers "F.Cu" "In5.Cu") (net 264))
  (via blind (at 194.786328 56.360008) (size 0.5) (drill 0.2) (layers "F.Cu" "In5.Cu") (net 264))
  (segment (start 191.195403 62.168199) (end 191.831802 62.804597) (width 0.146) (layer "In5.Cu") (net 264))
  (segment (start 188.220568 81.635568) (end 189.645008 83.060008) (width 0.09) (layer "In5.Cu") (net 264))
  (segment (start 188.649819 64.713783) (end 189.286217 65.350181) (width 0.146) (layer "In5.Cu") (net 264))
  (segment (start 190.346875 63.016727) (end 190.983273 63.653125) (width 0.146) (layer "In5.Cu") (net 264))
  (segment (start 188.331621 65.244113) (end 188.225555 65.138047) (width 0.146) (layer "In5.Cu") (net 264))
  (segment (start 188.220568 76.887731) (end 188.220568 81.635568) (width 0.09) (layer "In5.Cu") (net 264))
  (segment (start 193.908802 59.338946) (end 193.908802 59.338945) (width 0.146) (layer "In5.Cu") (net 264))
  (segment (start 192.256066 62.804597) (end 192.256065 62.804598) (width 0.146) (layer "In5.Cu") (net 264))
  (segment (start 192.15 61.85) (end 192.8 61.2) (width 0.146) (layer "In5.Cu") (net 264))
  (segment (start 190.771139 62.592463) (end 191.407537 63.228861) (width 0.146) (layer "In5.Cu") (net 264))
  (segment (start 194.236789 60.515464) (end 193.484536 59.76321) (width 0.146) (layer "In5.Cu") (net 264))
  (segment (start 188.220568 76.887731) (end 187.97 76.637163) (width 0.09) (layer "In5.Cu") (net 264))
  (segment (start 193.908802 59.338945) (end 194.072798 59.502941) (width 0.146) (layer "In5.Cu") (net 264))
  (segment (start 187.97 75.56) (end 187.97 66.03) (width 0.146) (layer "In5.Cu") (net 264))
  (segment (start 193.060271 60.187476) (end 193.812525 60.939729) (width 0.146) (layer "In5.Cu") (net 264))
  (segment (start 187.97 76.637163) (end 187.97 75.56) (width 0.09) (layer "In5.Cu") (net 264))
  (segment (start 192.149999 62.274266) (end 192.15 62.274266) (width 0.146) (layer "In5.Cu") (net 264))
  (segment (start 189.645008 83.060008) (end 189.655836 83.060008) (width 0.09) (layer "In5.Cu") (net 264))
  (segment (start 189.922611 63.440991) (end 190.559009 64.077389) (width 0.146) (layer "In5.Cu") (net 264))
  (segment (start 193.060271 60.187477) (end 193.060271 60.187476) (width 0.146) (layer "In5.Cu") (net 264))
  (segment (start 192.8 60.775736) (end 192.636005 60.611741) (width 0.146) (layer "In5.Cu") (net 264))
  (segment (start 192.256066 62.380333) (end 192.149999 62.274266) (width 0.146) (layer "In5.Cu") (net 264))
  (segment (start 194.497062 59.502941) (end 194.786328 59.213672) (width 0.146) (layer "In5.Cu") (net 264))
  (segment (start 189.498347 63.865255) (end 190.134745 64.501653) (width 0.146) (layer "In5.Cu") (net 264))
  (segment (start 189.074083 64.289519) (end 189.710481 64.925917) (width 0.146) (layer "In5.Cu") (net 264))
  (segment (start 194.786328 59.213672) (end 194.786328 56.360008) (width 0.146) (layer "In5.Cu") (net 264))
  (segment (start 194.236789 60.515463) (end 194.236789 60.515464) (width 0.146) (layer "In5.Cu") (net 264))
  (segment (start 187.97 66.03) (end 188.33162 65.668378) (width 0.146) (layer "In5.Cu") (net 264))
  (arc (start 189.286217 65.350181) (mid 189.498349 65.438049) (end 189.710481 65.350181) (width 0.146) (layer "In5.Cu") (net 264))
  (arc (start 193.484536 59.338946) (mid 193.69667 59.251077) (end 193.908802 59.338946) (width 0.146) (layer "In5.Cu") (net 264))
  (arc (start 190.771139 62.168199) (mid 190.983271 62.080331) (end 191.195403 62.168199) (width 0.146) (layer "In5.Cu") (net 264))
  (arc (start 189.710481 65.350181) (mid 189.798349 65.138049) (end 189.710481 64.925917) (width 0.146) (layer "In5.Cu") (net 264))
  (arc (start 188.225555 64.713783) (mid 188.437687 64.625915) (end 188.649819 64.713783) (width 0.146) (layer "In5.Cu") (net 264))
  (arc (start 189.922611 63.440991) (mid 189.834743 63.228859) (end 189.922611 63.016727) (width 0.146) (layer "In5.Cu") (net 264))
  (arc (start 194.236789 60.939729) (mid 194.324657 60.727596) (end 194.236789 60.515463) (width 0.146) (layer "In5.Cu") (net 264))
  (arc (start 189.074083 63.865255) (mid 189.286215 63.777387) (end 189.498347 63.865255) (width 0.146) (layer "In5.Cu") (net 264))
  (arc (start 189.922611 63.016727) (mid 190.134743 62.928859) (end 190.346875 63.016727) (width 0.146) (layer "In5.Cu") (net 264))
  (arc (start 190.559009 64.501653) (mid 190.646877 64.289521) (end 190.559009 64.077389) (width 0.146) (layer "In5.Cu") (net 264))
  (arc (start 192.8 61.2) (mid 192.887868 60.987868) (end 192.8 60.775736) (width 0.146) (layer "In5.Cu") (net 264))
  (arc (start 190.983273 63.653125) (mid 191.195405 63.740993) (end 191.407537 63.653125) (width 0.146) (layer "In5.Cu") (net 264))
  (arc (start 189.074083 64.289519) (mid 188.986215 64.077387) (end 189.074083 63.865255) (width 0.146) (layer "In5.Cu") (net 264))
  (arc (start 192.636005 60.187477) (mid 192.848139 60.099608) (end 193.060271 60.187477) (width 0.146) (layer "In5.Cu") (net 264))
  (arc (start 192.256065 62.804598) (mid 192.343935 62.592465) (end 192.256066 62.380333) (width 0.146) (layer "In5.Cu") (net 264))
  (arc (start 190.771139 62.592463) (mid 190.683271 62.380331) (end 190.771139 62.168199) (width 0.146) (layer "In5.Cu") (net 264))
  (arc (start 193.484536 59.76321) (mid 193.396668 59.551078) (end 193.484536 59.338946) (width 0.146) (layer "In5.Cu") (net 264))
  (arc (start 191.407537 63.653125) (mid 191.495405 63.440993) (end 191.407537 63.228861) (width 0.146) (layer "In5.Cu") (net 264))
  (arc (start 192.15 62.274266) (mid 192.062131 62.062134) (end 192.15 61.85) (width 0.146) (layer "In5.Cu") (net 264))
  (arc (start 191.831802 62.804597) (mid 192.043934 62.892465) (end 192.256066 62.804597) (width 0.146) (layer "In5.Cu") (net 264))
  (arc (start 192.636005 60.611741) (mid 192.548137 60.399609) (end 192.636005 60.187477) (width 0.146) (layer "In5.Cu") (net 264))
  (arc (start 190.134745 64.501653) (mid 190.346877 64.589521) (end 190.559009 64.501653) (width 0.146) (layer "In5.Cu") (net 264))
  (arc (start 188.225555 65.138047) (mid 188.137687 64.925915) (end 188.225555 64.713783) (width 0.146) (layer "In5.Cu") (net 264))
  (arc (start 188.33162 65.668378) (mid 188.419489 65.456246) (end 188.331621 65.244113) (width 0.146) (layer "In5.Cu") (net 264))
  (arc (start 194.072798 59.502941) (mid 194.28493 59.590809) (end 194.497062 59.502941) (width 0.146) (layer "In5.Cu") (net 264))
  (arc (start 193.812525 60.939729) (mid 194.024657 61.027597) (end 194.236789 60.939729) (width 0.146) (layer "In5.Cu") (net 264))
  (segment (start 190.136328 80.560008) (end 190.636328 80.060008) (width 0.127) (layer "F.Cu") (net 265))
  (segment (start 190.636328 80.060008) (end 190.655836 80.060008) (width 0.127) (layer "F.Cu") (net 265))
  (segment (start 192.236328 55.060008) (end 192.236328 56.360008) (width 0.2) (layer "F.Cu") (net 265))
  (via (at 192.236328 56.360008) (size 0.5) (drill 0.2) (layers "F.Cu" "B.Cu") (net 265))
  (via (at 190.655836 80.060008) (size 0.5) (drill 0.2) (layers "F.Cu" "B.Cu") (net 265))
  (segment (start 197.891554 74.436958) (end 197.891554 74.436957) (width 0.16) (layer "In9.Cu") (net 265))
  (segment (start 197.05 76.35) (end 197.5 75.9) (width 0.1) (layer "In9.Cu") (net 265))
  (segment (start 198.89944 74.808444) (end 198.89944 74.808445) (width 0.16) (layer "In9.Cu") (net 265))
  (segment (start 197.5 75.5) (end 197.5 75.2) (width 0.16) (layer "In9.Cu") (net 265))
  (segment (start 199.535839 74.172045) (end 199.535839 74.172046) (width 0.16) (layer "In9.Cu") (net 265))
  (segment (start 190.655836 79.654164) (end 190.655836 80.060008) (width 0.1) (layer "In9.Cu") (net 265))
  (segment (start 192.236328 58.736328) (end 192.236328 56.360008) (width 0.16) (layer "In9.Cu") (net 265))
  (segment (start 199.9 72.8) (end 199.9 64.05) (width 0.16) (layer "In9.Cu") (net 265))
  (segment (start 199.509197 73.190806) (end 199.9 72.8) (width 0.16) (layer "In9.Cu") (net 265))
  (segment (start 196.65 76.35) (end 197.05 76.35) (width 0.1) (layer "In9.Cu") (net 265))
  (segment (start 197.5 75.9) (end 197.5 75.5) (width 0.1) (layer "In9.Cu") (net 265))
  (segment (start 193.09 59.59) (end 192.236328 58.736328) (width 0.16) (layer "In9.Cu") (net 265))
  (segment (start 194.095 78.905) (end 191.405 78.905) (width 0.1) (layer "In9.Cu") (net 265))
  (segment (start 199.535839 74.172046) (end 198.846152 73.482358) (width 0.16) (layer "In9.Cu") (net 265))
  (segment (start 196.65 76.35) (end 194.095 78.905) (width 0.1) (layer "In9.Cu") (net 265))
  (segment (start 199.164352 73.16416) (end 199.164352 73.164159) (width 0.16) (layer "In9.Cu") (net 265))
  (segment (start 198.527953 73.800559) (end 198.527953 73.800558) (width 0.16) (layer "In9.Cu") (net 265))
  (segment (start 197.891554 74.436957) (end 198.581242 75.126644) (width 0.16) (layer "In9.Cu") (net 265))
  (segment (start 199.164352 73.164159) (end 199.190999 73.190806) (width 0.16) (layer "In9.Cu") (net 265))
  (segment (start 199.9 64.05) (end 195.44 59.59) (width 0.16) (layer "In9.Cu") (net 265))
  (segment (start 197.6 74.781802) (end 197.573354 74.755156) (width 0.16) (layer "In9.Cu") (net 265))
  (segment (start 191.405 78.905) (end 190.655836 79.654164) (width 0.1) (layer "In9.Cu") (net 265))
  (segment (start 198.89944 74.808445) (end 198.209753 74.118757) (width 0.16) (layer "In9.Cu") (net 265))
  (segment (start 195.44 59.59) (end 193.09 59.59) (width 0.16) (layer "In9.Cu") (net 265))
  (segment (start 197.5 75.2) (end 197.6 75.1) (width 0.16) (layer "In9.Cu") (net 265))
  (segment (start 198.527953 73.800558) (end 199.217641 74.490245) (width 0.16) (layer "In9.Cu") (net 265))
  (arc (start 198.581242 75.126644) (mid 198.740341 75.192545) (end 198.89944 75.126644) (width 0.16) (layer "In9.Cu") (net 265))
  (arc (start 197.573354 74.755156) (mid 197.507453 74.596057) (end 197.573354 74.436958) (width 0.16) (layer "In9.Cu") (net 265))
  (arc (start 199.217641 74.490245) (mid 199.37674 74.556146) (end 199.535839 74.490245) (width 0.16) (layer "In9.Cu") (net 265))
  (arc (start 198.846152 73.482358) (mid 198.780251 73.323259) (end 198.846152 73.16416) (width 0.16) (layer "In9.Cu") (net 265))
  (arc (start 197.6 75.1) (mid 197.665901 74.940901) (end 197.6 74.781802) (width 0.16) (layer "In9.Cu") (net 265))
  (arc (start 198.846152 73.16416) (mid 199.005253 73.098258) (end 199.164352 73.16416) (width 0.16) (layer "In9.Cu") (net 265))
  (arc (start 199.190999 73.190806) (mid 199.350098 73.256707) (end 199.509197 73.190806) (width 0.16) (layer "In9.Cu") (net 265))
  (arc (start 197.573354 74.436958) (mid 197.732455 74.371056) (end 197.891554 74.436958) (width 0.16) (layer "In9.Cu") (net 265))
  (arc (start 199.535839 74.490245) (mid 199.60174 74.331145) (end 199.535839 74.172045) (width 0.16) (layer "In9.Cu") (net 265))
  (arc (start 198.209753 73.800559) (mid 198.368854 73.734657) (end 198.527953 73.800559) (width 0.16) (layer "In9.Cu") (net 265))
  (arc (start 198.209753 74.118757) (mid 198.143852 73.959658) (end 198.209753 73.800559) (width 0.16) (layer "In9.Cu") (net 265))
  (arc (start 198.89944 75.126644) (mid 198.965341 74.967544) (end 198.89944 74.808444) (width 0.16) (layer "In9.Cu") (net 265))
  (segment (start 191.386328 55.060008) (end 191.386328 56.360008) (width 0.2) (layer "F.Cu") (net 266))
  (segment (start 190.136328 78.560008) (end 190.636328 78.060008) (width 0.127) (layer "F.Cu") (net 266))
  (segment (start 190.636328 78.060008) (end 190.655836 78.060008) (width 0.127) (layer "F.Cu") (net 266))
  (via (at 190.655836 78.060008) (size 0.5) (drill 0.2) (layers "F.Cu" "B.Cu") (net 266))
  (via (at 191.386328 56.360008) (size 0.5) (drill 0.2) (layers "F.Cu" "B.Cu") (net 266))
  (segment (start 197.096019 72.95043) (end 197.096017 72.950431) (width 0.16) (layer "In9.Cu") (net 266))
  (segment (start 197.9 66.35) (end 197.9 65) (width 0.16) (layer "In9.Cu") (net 266))
  (segment (start 196.60104 74.152511) (end 196.60104 74.152512) (width 0.16) (layer "In9.Cu") (net 266))
  (segment (start 197.732412 73.303984) (end 197.732412 73.303983) (width 0.16) (layer "In9.Cu") (net 266))
  (segment (start 193.55 77.35) (end 192.6 78.3) (width 0.1) (layer "In9.Cu") (net 266))
  (segment (start 197.096017 72.950431) (end 197.449569 73.303983) (width 0.16) (layer "In9.Cu") (net 266))
  (segment (start 197.732412 73.021139) (end 197.732412 73.02114) (width 0.16) (layer "In9.Cu") (net 266))
  (segment (start 191.361421 78.3) (end 191.161421 78.1) (width 0.1) (layer "In9.Cu") (net 266))
  (segment (start 197.166726 73.586826) (end 196.813174 73.233274) (width 0.16) (layer "In9.Cu") (net 266))
  (segment (start 196.813173 72.950431) (end 196.813175 72.95043) (width 0.16) (layer "In9.Cu") (net 266))
  (segment (start 197.606323 67.925) (end 198.193677 67.925) (width 0.16) (layer "In9.Cu") (net 266))
  (segment (start 191.4 56.37368) (end 191.386328 56.360008) (width 0.16) (layer "In9.Cu") (net 266))
  (segment (start 198.193677 66.575) (end 198.125 66.575) (width 0.16) (layer "In9.Cu") (net 266))
  (segment (start 197.166726 73.586825) (end 197.166726 73.586826) (width 0.16) (layer "In9.Cu") (net 266))
  (segment (start 198.193677 67.475) (end 197.606323 67.475) (width 0.16) (layer "In9.Cu") (net 266))
  (segment (start 197.166726 73.86967) (end 197.166726 73.869669) (width 0.16) (layer "In9.Cu") (net 266))
  (segment (start 196.282842 74.4) (end 196.318197 74.435355) (width 0.16) (layer "In9.Cu") (net 266))
  (segment (start 191.186328 61.203672) (end 191.186328 60.488672) (width 0.16) (layer "In9.Cu") (net 266))
  (segment (start 195.98 75.54) (end 195.98 74.42) (width 0.16) (layer "In9.Cu") (net 266))
  (segment (start 195.98 75.72) (end 194.35 77.35) (width 0.1) (layer "In9.Cu") (net 266))
  (segment (start 196.530333 73.516116) (end 196.530331 73.516117) (width 0.16) (layer "In9.Cu") (net 266))
  (segment (start 194.4 61.5) (end 191.482656 61.5) (width 0.16) (layer "In9.Cu") (net 266))
  (segment (start 191.161421 78.1) (end 190.695828 78.1) (width 0.1) (layer "In9.Cu") (net 266))
  (segment (start 197.732412 73.02114) (end 197.697056 72.985784) (width 0.16) (layer "In9.Cu") (net 266))
  (segment (start 197.606323 67.025) (end 198.193677 67.025) (width 0.16) (layer "In9.Cu") (net 266))
  (segment (start 191.186328 60.488672) (end 191.4 60.275) (width 0.16) (layer "In9.Cu") (net 266))
  (segment (start 192.6 78.3) (end 191.361421 78.3) (width 0.1) (layer "In9.Cu") (net 266))
  (segment (start 196.60104 74.152512) (end 196.247488 73.79896) (width 0.16) (layer "In9.Cu") (net 266))
  (segment (start 191.482656 61.5) (end 191.186328 61.203672) (width 0.16) (layer "In9.Cu") (net 266))
  (segment (start 196.247487 73.516117) (end 196.247489 73.516116) (width 0.16) (layer "In9.Cu") (net 266))
  (segment (start 195.98 74.42) (end 196 74.4) (width 0.16) (layer "In9.Cu") (net 266))
  (segment (start 197.675 68.375) (end 197.606323 68.375) (width 0.16) (layer "In9.Cu") (net 266))
  (segment (start 197.9 65) (end 194.4 61.5) (width 0.16) (layer "In9.Cu") (net 266))
  (segment (start 191.4 60.275) (end 191.4 56.37368) (width 0.16) (layer "In9.Cu") (net 266))
  (segment (start 195.98 75.54) (end 195.98 75.72) (width 0.1) (layer "In9.Cu") (net 266))
  (segment (start 196.530331 73.516117) (end 196.883883 73.869669) (width 0.16) (layer "In9.Cu") (net 266))
  (segment (start 196.60104 74.435354) (end 196.60104 74.435355) (width 0.16) (layer "In9.Cu") (net 266))
  (segment (start 197.9 72.5) (end 197.9 68.6) (width 0.16) (layer "In9.Cu") (net 266))
  (segment (start 194.35 77.35) (end 193.55 77.35) (width 0.1) (layer "In9.Cu") (net 266))
  (segment (start 197.697057 72.702941) (end 197.9 72.5) (width 0.16) (layer "In9.Cu") (net 266))
  (segment (start 190.695828 78.1) (end 190.655836 78.060008) (width 0.1) (layer "In9.Cu") (net 266))
  (arc (start 196.883883 73.869669) (mid 197.025304 73.928248) (end 197.166726 73.86967) (width 0.16) (layer "In9.Cu") (net 266))
  (arc (start 196.318197 74.435355) (mid 196.459619 74.493933) (end 196.60104 74.435354) (width 0.16) (layer "In9.Cu") (net 266))
  (arc (start 196 74.4) (mid 196.141421 74.341422) (end 196.282842 74.4) (width 0.16) (layer "In9.Cu") (net 266))
  (arc (start 198.193677 67.925) (mid 198.352776 67.859099) (end 198.418677 67.7) (width 0.16) (layer "In9.Cu") (net 266))
  (arc (start 197.606323 68.375) (mid 197.447224 68.309099) (end 197.381323 68.15) (width 0.16) (layer "In9.Cu") (net 266))
  (arc (start 198.418677 67.7) (mid 198.352776 67.540901) (end 198.193677 67.475) (width 0.16) (layer "In9.Cu") (net 266))
  (arc (start 196.60104 74.435355) (mid 196.659619 74.293933) (end 196.60104 74.152511) (width 0.16) (layer "In9.Cu") (net 266))
  (arc (start 197.697056 72.985784) (mid 197.638478 72.844362) (end 197.697057 72.702941) (width 0.16) (layer "In9.Cu") (net 266))
  (arc (start 197.606323 67.475) (mid 197.447224 67.409099) (end 197.381323 67.25) (width 0.16) (layer "In9.Cu") (net 266))
  (arc (start 197.9 68.6) (mid 197.834099 68.440901) (end 197.675 68.375) (width 0.16) (layer "In9.Cu") (net 266))
  (arc (start 196.247488 73.79896) (mid 196.188909 73.657539) (end 196.247487 73.516117) (width 0.16) (layer "In9.Cu") (net 266))
  (arc (start 196.813175 72.95043) (mid 196.954596 72.891852) (end 197.096019 72.95043) (width 0.16) (layer "In9.Cu") (net 266))
  (arc (start 198.125 66.575) (mid 197.965901 66.509099) (end 197.9 66.35) (width 0.16) (layer "In9.Cu") (net 266))
  (arc (start 196.813174 73.233274) (mid 196.754595 73.091853) (end 196.813173 72.950431) (width 0.16) (layer "In9.Cu") (net 266))
  (arc (start 197.732412 73.303983) (mid 197.790991 73.162561) (end 197.732412 73.021139) (width 0.16) (layer "In9.Cu") (net 266))
  (arc (start 197.166726 73.869669) (mid 197.225305 73.728247) (end 197.166726 73.586825) (width 0.16) (layer "In9.Cu") (net 266))
  (arc (start 197.381323 67.25) (mid 197.447224 67.090901) (end 197.606323 67.025) (width 0.16) (layer "In9.Cu") (net 266))
  (arc (start 198.193677 67.025) (mid 198.352776 66.959099) (end 198.418677 66.8) (width 0.16) (layer "In9.Cu") (net 266))
  (arc (start 196.247489 73.516116) (mid 196.38891 73.457538) (end 196.530333 73.516116) (width 0.16) (layer "In9.Cu") (net 266))
  (arc (start 197.381323 68.15) (mid 197.447224 67.990901) (end 197.606323 67.925) (width 0.16) (layer "In9.Cu") (net 266))
  (arc (start 197.449569 73.303983) (mid 197.59099 73.362562) (end 197.732412 73.303984) (width 0.16) (layer "In9.Cu") (net 266))
  (arc (start 198.418677 66.8) (mid 198.352776 66.640901) (end 198.193677 66.575) (width 0.16) (layer "In9.Cu") (net 266))
  (segment (start 188.836328 55.060008) (end 188.836328 56.360008) (width 0.2) (layer "F.Cu") (net 267))
  (segment (start 188.636328 81.060008) (end 188.655836 81.060008) (width 0.127) (layer "F.Cu") (net 267))
  (segment (start 188.136328 81.560008) (end 188.636328 81.060008) (width 0.127) (layer "F.Cu") (net 267))
  (via (at 188.655836 81.060008) (size 0.5) (drill 0.2) (layers "F.Cu" "B.Cu") (net 267))
  (via (at 188.836328 56.360008) (size 0.5) (drill 0.2) (layers "F.Cu" "B.Cu") (net 267))
  (segment (start 194.5 68.7) (end 194.7 68.7) (width 0.16) (layer "In9.Cu") (net 267))
  (segment (start 194.057545 72.702949) (end 194.057545 72.702948) (width 0.16) (layer "In9.Cu") (net 267))
  (segment (start 188.836328 59.686328) (end 188.836328 56.360008) (width 0.16) (layer "In9.Cu") (net 267))
  (segment (start 193.725 75.275) (end 193.775 75.275) (width 0.16) (layer "In9.Cu") (net 267))
  (segment (start 193.775 74.825) (end 193.725 74.825) (width 0.16) (layer "In9.Cu") (net 267))
  (segment (start 193.5 73.6) (end 193.75 73.35) (width 0.16) (layer "In9.Cu") (net 267))
  (segment (start 189.6 60.45) (end 188.836328 59.686328) (width 0.16) (layer "In9.Cu") (net 267))
  (segment (start 189.235836 80.480008) (end 188.655836 81.060008) (width 0.1) (layer "In9.Cu") (net 267))
  (segment (start 193.5 73.65) (end 193.5 73.6) (width 0.16) (layer "In9.Cu") (net 267))
  (segment (start 194.9 72.2) (end 194.9 72.1) (width 0.16) (layer "In9.Cu") (net 267))
  (segment (start 193.05 64.2) (end 191.5 64.2) (width 0.16) (layer "In9.Cu") (net 267))
  (segment (start 194.5 71.1) (end 195.3 71.1) (width 0.16) (layer "In9.Cu") (net 267))
  (segment (start 189.6 62.3) (end 189.6 60.45) (width 0.16) (layer "In9.Cu") (net 267))
  (segment (start 190.521874 76.6) (end 189.235836 77.886038) (width 0.1) (layer "In9.Cu") (net 267))
  (segment (start 194.386398 72.713603) (end 194.9 72.2) (width 0.16) (layer "In9.Cu") (net 267))
  (segment (start 193.5 75.6) (end 193.5 75.8) (width 0.1) (layer "In9.Cu") (net 267))
  (segment (start 191.5 64.2) (end 189.6 62.3) (width 0.16) (layer "In9.Cu") (net 267))
  (segment (start 195.3 69.1) (end 194.5 69.1) (width 0.16) (layer "In9.Cu") (net 267))
  (segment (start 193.5 75.8) (end 192.7 76.6) (width 0.1) (layer "In9.Cu") (net 267))
  (segment (start 193.5 74.6) (end 193.5 74.55) (width 0.16) (layer "In9.Cu") (net 267))
  (segment (start 193.75 73.031802) (end 193.739345 73.021147) (width 0.16) (layer "In9.Cu") (net 267))
  (segment (start 194.057545 72.702948) (end 194.068201 72.713604) (width 0.16) (layer "In9.Cu") (net 267))
  (segment (start 194.9 66.05) (end 193.05 64.2) (width 0.16) (layer "In9.Cu") (net 267))
  (segment (start 194.5 70.3) (end 195.3 70.3) (width 0.16) (layer "In9.Cu") (net 267))
  (segment (start 194.5 69.5) (end 195.3 69.5) (width 0.16) (layer "In9.Cu") (net 267))
  (segment (start 192.7 76.6) (end 190.521874 76.6) (width 0.1) (layer "In9.Cu") (net 267))
  (segment (start 195.3 71.5) (end 194.5 71.5) (width 0.16) (layer "In9.Cu") (net 267))
  (segment (start 189.235836 77.886038) (end 189.235836 80.480008) (width 0.1) (layer "In9.Cu") (net 267))
  (segment (start 195.3 70.7) (end 194.5 70.7) (width 0.16) (layer "In9.Cu") (net 267))
  (segment (start 193.5 75.6) (end 193.5 75.5) (width 0.16) (layer "In9.Cu") (net 267))
  (segment (start 194.9 68.5) (end 194.9 66.05) (width 0.16) (layer "In9.Cu") (net 267))
  (segment (start 195.1 71.9) (end 195.3 71.9) (width 0.16) (layer "In9.Cu") (net 267))
  (segment (start 195.3 69.9) (end 194.5 69.9) (width 0.16) (layer "In9.Cu") (net 267))
  (segment (start 194.386399 72.713604) (end 194.386398 72.713603) (width 0.16) (layer "In9.Cu") (net 267))
  (arc (start 194.9 72.1) (mid 194.958579 71.958579) (end 195.1 71.9) (width 0.16) (layer "In9.Cu") (net 267))
  (arc (start 193.725 73.875) (mid 193.565901 73.809099) (end 193.5 73.65) (width 0.16) (layer "In9.Cu") (net 267))
  (arc (start 195.5 71.7) (mid 195.441421 71.558579) (end 195.3 71.5) (width 0.16) (layer "In9.Cu") (net 267))
  (arc (start 193.739345 73.021147) (mid 193.673444 72.862048) (end 193.739345 72.702949) (width 0.16) (layer "In9.Cu") (net 267))
  (arc (start 195.3 70.3) (mid 195.441421 70.241421) (end 195.5 70.1) (width 0.16) (layer "In9.Cu") (net 267))
  (arc (start 194.3 71.3) (mid 194.358579 71.158579) (end 194.5 71.1) (width 0.16) (layer "In9.Cu") (net 267))
  (arc (start 194.5 69.9) (mid 194.358579 69.841421) (end 194.3 69.7) (width 0.16) (layer "In9.Cu") (net 267))
  (arc (start 195.3 69.5) (mid 195.441421 69.441421) (end 195.5 69.3) (width 0.16) (layer "In9.Cu") (net 267))
  (arc (start 194.3 69.7) (mid 194.358579 69.558579) (end 194.5 69.5) (width 0.16) (layer "In9.Cu") (net 267))
  (arc (start 193.725 74.825) (mid 193.565901 74.759099) (end 193.5 74.6) (width 0.16) (layer "In9.Cu") (net 267))
  (arc (start 195.5 69.3) (mid 195.441421 69.158579) (end 195.3 69.1) (width 0.16) (layer "In9.Cu") (net 267))
  (arc (start 195.5 70.9) (mid 195.441421 70.758579) (end 195.3 70.7) (width 0.16) (layer "In9.Cu") (net 267))
  (arc (start 193.739345 72.702949) (mid 193.898446 72.637047) (end 194.057545 72.702949) (width 0.16) (layer "In9.Cu") (net 267))
  (arc (start 193.775 75.275) (mid 193.934099 75.209099) (end 194 75.05) (width 0.16) (layer "In9.Cu") (net 267))
  (arc (start 193.5 75.5) (mid 193.565901 75.340901) (end 193.725 75.275) (width 0.16) (layer "In9.Cu") (net 267))
  (arc (start 195.3 71.1) (mid 195.441421 71.041421) (end 195.5 70.9) (width 0.16) (layer "In9.Cu") (net 267))
  (arc (start 194.5 69.1) (mid 194.358579 69.041421) (end 194.3 68.9) (width 0.16) (layer "In9.Cu") (net 267))
  (arc (start 194 75.05) (mid 193.934099 74.890901) (end 193.775 74.825) (width 0.16) (layer "In9.Cu") (net 267))
  (arc (start 194.5 70.7) (mid 194.358579 70.641421) (end 194.3 70.5) (width 0.16) (layer "In9.Cu") (net 267))
  (arc (start 195.3 71.9) (mid 195.441421 71.841421) (end 195.5 71.7) (width 0.16) (layer "In9.Cu") (net 267))
  (arc (start 194.068201 72.713604) (mid 194.2273 72.779505) (end 194.386399 72.713604) (width 0.16) (layer "In9.Cu") (net 267))
  (arc (start 194.3 70.5) (mid 194.358579 70.358579) (end 194.5 70.3) (width 0.16) (layer "In9.Cu") (net 267))
  (arc (start 193.95 74.1) (mid 193.884099 73.940901) (end 193.725 73.875) (width 0.16) (layer "In9.Cu") (net 267))
  (arc (start 195.5 70.1) (mid 195.441421 69.958579) (end 195.3 69.9) (width 0.16) (layer "In9.Cu") (net 267))
  (arc (start 194.5 71.5) (mid 194.358579 71.441421) (end 194.3 71.3) (width 0.16) (layer "In9.Cu") (net 267))
  (arc (start 193.5 74.55) (mid 193.565901 74.390901) (end 193.725 74.325) (width 0.16) (layer "In9.Cu") (net 267))
  (arc (start 193.75 73.35) (mid 193.815901 73.190901) (end 193.75 73.031802) (width 0.16) (layer "In9.Cu") (net 267))
  (arc (start 194.7 68.7) (mid 194.841421 68.641421) (end 194.9 68.5) (width 0.16) (layer "In9.Cu") (net 267))
  (arc (start 194.3 68.9) (mid 194.358579 68.758579) (end 194.5 68.7) (width 0.16) (layer "In9.Cu") (net 267))
  (arc (start 193.725 74.325) (mid 193.884099 74.259099) (end 193.95 74.1) (width 0.16) (layer "In9.Cu") (net 267))
  (segment (start 189.136328 78.560008) (end 189.636328 78.060008) (width 0.127) (layer "F.Cu") (net 268))
  (segment (start 189.636328 78.060008) (end 189.655836 78.060008) (width 0.127) (layer "F.Cu") (net 268))
  (segment (start 189.686328 55.060008) (end 189.686328 56.360008) (width 0.2) (layer "F.Cu") (net 268))
  (via (at 189.655836 78.060008) (size 0.5) (drill 0.2) (layers "F.Cu" "B.Cu") (net 268))
  (via (at 189.686328 56.360008) (size 0.5) (drill 0.2) (layers "F.Cu" "B.Cu") (net 268))
  (segment (start 197.203998 70.375) (end 196.596002 70.375) (width 0.16) (layer "In9.Cu") (net 268))
  (segment (start 195.2 75.54) (end 195.2 74.05) (width 0.16) (layer "In9.Cu") (net 268))
  (segment (start 189.686328 59.316328) (end 189.686328 56.360008) (width 0.16) (layer "In9.Cu") (net 268))
  (segment (start 195.2 74.05) (end 196.7 72.55) (width 0.16) (layer "In9.Cu") (net 268))
  (segment (start 190.075836 77.640008) (end 189.655836 78.060008) (width 0.1) (layer "In9.Cu") (net 268))
  (segment (start 192.4 78) (end 191.5 78) (width 0.1) (layer "In9.Cu") (net 268))
  (segment (start 196.7 72.55) (end 196.7 72.548198) (width 0.16) (layer "In9.Cu") (net 268))
  (segment (start 196.596002 69.925) (end 197.203998 69.925) (width 0.16) (layer "In9.Cu") (net 268))
  (segment (start 190.836328 60.466328) (end 189.686328 59.316328) (width 0.16) (layer "In9.Cu") (net 268))
  (segment (start 196.645 72.175) (end 196.596002 72.175) (width 0.16) (layer "In9.Cu") (net 268))
  (segment (start 194.2 76.8) (end 193.6 76.8) (width 0.1) (layer "In9.Cu") (net 268))
  (segment (start 196.7 72.23) (end 196.645 72.175) (width 0.16) (layer "In9.Cu") (net 268))
  (segment (start 193.6 76.8) (end 192.4 78) (width 0.1) (layer "In9.Cu") (net 268))
  (segment (start 191.77 62.52) (end 190.836328 61.586328) (width 0.16) (layer "In9.Cu") (net 268))
  (segment (start 195.2 75.54) (end 195.2 75.8) (width 0.1) (layer "In9.Cu") (net 268))
  (segment (start 197.203998 71.275) (end 196.596002 71.275) (width 0.16) (layer "In9.Cu") (net 268))
  (segment (start 196.9 65.18) (end 194.24 62.52) (width 0.16) (layer "In9.Cu") (net 268))
  (segment (start 196.596002 70.825) (end 197.203998 70.825) (width 0.16) (layer "In9.Cu") (net 268))
  (segment (start 194.24 62.52) (end 191.77 62.52) (width 0.16) (layer "In9.Cu") (net 268))
  (segment (start 196.596002 71.725) (end 197.203998 71.725) (width 0.16) (layer "In9.Cu") (net 268))
  (segment (start 197.203998 69.475) (end 197.125 69.475) (width 0.16) (layer "In9.Cu") (net 268))
  (segment (start 190.836328 61.586328) (end 190.836328 60.466328) (width 0.16) (layer "In9.Cu") (net 268))
  (segment (start 195.2 75.8) (end 194.2 76.8) (width 0.1) (layer "In9.Cu") (net 268))
  (segment (start 191.5 78) (end 191.140008 77.640008) (width 0.1) (layer "In9.Cu") (net 268))
  (segment (start 196.9 69.25) (end 196.9 65.18) (width 0.16) (layer "In9.Cu") (net 268))
  (segment (start 191.140008 77.640008) (end 190.075836 77.640008) (width 0.1) (layer "In9.Cu") (net 268))
  (arc (start 197.428998 69.7) (mid 197.363097 69.540901) (end 197.203998 69.475) (width 0.16) (layer "In9.Cu") (net 268))
  (arc (start 196.371002 71.05) (mid 196.436903 70.890901) (end 196.596002 70.825) (width 0.16) (layer "In9.Cu") (net 268))
  (arc (start 196.371002 71.95) (mid 196.436903 71.790901) (end 196.596002 71.725) (width 0.16) (layer "In9.Cu") (net 268))
  (arc (start 196.596002 72.175) (mid 196.436903 72.109099) (end 196.371002 71.95) (width 0.16) (layer "In9.Cu") (net 268))
  (arc (start 197.203998 69.925) (mid 197.363097 69.859099) (end 197.428998 69.7) (width 0.16) (layer "In9.Cu") (net 268))
  (arc (start 196.7 72.548198) (mid 196.765901 72.389099) (end 196.7 72.23) (width 0.16) (layer "In9.Cu") (net 268))
  (arc (start 197.203998 71.725) (mid 197.363097 71.659099) (end 197.428998 71.5) (width 0.16) (layer "In9.Cu") (net 268))
  (arc (start 196.596002 70.375) (mid 196.436903 70.309099) (end 196.371002 70.15) (width 0.16) (layer "In9.Cu") (net 268))
  (arc (start 197.428998 71.5) (mid 197.363097 71.340901) (end 197.203998 71.275) (width 0.16) (layer "In9.Cu") (net 268))
  (arc (start 197.125 69.475) (mid 196.965901 69.409099) (end 196.9 69.25) (width 0.16) (layer "In9.Cu") (net 268))
  (arc (start 196.596002 71.275) (mid 196.436903 71.209099) (end 196.371002 71.05) (width 0.16) (layer "In9.Cu") (net 268))
  (arc (start 197.428998 70.6) (mid 197.363097 70.440901) (end 197.203998 70.375) (width 0.16) (layer "In9.Cu") (net 268))
  (arc (start 196.371002 70.15) (mid 196.436903 69.990901) (end 196.596002 69.925) (width 0.16) (layer "In9.Cu") (net 268))
  (arc (start 197.203998 70.825) (mid 197.363097 70.759099) (end 197.428998 70.6) (width 0.16) (layer "In9.Cu") (net 268))
  (segment (start 187.136328 79.560008) (end 187.189992 79.560008) (width 0.127) (layer "F.Cu") (net 269))
  (segment (start 187.136328 55.060008) (end 187.136328 56.360008) (width 0.2) (layer "F.Cu") (net 269))
  (segment (start 187.189992 79.560008) (end 187.686 79.064) (width 0.127) (layer "F.Cu") (net 269))
  (segment (start 187.686 79.064) (end 187.745 79.064) (width 0.127) (layer "F.Cu") (net 269))
  (via (at 187.745 79.064) (size 0.5) (drill 0.2) (layers "F.Cu" "B.Cu") (net 269))
  (via (at 187.136328 56.360008) (size 0.5) (drill 0.2) (layers "F.Cu" "B.Cu") (net 269))
  (segment (start 188.44 76.87) (end 188.83 76.87) (width 0.1) (layer "In9.Cu") (net 269))
  (segment (start 188.83 76.87) (end 189.9 75.8) (width 0.1) (layer "In9.Cu") (net 269))
  (segment (start 187.443449 61.236337) (end 187.339381 61.236354) (width 0.16) (layer "In9.Cu") (net 269))
  (segment (start 187.51 78.33971) (end 187.51 77.8) (width 0.1) (layer "In9.Cu") (net 269))
  (segment (start 186.80842 62.436328) (end 187.514236 62.436328) (width 0.16) (layer "In9.Cu") (net 269))
  (segment (start 190.65 66.85) (end 190.437599 66.637599) (width 0.16) (layer "In9.Cu") (net 269))
  (segment (start 186.80842 61.636328) (end 187.514236 61.636328) (width 0.16) (layer "In9.Cu") (net 269))
  (segment (start 186.846262 62.83633) (end 187.034493 62.83637) (width 0.16) (layer "In9.Cu") (net 269))
  (segment (start 188.409649 65.07338) (end 188.87338 64.609649) (width 0.16) (layer "In9.Cu") (net 269))
  (segment (start 191.51 66.85) (end 190.65 66.85) (width 0.16) (layer "In9.Cu") (net 269))
  (segment (start 189.156225 64.892494) (end 188.692492 65.356223) (width 0.16) (layer "In9.Cu") (net 269))
  (segment (start 190.48 66.397157) (end 190.570444 66.306712) (width 0.16) (layer "In9.Cu") (net 269))
  (segment (start 187.843961 64.507692) (end 188.307692 64.043961) (width 0.16) (layer "In9.Cu") (net 269))
  (segment (start 190.004757 65.458182) (end 190.004756 65.458182) (width 0.16) (layer "In9.Cu") (net 269))
  (segment (start 188.409649 65.073381) (end 188.409649 65.07338) (width 0.16) (layer "In9.Cu") (net 269))
  (segment (start 187.278273 64.224848) (end 187.278274 64.224848) (width 0.16) (layer "In9.Cu") (net 269))
  (segment (start 189.9 73.55) (end 191.84 71.61) (width 0.16) (layer "In9.Cu") (net 269))
  (segment (start 189.9 75.55) (end 189.9 73.55) (width 0.16) (layer "In9.Cu") (net 269))
  (segment (start 187.136328 61.033334) (end 187.136328 56.360008) (width 0.16) (layer "In9.Cu") (net 269))
  (segment (start 186.80842 62.836328) (end 186.846262 62.83633) (width 0.16) (layer "In9.Cu") (net 269))
  (segment (start 187.368718 63.568718) (end 187.402427 63.602437) (width 0.16) (layer "In9.Cu") (net 269))
  (segment (start 191.84 67.18) (end 191.51 66.85) (width 0.16) (layer "In9.Cu") (net 269))
  (segment (start 188.975337 65.921912) (end 188.975338 65.921912) (width 0.16) (layer "In9.Cu") (net 269))
  (segment (start 190.570444 66.02387) (end 190.570444 66.023869) (width 0.16) (layer "In9.Cu") (net 269))
  (segment (start 189.721913 65.458182) (end 189.25818 65.921911) (width 0.16) (layer "In9.Cu") (net 269))
  (segment (start 188.975337 65.639069) (end 188.975337 65.639068) (width 0.16) (layer "In9.Cu") (net 269))
  (segment (start 188.975337 65.639068) (end 189.439068 65.175337) (width 0.16) (layer "In9.Cu") (net 269))
  (segment (start 187.843961 64.790536) (end 187.843962 64.790536) (width 0.16) (layer "In9.Cu") (net 269))
  (segment (start 187.278273 63.942004) (end 187.402411 63.817867) (width 0.16) (layer "In9.Cu") (net 269))
  (segment (start 188.307693 63.761118) (end 188.307692 63.761118) (width 0.16) (layer "In9.Cu") (net 269))
  (segment (start 189.541025 66.204756) (end 190.004756 65.741025) (width 0.16) (layer "In9.Cu") (net 269))
  (segment (start 188.590537 64.326806) (end 188.126804 64.790535) (width 0.16) (layer "In9.Cu") (net 269))
  (segment (start 190.479999 66.397157) (end 190.437614 66.43953) (width 0.16) (layer "In9.Cu") (net 269))
  (segment (start 191.84 71.61) (end 191.84 67.18) (width 0.16) (layer "In9.Cu") (net 269))
  (segment (start 188.409649 65.356224) (end 188.40965 65.356224) (width 0.16) (layer "In9.Cu") (net 269))
  (segment (start 187.368717 63.568716) (end 187.136328 63.336328) (width 0.16) (layer "In9.Cu") (net 269))
  (segment (start 190.479999 66.397157) (end 190.48 66.397157) (width 0.16) (layer "In9.Cu") (net 269))
  (segment (start 188.024849 63.761117) (end 188.024849 63.761118) (width 0.16) (layer "In9.Cu") (net 269))
  (segment (start 187.514236 62.036328) (end 186.80842 62.036328) (width 0.16) (layer "In9.Cu") (net 269))
  (segment (start 190.287601 66.023869) (end 189.823868 66.487599) (width 0.16) (layer "In9.Cu") (net 269))
  (segment (start 187.474753 61.236332) (end 187.443449 61.236337) (width 0.16) (layer "In9.Cu") (net 269))
  (segment (start 189.721913 65.458181) (end 189.721913 65.458182) (width 0.16) (layer "In9.Cu") (net 269))
  (segment (start 187.136328 63.336328) (end 187.136328 62.938227) (width 0.16) (layer "In9.Cu") (net 269))
  (segment (start 188.590537 64.326805) (end 188.590537 64.326806) (width 0.16) (layer "In9.Cu") (net 269))
  (segment (start 189.156225 64.892493) (end 189.156225 64.892494) (width 0.16) (layer "In9.Cu") (net 269))
  (segment (start 189.9 75.8) (end 189.9 75.55) (width 0.1) (layer "In9.Cu") (net 269))
  (segment (start 190.287601 66.023868) (end 190.287601 66.023869) (width 0.16) (layer "In9.Cu") (net 269))
  (segment (start 189.439069 64.892494) (end 189.439068 64.892494) (width 0.16) (layer "In9.Cu") (net 269))
  (segment (start 187.843961 64.507693) (end 187.843961 64.507692) (width 0.16) (layer "In9.Cu") (net 269))
  (segment (start 188.024849 63.761118) (end 187.561116 64.224847) (width 0.16) (layer "In9.Cu") (net 269))
  (segment (start 187.368718 63.568718) (end 187.368717 63.568716) (width 0.16) (layer "In9.Cu") (net 269))
  (segment (start 188.873381 64.326806) (end 188.87338 64.326806) (width 0.16) (layer "In9.Cu") (net 269))
  (segment (start 187.514236 61.236328) (end 187.474753 61.236332) (width 0.16) (layer "In9.Cu") (net 269))
  (segment (start 189.541025 66.4876) (end 189.541026 66.4876) (width 0.16) (layer "In9.Cu") (net 269))
  (segment (start 187.51 77.8) (end 188.44 76.87) (width 0.1) (layer "In9.Cu") (net 269))
  (segment (start 187.745 78.57471) (end 187.51 78.33971) (width 0.1) (layer "In9.Cu") (net 269))
  (segment (start 189.541025 66.204757) (end 189.541025 66.204756) (width 0.16) (layer "In9.Cu") (net 269))
  (segment (start 187.745 78.57471) (end 187.745 79.064) (width 0.1) (layer "In9.Cu") (net 269))
  (segment (start 187.278273 63.942005) (end 187.278273 63.942004) (width 0.16) (layer "In9.Cu") (net 269))
  (arc (start 187.339381 61.236354) (mid 187.195803 61.176902) (end 187.136328 61.033334) (width 0.16) (layer "In9.Cu") (net 269))
  (arc (start 190.570444 66.306712) (mid 190.629022 66.165291) (end 190.570444 66.02387) (width 0.16) (layer "In9.Cu") (net 269))
  (arc (start 189.823868 66.487599) (mid 189.682447 66.546178) (end 189.541025 66.4876) (width 0.16) (layer "In9.Cu") (net 269))
  (arc (start 188.307692 63.761118) (mid 188.166271 63.702539) (end 188.024849 63.761117) (width 0.16) (layer "In9.Cu") (net 269))
  (arc (start 187.714236 61.436328) (mid 187.655657 61.294907) (end 187.514236 61.236328) (width 0.16) (layer "In9.Cu") (net 269))
  (arc (start 186.60842 62.636328) (mid 186.666999 62.494907) (end 186.80842 62.436328) (width 0.16) (layer "In9.Cu") (net 269))
  (arc (start 190.437599 66.637599) (mid 190.396581 66.538561) (end 190.437614 66.43953) (width 0.16) (layer "In9.Cu") (net 269))
  (arc (start 188.307692 64.043961) (mid 188.366271 63.90254) (end 188.307693 63.761118) (width 0.16) (layer "In9.Cu") (net 269))
  (arc (start 187.514236 62.436328) (mid 187.655657 62.377749) (end 187.714236 62.236328) (width 0.16) (layer "In9.Cu") (net 269))
  (arc (start 190.570444 66.023869) (mid 190.429023 65.96529) (end 190.287601 66.023868) (width 0.16) (layer "In9.Cu") (net 269))
  (arc (start 190.004756 65.741025) (mid 190.063335 65.599604) (end 190.004757 65.458182) (width 0.16) (layer "In9.Cu") (net 269))
  (arc (start 187.402411 63.817867) (mid 187.447032 63.710155) (end 187.402427 63.602437) (width 0.16) (layer "In9.Cu") (net 269))
  (arc (start 187.843962 64.790536) (mid 187.785383 64.649115) (end 187.843961 64.507693) (width 0.16) (layer "In9.Cu") (net 269))
  (arc (start 188.40965 65.356224) (mid 188.351071 65.214803) (end 188.409649 65.073381) (width 0.16) (layer "In9.Cu") (net 269))
  (arc (start 188.126804 64.790535) (mid 187.985383 64.849114) (end 187.843961 64.790536) (width 0.16) (layer "In9.Cu") (net 269))
  (arc (start 189.439068 65.175337) (mid 189.497647 65.033916) (end 189.439069 64.892494) (width 0.16) (layer "In9.Cu") (net 269))
  (arc (start 187.514236 61.636328) (mid 187.655657 61.577749) (end 187.714236 61.436328) (width 0.16) (layer "In9.Cu") (net 269))
  (arc (start 190.004756 65.458182) (mid 189.863335 65.399603) (end 189.721913 65.458181) (width 0.16) (layer "In9.Cu") (net 269))
  (arc (start 189.25818 65.921911) (mid 189.116759 65.98049) (end 188.975337 65.921912) (width 0.16) (layer "In9.Cu") (net 269))
  (arc (start 187.136328 62.938227) (mid 187.106503 62.866211) (end 187.034493 62.83637) (width 0.16) (layer "In9.Cu") (net 269))
  (arc (start 188.87338 64.326806) (mid 188.731959 64.268227) (end 188.590537 64.326805) (width 0.16) (layer "In9.Cu") (net 269))
  (arc (start 188.975338 65.921912) (mid 188.916759 65.780491) (end 188.975337 65.639069) (width 0.16) (layer "In9.Cu") (net 269))
  (arc (start 189.439068 64.892494) (mid 189.297647 64.833915) (end 189.156225 64.892493) (width 0.16) (layer "In9.Cu") (net 269))
  (arc (start 186.80842 62.836328) (mid 186.666999 62.777749) (end 186.60842 62.636328) (width 0.16) (layer "In9.Cu") (net 269))
  (arc (start 186.60842 61.836328) (mid 186.666999 61.694907) (end 186.80842 61.636328) (width 0.16) (layer "In9.Cu") (net 269))
  (arc (start 188.87338 64.609649) (mid 188.931959 64.468228) (end 188.873381 64.326806) (width 0.16) (layer "In9.Cu") (net 269))
  (arc (start 189.541026 66.4876) (mid 189.482447 66.346179) (end 189.541025 66.204757) (width 0.16) (layer "In9.Cu") (net 269))
  (arc (start 187.714236 62.236328) (mid 187.655657 62.094907) (end 187.514236 62.036328) (width 0.16) (layer "In9.Cu") (net 269))
  (arc (start 187.278274 64.224848) (mid 187.219695 64.083427) (end 187.278273 63.942005) (width 0.16) (layer "In9.Cu") (net 269))
  (arc (start 187.561116 64.224847) (mid 187.419695 64.283426) (end 187.278273 64.224848) (width 0.16) (layer "In9.Cu") (net 269))
  (arc (start 188.692492 65.356223) (mid 188.551071 65.414802) (end 188.409649 65.356224) (width 0.16) (layer "In9.Cu") (net 269))
  (arc (start 186.80842 62.036328) (mid 186.666999 61.977749) (end 186.60842 61.836328) (width 0.16) (layer "In9.Cu") (net 269))
  (segment (start 186.63 80.066336) (end 186.136328 80.560008) (width 0.127) (layer "F.Cu") (net 270))
  (segment (start 186.63 79.97) (end 186.63 80.066336) (width 0.127) (layer "F.Cu") (net 270))
  (segment (start 186.286328 55.060008) (end 186.286328 56.360008) (width 0.2) (layer "F.Cu") (net 270))
  (via (at 186.286328 56.360008) (size 0.5) (drill 0.2) (layers "F.Cu" "B.Cu") (net 270))
  (via (at 186.63 79.97) (size 0.5) (drill 0.2) (layers "F.Cu" "B.Cu") (net 270))
  (segment (start 186.639856 77.46251) (end 187.06648 77.46251) (width 0.1) (layer "In9.Cu") (net 270))
  (segment (start 189.133847 68.447953) (end 189.2318 68.349999) (width 0.16) (layer "In9.Cu") (net 270))
  (segment (start 186.286328 56.360008) (end 186.286328 59.738672) (width 0.16) (layer "In9.Cu") (net 270))
  (segment (start 188.17925 67.493354) (end 188.179248 67.493353) (width 0.16) (layer "In9.Cu") (net 270))
  (segment (start 185.8 60.225) (end 185.8 61.95) (width 0.16) (layer "In9.Cu") (net 270))
  (segment (start 188.339798 66.696404) (end 188.339798 66.696403) (width 0.16) (layer "In9.Cu") (net 270))
  (segment (start 186.906448 66.220552) (end 186.906446 66.220551) (width 0.16) (layer "In9.Cu") (net 270))
  (segment (start 189.7 68.5) (end 189.7 71.575) (width 0.16) (layer "In9.Cu") (net 270))
  (segment (start 185.633646 64.94775) (end 185.633644 64.947749) (width 0.16) (layer "In9.Cu") (net 270))
  (segment (start 188.657997 67.014602) (end 188.17925 67.493354) (width 0.16) (layer "In9.Cu") (net 270))
  (segment (start 186.175 77.927366) (end 186.639856 77.46251) (width 0.1) (layer "In9.Cu") (net 270))
  (segment (start 186.748794 65.105399) (end 186.270047 65.584151) (width 0.16) (layer "In9.Cu") (net 270))
  (segment (start 186.430595 64.787201) (end 186.430595 64.7872) (width 0.16) (layer "In9.Cu") (net 270))
  (segment (start 187.542849 66.856953) (end 187.542847 66.856952) (width 0.16) (layer "In9.Cu") (net 270))
  (segment (start 189.7 71.575) (end 188.3 72.975) (width 0.16) (layer "In9.Cu") (net 270))
  (segment (start 185.4 62.35) (end 185.4 64.2) (width 0.16) (layer "In9.Cu") (net 270))
  (segment (start 187.066996 65.423602) (end 187.066996 65.423601) (width 0.16) (layer "In9.Cu") (net 270))
  (segment (start 187.861046 67.175151) (end 188.339798 66.696404) (width 0.16) (layer "In9.Cu") (net 270))
  (segment (start 189.55 68.35) (end 189.7 68.5) (width 0.16) (layer "In9.Cu") (net 270))
  (segment (start 186.175 79.515) (end 186.175 77.927366) (width 0.1) (layer "In9.Cu") (net 270))
  (segment (start 187.06648 77.46251) (end 188.3 76.22899) (width 0.1) (layer "In9.Cu") (net 270))
  (segment (start 185.8 61.95) (end 185.4 62.35) (width 0.16) (layer "In9.Cu") (net 270))
  (segment (start 188.021596 66.378201) (end 187.542849 66.856953) (width 0.16) (layer "In9.Cu") (net 270))
  (segment (start 187.224645 66.53875) (end 187.703397 66.060003) (width 0.16) (layer "In9.Cu") (net 270))
  (segment (start 186.286328 59.738672) (end 185.8 60.225) (width 0.16) (layer "In9.Cu") (net 270))
  (segment (start 188.3 76.22899) (end 188.3 75.55) (width 0.1) (layer "In9.Cu") (net 270))
  (segment (start 188.497447 67.811552) (end 188.976199 67.332805) (width 0.16) (layer "In9.Cu") (net 270))
  (segment (start 187.703397 66.060003) (end 187.703397 66.060002) (width 0.16) (layer "In9.Cu") (net 270))
  (segment (start 188.815648 68.129753) (end 188.815648 68.129754) (width 0.16) (layer "In9.Cu") (net 270))
  (segment (start 189.294398 67.651003) (end 188.815648 68.129753) (width 0.16) (layer "In9.Cu") (net 270))
  (segment (start 186.63 79.97) (end 186.175 79.515) (width 0.1) (layer "In9.Cu") (net 270))
  (segment (start 189.2318 68.349999) (end 189.231801 68.349999) (width 0.16) (layer "In9.Cu") (net 270))
  (segment (start 188.976199 67.332805) (end 188.976199 67.332804) (width 0.16) (layer "In9.Cu") (net 270))
  (segment (start 187.385195 65.7418) (end 186.906448 66.220552) (width 0.16) (layer "In9.Cu") (net 270))
  (segment (start 186.588244 65.902349) (end 187.066996 65.423602) (width 0.16) (layer "In9.Cu") (net 270))
  (segment (start 188.3 72.975) (end 188.3 75.55) (width 0.16) (layer "In9.Cu") (net 270))
  (segment (start 185.4 64.2) (end 185.731598 64.531597) (width 0.16) (layer "In9.Cu") (net 270))
  (segment (start 185.951843 65.265948) (end 186.430595 64.787201) (width 0.16) (layer "In9.Cu") (net 270))
  (segment (start 185.731598 64.849795) (end 185.633646 64.94775) (width 0.16) (layer "In9.Cu") (net 270))
  (segment (start 186.270047 65.584151) (end 186.270045 65.58415) (width 0.16) (layer "In9.Cu") (net 270))
  (arc (start 188.339798 66.696403) (mid 188.498898 66.630502) (end 188.657997 66.696404) (width 0.16) (layer "In9.Cu") (net 270))
  (arc (start 188.815648 68.129754) (mid 188.749746 68.288853) (end 188.815649 68.447953) (width 0.16) (layer "In9.Cu") (net 270))
  (arc (start 187.542847 66.856952) (mid 187.476947 67.016053) (end 187.542848 67.175151) (width 0.16) (layer "In9.Cu") (net 270))
  (arc (start 187.385195 65.423602) (mid 187.451096 65.582701) (end 187.385195 65.7418) (width 0.16) (layer "In9.Cu") (net 270))
  (arc (start 185.633645 65.265948) (mid 185.792744 65.331849) (end 185.951843 65.265948) (width 0.16) (layer "In9.Cu") (net 270))
  (arc (start 188.976199 67.332804) (mid 189.135299 67.266903) (end 189.294398 67.332805) (width 0.16) (layer "In9.Cu") (net 270))
  (arc (start 189.294398 67.332805) (mid 189.360299 67.491904) (end 189.294398 67.651003) (width 0.16) (layer "In9.Cu") (net 270))
  (arc (start 186.748794 64.787201) (mid 186.814695 64.9463) (end 186.748794 65.105399) (width 0.16) (layer "In9.Cu") (net 270))
  (arc (start 185.633644 64.947749) (mid 185.567744 65.10685) (end 185.633645 65.265948) (width 0.16) (layer "In9.Cu") (net 270))
  (arc (start 186.270045 65.58415) (mid 186.204145 65.743251) (end 186.270046 65.902349) (width 0.16) (layer "In9.Cu") (net 270))
  (arc (start 187.066996 65.423601) (mid 187.226096 65.3577) (end 187.385195 65.423602) (width 0.16) (layer "In9.Cu") (net 270))
  (arc (start 187.703397 66.060002) (mid 187.862497 65.994101) (end 188.021596 66.060003) (width 0.16) (layer "In9.Cu") (net 270))
  (arc (start 185.731598 64.531597) (mid 185.797499 64.690696) (end 185.731598 64.849795) (width 0.16) (layer "In9.Cu") (net 270))
  (arc (start 187.542848 67.175151) (mid 187.701947 67.241052) (end 187.861046 67.175151) (width 0.16) (layer "In9.Cu") (net 270))
  (arc (start 188.179249 67.811552) (mid 188.338348 67.877453) (end 188.497447 67.811552) (width 0.16) (layer "In9.Cu") (net 270))
  (arc (start 188.657997 66.696404) (mid 188.723898 66.855503) (end 188.657997 67.014602) (width 0.16) (layer "In9.Cu") (net 270))
  (arc (start 188.179248 67.493353) (mid 188.113348 67.652454) (end 188.179249 67.811552) (width 0.16) (layer "In9.Cu") (net 270))
  (arc (start 188.021596 66.060003) (mid 188.087497 66.219102) (end 188.021596 66.378201) (width 0.16) (layer "In9.Cu") (net 270))
  (arc (start 186.270046 65.902349) (mid 186.429145 65.96825) (end 186.588244 65.902349) (width 0.16) (layer "In9.Cu") (net 270))
  (arc (start 186.906447 66.53875) (mid 187.065546 66.604651) (end 187.224645 66.53875) (width 0.16) (layer "In9.Cu") (net 270))
  (arc (start 189.231801 68.349999) (mid 189.3909 68.284097) (end 189.55 68.35) (width 0.16) (layer "In9.Cu") (net 270))
  (arc (start 186.906446 66.220551) (mid 186.840546 66.379652) (end 186.906447 66.53875) (width 0.16) (layer "In9.Cu") (net 270))
  (arc (start 186.430595 64.7872) (mid 186.589695 64.721299) (end 186.748794 64.787201) (width 0.16) (layer "In9.Cu") (net 270))
  (arc (start 188.815649 68.447953) (mid 188.974748 68.513854) (end 189.133847 68.447953) (width 0.16) (layer "In9.Cu") (net 270))
  (segment (start 194.636328 77.060008) (end 194.655836 77.060008) (width 0.127) (layer "F.Cu") (net 271))
  (segment (start 194.136328 77.560008) (end 194.636328 77.060008) (width 0.127) (layer "F.Cu") (net 271))
  (segment (start 214.336328 59.660008) (end 214.336328 60.960008) (width 0.2) (layer "F.Cu") (net 271))
  (via blind (at 214.336328 60.960008) (size 0.5) (drill 0.2) (layers "F.Cu" "In5.Cu") (net 271))
  (via blind (at 194.655836 77.060008) (size 0.5) (drill 0.2) (layers "F.Cu" "In5.Cu") (net 271))
  (segment (start 196.886817 70.894169) (end 196.886817 70.894168) (width 0.146) (layer "In5.Cu") (net 271))
  (segment (start 198.144363 70.737495) (end 198.144362 70.737496) (width 0.146) (layer "In5.Cu") (net 271))
  (segment (start 196.447302 72.434556) (end 196.447301 72.434557) (width 0.146) (layer "In5.Cu") (net 271))
  (segment (start 197.578676 71.303182) (end 197.578675 71.303183) (width 0.146) (layer "In5.Cu") (net 271))
  (segment (start 194.906913 72.591229) (end 194.906915 72.591228) (width 0.146) (layer "In5.Cu") (net 271))
  (segment (start 196.447301 72.151713) (end 196.447301 72.151714) (width 0.146) (layer "In5.Cu") (net 271))
  (segment (start 197.452504 70.328482) (end 197.452504 70.328481) (width 0.146) (layer "In5.Cu") (net 271))
  (segment (start 194.655836 76.004164) (end 194.87 75.79) (width 0.09) (layer "In5.Cu") (net 271))
  (segment (start 196.038287 71.459855) (end 196.038286 71.459856) (width 0.146) (layer "In5.Cu") (net 271))
  (segment (start 195.881614 72.717401) (end 195.472599 72.308385) (width 0.146) (layer "In5.Cu") (net 271))
  (segment (start 195.4726 72.025542) (end 195.472599 72.025543) (width 0.146) (layer "In5.Cu") (net 271))
  (segment (start 197.012989 71.868869) (end 197.012988 71.86887) (width 0.146) (layer "In5.Cu") (net 271))
  (segment (start 196.447301 72.151714) (end 196.038286 71.742698) (width 0.146) (layer "In5.Cu") (net 271))
  (segment (start 196.32113 71.459855) (end 196.730146 71.86887) (width 0.146) (layer "In5.Cu") (net 271))
  (segment (start 195.189759 72.591228) (end 195.189757 72.591229) (width 0.146) (layer "In5.Cu") (net 271))
  (segment (start 197.578675 71.020339) (end 197.578675 71.02034) (width 0.146) (layer "In5.Cu") (net 271))
  (segment (start 198.081275 70.108723) (end 198.69 69.5) (width 0.146) (layer "In5.Cu") (net 271))
  (segment (start 196.886817 70.894168) (end 197.295833 71.303183) (width 0.146) (layer "In5.Cu") (net 271))
  (segment (start 194.97 72.937158) (end 194.906914 72.874072) (width 0.146) (layer "In5.Cu") (net 271))
  (segment (start 195.881615 73.000243) (end 195.881614 73.000244) (width 0.146) (layer "In5.Cu") (net 271))
  (segment (start 195.755443 72.025542) (end 196.164459 72.434557) (width 0.146) (layer "In5.Cu") (net 271))
  (segment (start 195.189757 72.591229) (end 195.598772 73.000244) (width 0.146) (layer "In5.Cu") (net 271))
  (segment (start 197.012988 71.586027) (end 196.603973 71.177011) (width 0.146) (layer "In5.Cu") (net 271))
  (segment (start 194.655836 77.060008) (end 194.655836 76.004164) (width 0.09) (layer "In5.Cu") (net 271))
  (segment (start 195.881614 72.7174) (end 195.881614 72.717401) (width 0.146) (layer "In5.Cu") (net 271))
  (segment (start 214.336328 63.563672) (end 214.336328 60.960008) (width 0.146) (layer "In5.Cu") (net 271))
  (segment (start 198.69 69.5) (end 208.4 69.5) (width 0.146) (layer "In5.Cu") (net 271))
  (segment (start 198.144362 70.454652) (end 198.144362 70.454653) (width 0.146) (layer "In5.Cu") (net 271))
  (segment (start 196.32113 71.459856) (end 196.32113 71.459855) (width 0.146) (layer "In5.Cu") (net 271))
  (segment (start 208.4 69.5) (end 214.336328 63.563672) (width 0.146) (layer "In5.Cu") (net 271))
  (segment (start 197.578675 71.02034) (end 197.16966 70.611324) (width 0.146) (layer "In5.Cu") (net 271))
  (segment (start 198.144362 70.454653) (end 198.081275 70.391566) (width 0.146) (layer "In5.Cu") (net 271))
  (segment (start 197.169661 70.328481) (end 197.16966 70.328482) (width 0.146) (layer "In5.Cu") (net 271))
  (segment (start 197.012988 71.586026) (end 197.012988 71.586027) (width 0.146) (layer "In5.Cu") (net 271))
  (segment (start 194.87 75.57) (end 194.87 73.32) (width 0.146) (layer "In5.Cu") (net 271))
  (segment (start 194.87 73.32) (end 194.97 73.22) (width 0.146) (layer "In5.Cu") (net 271))
  (segment (start 197.452504 70.328481) (end 197.86152 70.737496) (width 0.146) (layer "In5.Cu") (net 271))
  (segment (start 196.603974 70.894168) (end 196.603973 70.894169) (width 0.146) (layer "In5.Cu") (net 271))
  (segment (start 194.87 75.79) (end 194.87 75.57) (width 0.09) (layer "In5.Cu") (net 271))
  (segment (start 195.755443 72.025543) (end 195.755443 72.025542) (width 0.146) (layer "In5.Cu") (net 271))
  (segment (start 198.081274 70.108723) (end 198.081275 70.108723) (width 0.146) (layer "In5.Cu") (net 271))
  (arc (start 195.598772 73.000244) (mid 195.740194 73.058822) (end 195.881615 73.000243) (width 0.146) (layer "In5.Cu") (net 271))
  (arc (start 198.144362 70.737496) (mid 198.202941 70.596074) (end 198.144362 70.454652) (width 0.146) (layer "In5.Cu") (net 271))
  (arc (start 196.038286 71.742698) (mid 195.979708 71.601276) (end 196.038287 71.459855) (width 0.146) (layer "In5.Cu") (net 271))
  (arc (start 196.603973 70.894169) (mid 196.745396 70.835589) (end 196.886817 70.894169) (width 0.146) (layer "In5.Cu") (net 271))
  (arc (start 197.012988 71.86887) (mid 197.071567 71.727448) (end 197.012988 71.586026) (width 0.146) (layer "In5.Cu") (net 271))
  (arc (start 194.906915 72.591228) (mid 195.048336 72.53265) (end 195.189759 72.591228) (width 0.146) (layer "In5.Cu") (net 271))
  (arc (start 198.081275 70.391566) (mid 198.022696 70.250145) (end 198.081274 70.108723) (width 0.146) (layer "In5.Cu") (net 271))
  (arc (start 196.730146 71.86887) (mid 196.871568 71.927448) (end 197.012989 71.868869) (width 0.146) (layer "In5.Cu") (net 271))
  (arc (start 197.16966 70.611324) (mid 197.111082 70.469902) (end 197.169661 70.328481) (width 0.146) (layer "In5.Cu") (net 271))
  (arc (start 194.97 73.22) (mid 195.028579 73.078578) (end 194.97 72.937158) (width 0.146) (layer "In5.Cu") (net 271))
  (arc (start 197.578675 71.303183) (mid 197.637254 71.161761) (end 197.578675 71.020339) (width 0.146) (layer "In5.Cu") (net 271))
  (arc (start 196.164459 72.434557) (mid 196.305881 72.493135) (end 196.447302 72.434556) (width 0.146) (layer "In5.Cu") (net 271))
  (arc (start 195.472599 72.308385) (mid 195.414021 72.166963) (end 195.4726 72.025542) (width 0.146) (layer "In5.Cu") (net 271))
  (arc (start 197.16966 70.328482) (mid 197.311083 70.269902) (end 197.452504 70.328482) (width 0.146) (layer "In5.Cu") (net 271))
  (arc (start 197.86152 70.737496) (mid 198.002942 70.796074) (end 198.144363 70.737495) (width 0.146) (layer "In5.Cu") (net 271))
  (arc (start 195.881614 73.000244) (mid 195.940193 72.858822) (end 195.881614 72.7174) (width 0.146) (layer "In5.Cu") (net 271))
  (arc (start 197.295833 71.303183) (mid 197.437255 71.361761) (end 197.578676 71.303182) (width 0.146) (layer "In5.Cu") (net 271))
  (arc (start 196.447301 72.434557) (mid 196.50588 72.293135) (end 196.447301 72.151713) (width 0.146) (layer "In5.Cu") (net 271))
  (arc (start 194.906914 72.874072) (mid 194.848335 72.732651) (end 194.906913 72.591229) (width 0.146) (layer "In5.Cu") (net 271))
  (arc (start 195.472599 72.025543) (mid 195.614022 71.966963) (end 195.755443 72.025543) (width 0.146) (layer "In5.Cu") (net 271))
  (arc (start 196.038286 71.459856) (mid 196.179709 71.401276) (end 196.32113 71.459856) (width 0.146) (layer "In5.Cu") (net 271))
  (arc (start 196.603973 71.177011) (mid 196.545395 71.035589) (end 196.603974 70.894168) (width 0.146) (layer "In5.Cu") (net 271))
  (segment (start 179.674516 86.174516) (end 180.060008 86.560008) (width 0.127) (layer "F.Cu") (net 272))
  (segment (start 204.986328 59.660008) (end 204.986328 60.960008) (width 0.2) (layer "F.Cu") (net 272))
  (segment (start 179.65 86.174516) (end 179.674516 86.174516) (width 0.127) (layer "F.Cu") (net 272))
  (segment (start 180.060008 86.560008) (end 180.136328 86.560008) (width 0.127) (layer "F.Cu") (net 272))
  (via (at 179.65 86.174516) (size 0.5) (drill 0.2) (layers "F.Cu" "B.Cu") (net 272))
  (via (at 204.986328 60.960008) (size 0.5) (drill 0.2) (layers "F.Cu" "B.Cu") (net 272))
  (segment (start 193.215 71.085718) (end 193.215 71.534282) (width 0.196) (layer "In7.Cu") (net 272))
  (segment (start 188.715 71.534282) (end 188.715 71.085718) (width 0.196) (layer "In7.Cu") (net 272))
  (segment (start 180.202828 75.587172) (end 180.202828 73.137172) (width 0.196) (layer "In7.Cu") (net 272))
  (segment (start 194.939282 71.31) (end 199.85 71.31) (width 0.196) (layer "In7.Cu") (net 272))
  (segment (start 187.938564 70.861436) (end 187.99 70.861436) (width 0.196) (layer "In7.Cu") (net 272))
  (segment (start 191.715 71.534282) (end 191.715 71.085718) (width 0.196) (layer "In7.Cu") (net 272))
  (segment (start 193.715 71.534282) (end 193.715 71.085718) (width 0.196) (layer "In7.Cu") (net 272))
  (segment (start 191.215 71.085718) (end 191.215 71.534282) (width 0.196) (layer "In7.Cu") (net 272))
  (segment (start 180.202828 73.137172) (end 182.34 71) (width 0.196) (layer "In7.Cu") (net 272))
  (segment (start 180.15 85.28) (end 180.15 84.455656) (width 0.127) (layer "In7.Cu") (net 272))
  (segment (start 180.202828 84.402828) (end 180.202828 75.587172) (width 0.127) (layer "In7.Cu") (net 272))
  (segment (start 192.939282 70.861436) (end 192.990718 70.861436) (width 0.196) (layer "In7.Cu") (net 272))
  (segment (start 189.939282 70.861436) (end 189.990718 70.861436) (width 0.196) (layer "In7.Cu") (net 272))
  (segment (start 190.939282 70.861436) (end 190.990718 70.861436) (width 0.196) (layer "In7.Cu") (net 272))
  (segment (start 204.986328 66.173672) (end 204.986328 60.960008) (width 0.196) (layer "In7.Cu") (net 272))
  (segment (start 194.215 71.085718) (end 194.215 71.534282) (width 0.196) (layer "In7.Cu") (net 272))
  (segment (start 194.439282 71.758564) (end 194.490718 71.758564) (width 0.196) (layer "In7.Cu") (net 272))
  (segment (start 188.939282 70.861436) (end 188.990718 70.861436) (width 0.196) (layer "In7.Cu") (net 272))
  (segment (start 193.939282 70.861436) (end 193.990718 70.861436) (width 0.196) (layer "In7.Cu") (net 272))
  (segment (start 187.227212 71.31) (end 187.49 71.31) (width 0.196) (layer "In7.Cu") (net 272))
  (segment (start 188.214282 71.31) (end 188.215 71.31) (width 0.196) (layer "In7.Cu") (net 272))
  (segment (start 188.214282 71.085718) (end 188.214282 71.31) (width 0.196) (layer "In7.Cu") (net 272))
  (segment (start 189.215 71.085718) (end 189.215 71.534282) (width 0.196) (layer "In7.Cu") (net 272))
  (segment (start 186.867868 71.087868) (end 186.992976 71.212976) (width 0.196) (layer "In7.Cu") (net 272))
  (segment (start 191.939282 70.861436) (end 191.990718 70.861436) (width 0.196) (layer "In7.Cu") (net 272))
  (segment (start 192.715 71.534282) (end 192.715 71.085718) (width 0.196) (layer "In7.Cu") (net 272))
  (segment (start 179.65 85.78) (end 180.15 85.28) (width 0.127) (layer "In7.Cu") (net 272))
  (segment (start 182.34 71) (end 186.655736 71) (width 0.196) (layer "In7.Cu") (net 272))
  (segment (start 188.215 71.31) (end 188.215 71.534282) (width 0.196) (layer "In7.Cu") (net 272))
  (segment (start 190.715 71.534282) (end 190.715 71.085718) (width 0.196) (layer "In7.Cu") (net 272))
  (segment (start 191.439282 71.758564) (end 191.490718 71.758564) (width 0.196) (layer "In7.Cu") (net 272))
  (segment (start 192.215 71.085718) (end 192.215 71.534282) (width 0.196) (layer "In7.Cu") (net 272))
  (segment (start 190.215 71.085718) (end 190.215 71.534282) (width 0.196) (layer "In7.Cu") (net 272))
  (segment (start 193.439282 71.758564) (end 193.490718 71.758564) (width 0.196) (layer "In7.Cu") (net 272))
  (segment (start 189.439282 71.758564) (end 189.490718 71.758564) (width 0.196) (layer "In7.Cu") (net 272))
  (segment (start 180.15 84.455656) (end 180.202828 84.402828) (width 0.127) (layer "In7.Cu") (net 272))
  (segment (start 189.715 71.534282) (end 189.715 71.085718) (width 0.196) (layer "In7.Cu") (net 272))
  (segment (start 179.65 85.78) (end 179.65 86.174516) (width 0.127) (layer "In7.Cu") (net 272))
  (segment (start 192.439282 71.758564) (end 192.490718 71.758564) (width 0.196) (layer "In7.Cu") (net 272))
  (segment (start 188.439282 71.758564) (end 188.490718 71.758564) (width 0.196) (layer "In7.Cu") (net 272))
  (segment (start 190.439282 71.758564) (end 190.490718 71.758564) (width 0.196) (layer "In7.Cu") (net 272))
  (segment (start 199.85 71.31) (end 204.986328 66.173672) (width 0.196) (layer "In7.Cu") (net 272))
  (arc (start 188.990718 70.861436) (mid 189.149309 70.927127) (end 189.215 71.085718) (width 0.196) (layer "In7.Cu") (net 272))
  (arc (start 192.715 71.085718) (mid 192.780691 70.927127) (end 192.939282 70.861436) (width 0.196) (layer "In7.Cu") (net 272))
  (arc (start 190.490718 71.758564) (mid 190.649309 71.692873) (end 190.715 71.534282) (width 0.196) (layer "In7.Cu") (net 272))
  (arc (start 187.714282 71.085718) (mid 187.779973 70.927127) (end 187.938564 70.861436) (width 0.196) (layer "In7.Cu") (net 272))
  (arc (start 189.490718 71.758564) (mid 189.649309 71.692873) (end 189.715 71.534282) (width 0.196) (layer "In7.Cu") (net 272))
  (arc (start 189.715 71.085718) (mid 189.780691 70.927127) (end 189.939282 70.861436) (width 0.196) (layer "In7.Cu") (net 272))
  (arc (start 188.715 71.085718) (mid 188.780691 70.927127) (end 188.939282 70.861436) (width 0.196) (layer "In7.Cu") (net 272))
  (arc (start 193.490718 71.758564) (mid 193.649309 71.692873) (end 193.715 71.534282) (width 0.196) (layer "In7.Cu") (net 272))
  (arc (start 194.715 71.534282) (mid 194.780691 71.375691) (end 194.939282 71.31) (width 0.196) (layer "In7.Cu") (net 272))
  (arc (start 189.990718 70.861436) (mid 190.149309 70.927127) (end 190.215 71.085718) (width 0.196) (layer "In7.Cu") (net 272))
  (arc (start 187.49 71.31) (mid 187.648591 71.244309) (end 187.714282 71.085718) (width 0.196) (layer "In7.Cu") (net 272))
  (arc (start 190.715 71.085718) (mid 190.780691 70.927127) (end 190.939282 70.861436) (width 0.196) (layer "In7.Cu") (net 272))
  (arc (start 190.990718 70.861436) (mid 191.149309 70.927127) (end 191.215 71.085718) (width 0.196) (layer "In7.Cu") (net 272))
  (arc (start 191.490718 71.758564) (mid 191.649309 71.692873) (end 191.715 71.534282) (width 0.196) (layer "In7.Cu") (net 272))
  (arc (start 194.215 71.534282) (mid 194.280691 71.692873) (end 194.439282 71.758564) (width 0.196) (layer "In7.Cu") (net 272))
  (arc (start 186.867868 71.087868) (mid 186.770541 71.022836) (end 186.655736 71) (width 0.196) (layer "In7.Cu") (net 272))
  (arc (start 193.215 71.534282) (mid 193.280691 71.692873) (end 193.439282 71.758564) (width 0.196) (layer "In7.Cu") (net 272))
  (arc (start 187.99 70.861436) (mid 188.148591 70.927127) (end 188.214282 71.085718) (width 0.196) (layer "In7.Cu") (net 272))
  (arc (start 188.215 71.534282) (mid 188.280691 71.692873) (end 188.439282 71.758564) (width 0.196) (layer "In7.Cu") (net 272))
  (arc (start 188.490718 71.758564) (mid 188.649309 71.692873) (end 188.715 71.534282) (width 0.196) (layer "In7.Cu") (net 272))
  (arc (start 193.715 71.085718) (mid 193.780691 70.927127) (end 193.939282 70.861436) (width 0.196) (layer "In7.Cu") (net 272))
  (arc (start 192.490718 71.758564) (mid 192.649309 71.692873) (end 192.715 71.534282) (width 0.196) (layer "In7.Cu") (net 272))
  (arc (start 192.215 71.534282) (mid 192.280691 71.692873) (end 192.439282 71.758564) (width 0.196) (layer "In7.Cu") (net 272))
  (arc (start 191.215 71.534282) (mid 191.280691 71.692873) (end 191.439282 71.758564) (width 0.196) (layer "In7.Cu") (net 272))
  (arc (start 186.992976 71.212976) (mid 187.100444 71.284784) (end 187.227212 71.31) (width 0.196) (layer "In7.Cu") (net 272))
  (arc (start 192.990718 70.861436) (mid 193.149309 70.927127) (end 193.215 71.085718) (width 0.196) (layer "In7.Cu") (net 272))
  (arc (start 193.990718 70.861436) (mid 194.149309 70.927127) (end 194.215 71.085718) (width 0.196) (layer "In7.Cu") (net 272))
  (arc (start 194.490718 71.758564) (mid 194.649309 71.692873) (end 194.715 71.534282) (width 0.196) (layer "In7.Cu") (net 272))
  (arc (start 191.715 71.085718) (mid 191.780691 70.927127) (end 191.939282 70.861436) (width 0.196) (layer "In7.Cu") (net 272))
  (arc (start 189.215 71.534282) (mid 189.280691 71.692873) (end 189.439282 71.758564) (width 0.196) (layer "In7.Cu") (net 272))
  (arc (start 191.990718 70.861436) (mid 192.149309 70.927127) (end 192.215 71.085718) (width 0.196) (layer "In7.Cu") (net 272))
  (arc (start 190.215 71.534282) (mid 190.280691 71.692873) (end 190.439282 71.758564) (width 0.196) (layer "In7.Cu") (net 272))
  (segment (start 193.136328 81.560008) (end 193.636328 81.060008) (width 0.127) (layer "F.Cu") (net 273))
  (segment (start 228.786328 59.660008) (end 228.786328 60.960008) (width 0.2) (layer "F.Cu") (net 273))
  (segment (start 193.636328 81.060008) (end 193.655836 81.060008) (width 0.127) (layer "F.Cu") (net 273))
  (via blind (at 228.786328 60.960008) (size 0.5) (drill 0.2) (layers "F.Cu" "In5.Cu") (net 273))
  (via blind (at 193.655836 81.060008) (size 0.5) (drill 0.2) (layers "F.Cu" "In5.Cu") (net 273))
  (segment (start 209.54 77.553416) (end 209.54 78.246584) (width 0.146) (layer "In5.Cu") (net 273))
  (segment (start 211.54 77.553416) (end 211.54 78.246584) (width 0.146) (layer "In5.Cu") (net 273))
  (segment (start 207.54 77.553416) (end 207.54 78.246584) (width 0.146) (layer "In5.Cu") (net 273))
  (segment (start 205.04 78.246584) (end 205.04 77.553416) (width 0.146) (layer "In5.Cu") (net 273))
  (segment (start 204.04 78.246584) (end 204.04 77.553416) (width 0.146) (layer "In5.Cu") (net 273))
  (segment (start 203.04 78.246584) (end 203.04 77.553416) (width 0.146) (layer "In5.Cu") (net 273))
  (segment (start 212.29 77.9) (end 212.6 77.9) (width 0.146) (layer "In5.Cu") (net 273))
  (segment (start 204.54 77.553416) (end 204.54 78.246584) (width 0.146) (layer "In5.Cu") (net 273))
  (segment (start 201.7 77.9) (end 201.79 77.9) (width 0.146) (layer "In5.Cu") (net 273))
  (segment (start 197.04 79.88) (end 196.4 80.52) (width 0.09) (layer "In5.Cu") (net 273))
  (segment (start 208.04 78.246584) (end 208.04 77.553416) (width 0.146) (layer "In5.Cu") (net 273))
  (segment (start 194.195844 80.52) (end 193.655836 81.060008) (width 0.09) (layer "In5.Cu") (net 273))
  (segment (start 209.04 78.246584) (end 209.04 77.553416) (width 0.146) (layer "In5.Cu") (net 273))
  (segment (start 207.04 78.246584) (end 207.04 77.553416) (width 0.146) (layer "In5.Cu") (net 273))
  (segment (start 198.13 79.88) (end 197.04 79.88) (width 0.09) (layer "In5.Cu") (net 273))
  (segment (start 208.54 77.553416) (end 208.54 78.246584) (width 0.146) (layer "In5.Cu") (net 273))
  (segment (start 206.04 78.246584) (end 206.04 77.553416) (width 0.146) (layer "In5.Cu") (net 273))
  (segment (start 206.54 77.553416) (end 206.54 78.246584) (width 0.146) (layer "In5.Cu") (net 273))
  (segment (start 212.04 78.246584) (end 212.04 78.15) (width 0.146) (layer "In5.Cu") (net 273))
  (segment (start 203.54 77.553416) (end 203.54 78.246584) (width 0.146) (layer "In5.Cu") (net 273))
  (segment (start 211.04 78.246584) (end 211.04 77.553416) (width 0.146) (layer "In5.Cu") (net 273))
  (segment (start 202.54 77.553416) (end 202.54 77.65) (width 0.146) (layer "In5.Cu") (net 273))
  (segment (start 205.54 77.553416) (end 205.54 78.246584) (width 0.146) (layer "In5.Cu") (net 273))
  (segment (start 212.6 77.9) (end 228.786328 61.713672) (width 0.146) (layer "In5.Cu") (net 273))
  (segment (start 202.54 77.65) (end 202.54 78.246584) (width 0.146) (layer "In5.Cu") (net 273))
  (segment (start 210.04 78.246584) (end 210.04 77.553416) (width 0.146) (layer "In5.Cu") (net 273))
  (segment (start 199.72 79.88) (end 201.7 77.9) (width 0.146) (layer "In5.Cu") (net 273))
  (segment (start 210.54 77.553416) (end 210.54 78.246584) (width 0.146) (layer "In5.Cu") (net 273))
  (segment (start 228.786328 61.713672) (end 228.786328 60.960008) (width 0.146) (layer "In5.Cu") (net 273))
  (segment (start 198.13 79.88) (end 199.72 79.88) (width 0.146) (layer "In5.Cu") (net 273))
  (segment (start 202.04 77.65) (end 202.04 77.553416) (width 0.146) (layer "In5.Cu") (net 273))
  (segment (start 196.4 80.52) (end 194.195844 80.52) (width 0.09) (layer "In5.Cu") (net 273))
  (arc (start 208.54 78.246584) (mid 208.613223 78.423361) (end 208.79 78.496584) (width 0.146) (layer "In5.Cu") (net 273))
  (arc (start 204.79 78.496584) (mid 204.966777 78.423361) (end 205.04 78.246584) (width 0.146) (layer "In5.Cu") (net 273))
  (arc (start 210.54 78.246584) (mid 210.613223 78.423361) (end 210.79 78.496584) (width 0.146) (layer "In5.Cu") (net 273))
  (arc (start 206.54 78.246584) (mid 206.613223 78.423361) (end 206.79 78.496584) (width 0.146) (layer "In5.Cu") (net 273))
  (arc (start 204.29 77.303416) (mid 204.466777 77.376639) (end 204.54 77.553416) (width 0.146) (layer "In5.Cu") (net 273))
  (arc (start 206.79 78.496584) (mid 206.966777 78.423361) (end 207.04 78.246584) (width 0.146) (layer "In5.Cu") (net 273))
  (arc (start 206.29 77.303416) (mid 206.466777 77.376639) (end 206.54 77.553416) (width 0.146) (layer "In5.Cu") (net 273))
  (arc (start 202.79 78.496584) (mid 202.966777 78.423361) (end 203.04 78.246584) (width 0.146) (layer "In5.Cu") (net 273))
  (arc (start 203.29 77.303416) (mid 203.466777 77.376639) (end 203.54 77.553416) (width 0.146) (layer "In5.Cu") (net 273))
  (arc (start 208.79 78.496584) (mid 208.966777 78.423361) (end 209.04 78.246584) (width 0.146) (layer "In5.Cu") (net 273))
  (arc (start 203.54 78.246584) (mid 203.613223 78.423361) (end 203.79 78.496584) (width 0.146) (layer "In5.Cu") (net 273))
  (arc (start 211.29 77.303416) (mid 211.466777 77.376639) (end 211.54 77.553416) (width 0.146) (layer "In5.Cu") (net 273))
  (arc (start 211.04 77.553416) (mid 211.113223 77.376639) (end 211.29 77.303416) (width 0.146) (layer "In5.Cu") (net 273))
  (arc (start 202.29 77.303416) (mid 202.466777 77.376639) (end 202.54 77.553416) (width 0.146) (layer "In5.Cu") (net 273))
  (arc (start 211.54 78.246584) (mid 211.613223 78.423361) (end 211.79 78.496584) (width 0.146) (layer "In5.Cu") (net 273))
  (arc (start 210.79 78.496584) (mid 210.966777 78.423361) (end 211.04 78.246584) (width 0.146) (layer "In5.Cu") (net 273))
  (arc (start 209.29 77.303416) (mid 209.466777 77.376639) (end 209.54 77.553416) (width 0.146) (layer "In5.Cu") (net 273))
  (arc (start 208.29 77.303416) (mid 208.466777 77.376639) (end 208.54 77.553416) (width 0.146) (layer "In5.Cu") (net 273))
  (arc (start 209.04 77.553416) (mid 209.113223 77.376639) (end 209.29 77.303416) (width 0.146) (layer "In5.Cu") (net 273))
  (arc (start 207.29 77.303416) (mid 207.466777 77.376639) (end 207.54 77.553416) (width 0.146) (layer "In5.Cu") (net 273))
  (arc (start 202.04 77.553416) (mid 202.113223 77.376639) (end 202.29 77.303416) (width 0.146) (layer "In5.Cu") (net 273))
  (arc (start 212.04 78.15) (mid 212.113223 77.973223) (end 212.29 77.9) (width 0.146) (layer "In5.Cu") (net 273))
  (arc (start 208.04 77.553416) (mid 208.113223 77.376639) (end 208.29 77.303416) (width 0.146) (layer "In5.Cu") (net 273))
  (arc (start 206.04 77.553416) (mid 206.113223 77.376639) (end 206.29 77.303416) (width 0.146) (layer "In5.Cu") (net 273))
  (arc (start 205.04 77.553416) (mid 205.113223 77.376639) (end 205.29 77.303416) (width 0.146) (layer "In5.Cu") (net 273))
  (arc (start 209.54 78.246584) (mid 209.613223 78.423361) (end 209.79 78.496584) (width 0.146) (layer "In5.Cu") (net 273))
  (arc (start 205.54 78.246584) (mid 205.613223 78.423361) (end 205.79 78.496584) (width 0.146) (layer "In5.Cu") (net 273))
  (arc (start 210.04 77.553416) (mid 210.113223 77.376639) (end 210.29 77.303416) (width 0.146) (layer "In5.Cu") (net 273))
  (arc (start 204.04 77.553416) (mid 204.113223 77.376639) (end 204.29 77.303416) (width 0.146) (layer "In5.Cu") (net 273))
  (arc (start 207.54 78.246584) (mid 207.613223 78.423361) (end 207.79 78.496584) (width 0.146) (layer "In5.Cu") (net 273))
  (arc (start 207.04 77.553416) (mid 207.113223 77.376639) (end 207.29 77.303416) (width 0.146) (layer "In5.Cu") (net 273))
  (arc (start 211.79 78.496584) (mid 211.966777 78.423361) (end 212.04 78.246584) (width 0.146) (layer "In5.Cu") (net 273))
  (arc (start 201.79 77.9) (mid 201.966777 77.826777) (end 202.04 77.65) (width 0.146) (layer "In5.Cu") (net 273))
  (arc (start 205.79 78.496584) (mid 205.966777 78.423361) (end 206.04 78.246584) (width 0.146) (layer "In5.Cu") (net 273))
  (arc (start 205.29 77.303416) (mid 205.466777 77.376639) (end 205.54 77.553416) (width 0.146) (layer "In5.Cu") (net 273))
  (arc (start 203.04 77.553416) (mid 203.113223 77.376639) (end 203.29 77.303416) (width 0.146) (layer "In5.Cu") (net 273))
  (arc (start 204.54 78.246584) (mid 204.613223 78.423361) (end 204.79 78.496584) (width 0.146) (layer "In5.Cu") (net 273))
  (arc (start 210.29 77.303416) (mid 210.466777 77.376639) (end 210.54 77.553416) (width 0.146) (layer "In5.Cu") (net 273))
  (arc (start 202.54 78.246584) (mid 202.613223 78.423361) (end 202.79 78.496584) (width 0.146) (layer "In5.Cu") (net 273))
  (arc (start 207.79 78.496584) (mid 207.966777 78.423361) (end 208.04 78.246584) (width 0.146) (layer "In5.Cu") (net 273))
  (arc (start 203.79 78.496584) (mid 203.966777 78.423361) (end 204.04 78.246584) (width 0.146) (layer "In5.Cu") (net 273))
  (arc (start 209.79 78.496584) (mid 209.966777 78.423361) (end 210.04 78.246584) (width 0.146) (layer "In5.Cu") (net 273))
  (segment (start 227.086328 59.660008) (end 227.086328 60.960008) (width 0.2) (layer "F.Cu") (net 274))
  (segment (start 193.136328 80.560008) (end 193.145828 80.560008) (width 0.127) (layer "F.Cu") (net 274))
  (segment (start 193.145828 80.560008) (end 193.655836 80.05) (width 0.127) (layer "F.Cu") (net 274))
  (via blind (at 227.086328 60.960008) (size 0.5) (drill 0.2) (layers "F.Cu" "In5.Cu") (net 274))
  (via blind (at 193.655836 80.05) (size 0.5) (drill 0.2) (layers "F.Cu" "In5.Cu") (net 274))
  (segment (start 202.45 75.359226) (end 202.45 76.240774) (width 0.146) (layer "In5.Cu") (net 274))
  (segment (start 203.95 76.240774) (end 203.95 75.359226) (width 0.146) (layer "In5.Cu") (net 274))
  (segment (start 210.45 75.359226) (end 210.45 76.240774) (width 0.146) (layer "In5.Cu") (net 274))
  (segment (start 206.45 75.359226) (end 206.45 76.240774) (width 0.146) (layer "In5.Cu") (net 274))
  (segment (start 196.94 78.61) (end 195.99 79.56) (width 0.09) (layer "In5.Cu") (net 274))
  (segment (start 194.145836 79.56) (end 193.655836 80.05) (width 0.09) (layer "In5.Cu") (net 274))
  (segment (start 206.95 76.240774) (end 206.95 75.359226) (width 0.146) (layer "In5.Cu") (net 274))
  (segment (start 198.89 78.61) (end 201.7 75.8) (width 0.146) (layer "In5.Cu") (net 274))
  (segment (start 209.95 76.240774) (end 209.95 75.359226) (width 0.146) (layer "In5.Cu") (net 274))
  (segment (start 207.45 75.359226) (end 207.45 76.240774) (width 0.146) (layer "In5.Cu") (net 274))
  (segment (start 198.11 78.61) (end 198.89 78.61) (width 0.146) (layer "In5.Cu") (net 274))
  (segment (start 208.95 76.240774) (end 208.95 75.359226) (width 0.146) (layer "In5.Cu") (net 274))
  (segment (start 204.45 75.359226) (end 204.45 76.240774) (width 0.146) (layer "In5.Cu") (net 274))
  (segment (start 201.95 75.55) (end 201.95 75.359226) (width 0.146) (layer "In5.Cu") (net 274))
  (segment (start 207.95 76.240774) (end 207.95 75.359226) (width 0.146) (layer "In5.Cu") (net 274))
  (segment (start 202.95 76.240774) (end 202.95 75.359226) (width 0.146) (layer "In5.Cu") (net 274))
  (segment (start 209.45 75.359226) (end 209.45 76.240774) (width 0.146) (layer "In5.Cu") (net 274))
  (segment (start 195.99 79.56) (end 194.145836 79.56) (width 0.09) (layer "In5.Cu") (net 274))
  (segment (start 203.45 75.359226) (end 203.45 76.240774) (width 0.146) (layer "In5.Cu") (net 274))
  (segment (start 208.45 75.359226) (end 208.45 76.240774) (width 0.146) (layer "In5.Cu") (net 274))
  (segment (start 210.95 76.240774) (end 210.95 76.05) (width 0.146) (layer "In5.Cu") (net 274))
  (segment (start 226.339992 60.960008) (end 227.086328 60.960008) (width 0.146) (layer "In5.Cu") (net 274))
  (segment (start 198.11 78.61) (end 196.94 78.61) (width 0.09) (layer "In5.Cu") (net 274))
  (segment (start 211.5 75.8) (end 226.339992 60.960008) (width 0.146) (layer "In5.Cu") (net 274))
  (segment (start 205.95 76.240774) (end 205.95 75.359226) (width 0.146) (layer "In5.Cu") (net 274))
  (segment (start 205.45 75.359226) (end 205.45 76.240774) (width 0.146) (layer "In5.Cu") (net 274))
  (segment (start 204.95 76.240774) (end 204.95 75.359226) (width 0.146) (layer "In5.Cu") (net 274))
  (segment (start 211.2 75.8) (end 211.5 75.8) (width 0.146) (layer "In5.Cu") (net 274))
  (arc (start 207.95 75.359226) (mid 208.023223 75.182449) (end 208.2 75.109226) (width 0.146) (layer "In5.Cu") (net 274))
  (arc (start 204.45 76.240774) (mid 204.523223 76.417551) (end 204.7 76.490774) (width 0.146) (layer "In5.Cu") (net 274))
  (arc (start 204.95 75.359226) (mid 205.023223 75.182449) (end 205.2 75.109226) (width 0.146) (layer "In5.Cu") (net 274))
  (arc (start 205.45 76.240774) (mid 205.523223 76.417551) (end 205.7 76.490774) (width 0.146) (layer "In5.Cu") (net 274))
  (arc (start 205.95 75.359226) (mid 206.023223 75.182449) (end 206.2 75.109226) (width 0.146) (layer "In5.Cu") (net 274))
  (arc (start 210.95 76.05) (mid 211.023223 75.873223) (end 211.2 75.8) (width 0.146) (layer "In5.Cu") (net 274))
  (arc (start 206.2 75.109226) (mid 206.376777 75.182449) (end 206.45 75.359226) (width 0.146) (layer "In5.Cu") (net 274))
  (arc (start 210.2 75.109226) (mid 210.376777 75.182449) (end 210.45 75.359226) (width 0.146) (layer "In5.Cu") (net 274))
  (arc (start 209.95 75.359226) (mid 210.023223 75.182449) (end 210.2 75.109226) (width 0.146) (layer "In5.Cu") (net 274))
  (arc (start 202.45 76.240774) (mid 202.523223 76.417551) (end 202.7 76.490774) (width 0.146) (layer "In5.Cu") (net 274))
  (arc (start 205.7 76.490774) (mid 205.876777 76.417551) (end 205.95 76.240774) (width 0.146) (layer "In5.Cu") (net 274))
  (arc (start 201.7 75.8) (mid 201.876777 75.726777) (end 201.95 75.55) (width 0.146) (layer "In5.Cu") (net 274))
  (arc (start 208.7 76.490774) (mid 208.876777 76.417551) (end 208.95 76.240774) (width 0.146) (layer "In5.Cu") (net 274))
  (arc (start 203.95 75.359226) (mid 204.023223 75.182449) (end 204.2 75.109226) (width 0.146) (layer "In5.Cu") (net 274))
  (arc (start 207.7 76.490774) (mid 207.876777 76.417551) (end 207.95 76.240774) (width 0.146) (layer "In5.Cu") (net 274))
  (arc (start 209.45 76.240774) (mid 209.523223 76.417551) (end 209.7 76.490774) (width 0.146) (layer "In5.Cu") (net 274))
  (arc (start 206.7 76.490774) (mid 206.876777 76.417551) (end 206.95 76.240774) (width 0.146) (layer "In5.Cu") (net 274))
  (arc (start 210.7 76.490774) (mid 210.876777 76.417551) (end 210.95 76.240774) (width 0.146) (layer "In5.Cu") (net 274))
  (arc (start 205.2 75.109226) (mid 205.376777 75.182449) (end 205.45 75.359226) (width 0.146) (layer "In5.Cu") (net 274))
  (arc (start 208.95 75.359226) (mid 209.023223 75.182449) (end 209.2 75.109226) (width 0.146) (layer "In5.Cu") (net 274))
  (arc (start 204.2 75.109226) (mid 204.376777 75.182449) (end 204.45 75.359226) (width 0.146) (layer "In5.Cu") (net 274))
  (arc (start 210.45 76.240774) (mid 210.523223 76.417551) (end 210.7 76.490774) (width 0.146) (layer "In5.Cu") (net 274))
  (arc (start 206.45 76.240774) (mid 206.523223 76.417551) (end 206.7 76.490774) (width 0.146) (layer "In5.Cu") (net 274))
  (arc (start 207.2 75.109226) (mid 207.376777 75.182449) (end 207.45 75.359226) (width 0.146) (layer "In5.Cu") (net 274))
  (arc (start 203.2 75.109226) (mid 203.376777 75.182449) (end 203.45 75.359226) (width 0.146) (layer "In5.Cu") (net 274))
  (arc (start 209.7 76.490774) (mid 209.876777 76.417551) (end 209.95 76.240774) (width 0.146) (layer "In5.Cu") (net 274))
  (arc (start 202.95 75.359226) (mid 203.023223 75.182449) (end 203.2 75.109226) (width 0.146) (layer "In5.Cu") (net 274))
  (arc (start 207.45 76.240774) (mid 207.523223 76.417551) (end 207.7 76.490774) (width 0.146) (layer "In5.Cu") (net 274))
  (arc (start 208.2 75.109226) (mid 208.376777 75.182449) (end 208.45 75.359226) (width 0.146) (layer "In5.Cu") (net 274))
  (arc (start 204.7 76.490774) (mid 204.876777 76.417551) (end 204.95 76.240774) (width 0.146) (layer "In5.Cu") (net 274))
  (arc (start 209.2 75.109226) (mid 209.376777 75.182449) (end 209.45 75.359226) (width 0.146) (layer "In5.Cu") (net 274))
  (arc (start 202.2 75.109226) (mid 202.376777 75.182449) (end 202.45 75.359226) (width 0.146) (layer "In5.Cu") (net 274))
  (arc (start 203.45 76.240774) (mid 203.523223 76.417551) (end 203.7 76.490774) (width 0.146) (layer "In5.Cu") (net 274))
  (arc (start 201.95 75.359226) (mid 202.023223 75.182449) (end 202.2 75.109226) (width 0.146) (layer "In5.Cu") (net 274))
  (arc (start 208.45 76.240774) (mid 208.523223 76.417551) (end 208.7 76.490774) (width 0.146) (layer "In5.Cu") (net 274))
  (arc (start 203.7 76.490774) (mid 203.876777 76.417551) (end 203.95 76.240774) (width 0.146) (layer "In5.Cu") (net 274))
  (arc (start 206.95 75.359226) (mid 207.023223 75.182449) (end 207.2 75.109226) (width 0.146) (layer "In5.Cu") (net 274))
  (arc (start 202.7 76.490774) (mid 202.876777 76.417551) (end 202.95 76.240774) (width 0.146) (layer "In5.Cu") (net 274))
  (segment (start 234.736328 59.660008) (end 234.736328 60.960008) (width 0.2) (layer "F.Cu") (net 275))
  (segment (start 193.636328 85.060008) (end 193.655836 85.060008) (width 0.127) (layer "F.Cu") (net 275))
  (segment (start 193.136328 85.560008) (end 193.636328 85.060008) (width 0.127) (layer "F.Cu") (net 275))
  (via blind (at 193.655836 85.060008) (size 0.5) (drill 0.2) (layers "F.Cu" "In5.Cu") (net 275))
  (via blind (at 234.736328 60.960008) (size 0.5) (drill 0.2) (layers "F.Cu" "In5.Cu") (net 275))
  (segment (start 206.06 85.990112) (end 206.06 85.409888) (width 0.146) (layer "In5.Cu") (net 275))
  (segment (start 207.56 85.409888) (end 207.56 85.990112) (width 0.146) (layer "In5.Cu") (net 275))
  (segment (start 208.06 85.990112) (end 208.06 85.409888) (width 0.146) (layer "In5.Cu") (net 275))
  (segment (start 210.31 85.7) (end 215.3 85.7) (width 0.146) (layer "In5.Cu") (net 275))
  (segment (start 204.56 85.45) (end 204.56 85.990112) (width 0.146) (layer "In5.Cu") (net 275))
  (segment (start 193.655836 85.060008) (end 193.655836 85.646907) (width 0.09) (layer "In5.Cu") (net 275))
  (segment (start 197.407992 86.512008) (end 197.75 86.17) (width 0.09) (layer "In5.Cu") (net 275))
  (segment (start 209.06 85.990112) (end 209.06 85.409888) (width 0.146) (layer "In5.Cu") (net 275))
  (segment (start 210.06 85.990112) (end 210.06 85.95) (width 0.146) (layer "In5.Cu") (net 275))
  (segment (start 205.06 85.990112) (end 205.06 85.409888) (width 0.146) (layer "In5.Cu") (net 275))
  (segment (start 207.06 85.990112) (end 207.06 85.409888) (width 0.146) (layer "In5.Cu") (net 275))
  (segment (start 203.6 85.7) (end 203.81 85.7) (width 0.146) (layer "In5.Cu") (net 275))
  (segment (start 194.520937 86.512008) (end 197.407992 86.512008) (width 0.09) (layer "In5.Cu") (net 275))
  (segment (start 205.56 85.409888) (end 205.56 85.990112) (width 0.146) (layer "In5.Cu") (net 275))
  (segment (start 209.56 85.409888) (end 209.56 85.990112) (width 0.146) (layer "In5.Cu") (net 275))
  (segment (start 197.75 86.17) (end 198.14 86.17) (width 0.09) (layer "In5.Cu") (net 275))
  (segment (start 198.14 86.17) (end 203.13 86.17) (width 0.146) (layer "In5.Cu") (net 275))
  (segment (start 208.56 85.409888) (end 208.56 85.990112) (width 0.146) (layer "In5.Cu") (net 275))
  (segment (start 204.56 85.409888) (end 204.56 85.45) (width 0.146) (layer "In5.Cu") (net 275))
  (segment (start 206.56 85.409888) (end 206.56 85.990112) (width 0.146) (layer "In5.Cu") (net 275))
  (segment (start 204.06 85.45) (end 204.06 85.409888) (width 0.146) (layer "In5.Cu") (net 275))
  (segment (start 203.13 86.17) (end 203.6 85.7) (width 0.146) (layer "In5.Cu") (net 275))
  (segment (start 215.3 85.7) (end 234.736328 66.263672) (width 0.146) (layer "In5.Cu") (net 275))
  (segment (start 234.736328 66.263672) (end 234.736328 60.960008) (width 0.146) (layer "In5.Cu") (net 275))
  (segment (start 193.655836 85.646907) (end 194.520937 86.512008) (width 0.09) (layer "In5.Cu") (net 275))
  (arc (start 205.31 85.159888) (mid 205.486777 85.233111) (end 205.56 85.409888) (width 0.146) (layer "In5.Cu") (net 275))
  (arc (start 208.56 85.990112) (mid 208.633223 86.166889) (end 208.81 86.240112) (width 0.146) (layer "In5.Cu") (net 275))
  (arc (start 206.31 85.159888) (mid 206.486777 85.233111) (end 206.56 85.409888) (width 0.146) (layer "In5.Cu") (net 275))
  (arc (start 206.06 85.409888) (mid 206.133223 85.233111) (end 206.31 85.159888) (width 0.146) (layer "In5.Cu") (net 275))
  (arc (start 205.81 86.240112) (mid 205.986777 86.166889) (end 206.06 85.990112) (width 0.146) (layer "In5.Cu") (net 275))
  (arc (start 210.06 85.95) (mid 210.133223 85.773223) (end 210.31 85.7) (width 0.146) (layer "In5.Cu") (net 275))
  (arc (start 209.56 85.990112) (mid 209.633223 86.166889) (end 209.81 86.240112) (width 0.146) (layer "In5.Cu") (net 275))
  (arc (start 209.31 85.159888) (mid 209.486777 85.233111) (end 209.56 85.409888) (width 0.146) (layer "In5.Cu") (net 275))
  (arc (start 209.06 85.409888) (mid 209.133223 85.233111) (end 209.31 85.159888) (width 0.146) (layer "In5.Cu") (net 275))
  (arc (start 203.81 85.7) (mid 203.986777 85.626777) (end 204.06 85.45) (width 0.146) (layer "In5.Cu") (net 275))
  (arc (start 206.81 86.240112) (mid 206.986777 86.166889) (end 207.06 85.990112) (width 0.146) (layer "In5.Cu") (net 275))
  (arc (start 204.06 85.409888) (mid 204.133223 85.233111) (end 204.31 85.159888) (width 0.146) (layer "In5.Cu") (net 275))
  (arc (start 205.56 85.990112) (mid 205.633223 86.166889) (end 205.81 86.240112) (width 0.146) (layer "In5.Cu") (net 275))
  (arc (start 205.06 85.409888) (mid 205.133223 85.233111) (end 205.31 85.159888) (width 0.146) (layer "In5.Cu") (net 275))
  (arc (start 204.81 86.240112) (mid 204.986777 86.166889) (end 205.06 85.990112) (width 0.146) (layer "In5.Cu") (net 275))
  (arc (start 207.31 85.159888) (mid 207.486777 85.233111) (end 207.56 85.409888) (width 0.146) (layer "In5.Cu") (net 275))
  (arc (start 207.81 86.240112) (mid 207.986777 86.166889) (end 208.06 85.990112) (width 0.146) (layer "In5.Cu") (net 275))
  (arc (start 208.81 86.240112) (mid 208.986777 86.166889) (end 209.06 85.990112) (width 0.146) (layer "In5.Cu") (net 275))
  (arc (start 208.06 85.409888) (mid 208.133223 85.233111) (end 208.31 85.159888) (width 0.146) (layer "In5.Cu") (net 275))
  (arc (start 209.81 86.240112) (mid 209.986777 86.166889) (end 210.06 85.990112) (width 0.146) (layer "In5.Cu") (net 275))
  (arc (start 204.56 85.990112) (mid 204.633223 86.166889) (end 204.81 86.240112) (width 0.146) (layer "In5.Cu") (net 275))
  (arc (start 207.56 85.990112) (mid 207.633223 86.166889) (end 207.81 86.240112) (width 0.146) (layer "In5.Cu") (net 275))
  (arc (start 208.31 85.159888) (mid 208.486777 85.233111) (end 208.56 85.409888) (width 0.146) (layer "In5.Cu") (net 275))
  (arc (start 206.56 85.990112) (mid 206.633223 86.166889) (end 206.81 86.240112) (width 0.146) (layer "In5.Cu") (net 275))
  (arc (start 207.06 85.409888) (mid 207.133223 85.233111) (end 207.31 85.159888) (width 0.146) (layer "In5.Cu") (net 275))
  (arc (start 204.31 85.159888) (mid 204.486777 85.233111) (end 204.56 85.409888) (width 0.146) (layer "In5.Cu") (net 275))
  (segment (start 188.645336 79.051) (end 188.136328 79.560008) (width 0.127) (layer "F.Cu") (net 276))
  (segment (start 188.675 79.051) (end 188.645336 79.051) (width 0.127) (layer "F.Cu") (net 276))
  (segment (start 188.836328 59.660008) (end 188.836328 60.960008) (width 0.2) (layer "F.Cu") (net 276))
  (via (at 188.675 79.051) (size 0.5) (drill 0.2) (layers "F.Cu" "B.Cu") (net 276))
  (via (at 188.836328 60.960008) (size 0.5) (drill 0.2) (layers "F.Cu" "B.Cu") (net 276))
  (segment (start 190.35 76.3) (end 192.1 76.3) (width 0.1) (layer "In9.Cu") (net 276))
  (segment (start 192.3 74) (end 192.1 74) (width 0.16) (layer "In9.Cu") (net 276))
  (segment (start 194.275 67.475) (end 193.525 67.475) (width 0.16) (layer "In9.Cu") (net 276))
  (segment (start 192.2 65.05) (end 192.5 65.05) (width 0.16) (layer "In9.Cu") (net 276))
  (segment (start 189.554992 63.038751) (end 189.554992 63.03875) (width 0.16) (layer "In9.Cu") (net 276))
  (segment (start 190.270127 64.586368) (end 190.686371 64.17013) (width 0.16) (layer "In9.Cu") (net 276))
  (segment (start 193.471721 65.464058) (end 192.914058 66.021721) (width 0.16) (layer "In9.Cu") (net 276))
  (segment (start 190.902515 64.519672) (end 190.902514 64.519672) (width 0.16) (layer "In9.Cu") (net 276))
  (segment (start 190.403524 63.887283) (end 189.987284 64.303525) (width 0.16) (layer "In9.Cu") (net 276))
  (segment (start 193.525 67.925) (end 194.275 67.925) (width 0.16) (layer "In9.Cu") (net 276))
  (segment (start 193.9 66.167157) (end 193.899999 66.167157) (width 0.16) (layer "In9.Cu") (net 276))
  (segment (start 189.987284 64.303525) (end 189.987284 64.303526) (width 0.16) (layer "In9.Cu") (net 276))
  (segment (start 190.969214 64.17013) (end 190.969213 64.170129) (width 0.16) (layer "In9.Cu") (net 276))
  (segment (start 188.675 79.051) (end 188.675 78.673142) (width 0.1) (layer "In9.Cu") (net 276))
  (segment (start 189.421595 63.737836) (end 189.421595 63.737837) (width 0.16) (layer "In9.Cu") (net 276))
  (segment (start 192.5 75.4) (end 192.5 75.6) (width 0.16) (layer "In9.Cu") (net 276))
  (segment (start 190.686371 64.17013) (end 190.686371 64.170129) (width 0.16) (layer "In9.Cu") (net 276))
  (segment (start 188.836328 60.960008) (end 188.836328 62.736328) (width 0.16) (layer "In9.Cu") (net 276))
  (segment (start 194.037409 66.029747) (end 193.9 66.167157) (width 0.16) (layer "In9.Cu") (net 276))
  (segment (start 194.275 68.375) (end 194.125 68.375) (width 0.16) (layer "In9.Cu") (net 276))
  (segment (start 190.902515 64.802515) (end 191.15 65.05) (width 0.16) (layer "In9.Cu") (net 276))
  (segment (start 192.9 74.8) (end 192.1 74.8) (width 0.16) (layer "In9.Cu") (net 276))
  (segment (start 192.1 74.4) (end 192.9 74.4) (width 0.16) (layer "In9.Cu") (net 276))
  (segment (start 192.1 75.2) (end 192.3 75.2) (width 0.16) (layer "In9.Cu") (net 276))
  (segment (start 190.969214 64.452972) (end 190.902515 64.519672) (width 0.16) (layer "In9.Cu") (net 276))
  (segment (start 189.837835 63.321594) (end 189.421595 63.737836) (width 0.16) (layer "In9.Cu") (net 276))
  (segment (start 188.235836 77.886038) (end 188.481866 77.640008) (width 0.1) (layer "In9.Cu") (net 276))
  (segment (start 189.837835 63.038751) (end 189.837835 63.038752) (width 0.16) (layer "In9.Cu") (net 276))
  (segment (start 189.704438 64.020679) (end 190.120681 63.60444) (width 0.16) (layer "In9.Cu") (net 276))
  (segment (start 188.836328 62.736328) (end 189.205449 63.105449) (width 0.16) (layer "In9.Cu") (net 276))
  (segment (start 188.675 78.673142) (end 188.235836 78.233978) (width 0.1) (layer "In9.Cu") (net 276))
  (segment (start 190.403524 63.60444) (end 190.403524 63.604441) (width 0.16) (layer "In9.Cu") (net 276))
  (segment (start 188.235836 78.233978) (end 188.235836 77.886038) (width 0.1) (layer "In9.Cu") (net 276))
  (segment (start 192.5 65.05) (end 192.768625 65.318625) (width 0.16) (layer "In9.Cu") (net 276))
  (segment (start 193.9 66.45) (end 193.9 66.8) (width 0.16) (layer "In9.Cu") (net 276))
  (segment (start 193.471721 65.181215) (end 193.47172 65.181215) (width 0.16) (layer "In9.Cu") (net 276))
  (segment (start 192.5 73.4) (end 192.5 73.8) (width 0.16) (layer "In9.Cu") (net 276))
  (segment (start 192.1 76.3) (end 192.5 75.9) (width 0.1) (layer "In9.Cu") (net 276))
  (segment (start 192.5 75.9) (end 192.5 75.6) (width 0.1) (layer "In9.Cu") (net 276))
  (segment (start 190.120681 63.60444) (end 190.120681 63.604439) (width 0.16) (layer "In9.Cu") (net 276))
  (segment (start 192.15 65.05) (end 192.2 65.05) (width 0.16) (layer "In9.Cu") (net 276))
  (segment (start 193.051468 65.318624) (end 193.188878 65.181215) (width 0.16) (layer "In9.Cu") (net 276))
  (segment (start 193.754566 65.746904) (end 193.754566 65.746903) (width 0.16) (layer "In9.Cu") (net 276))
  (segment (start 189.009992 77.640008) (end 190.35 76.3) (width 0.1) (layer "In9.Cu") (net 276))
  (segment (start 193.188878 65.181215) (end 193.188878 65.181214) (width 0.16) (layer "In9.Cu") (net 276))
  (segment (start 188.481866 77.640008) (end 189.009992 77.640008) (width 0.1) (layer "In9.Cu") (net 276))
  (segment (start 194.037409 65.746904) (end 194.03741 65.746904) (width 0.16) (layer "In9.Cu") (net 276))
  (segment (start 192.914059 66.304565) (end 192.914058 66.304563) (width 0.16) (layer "In9.Cu") (net 276))
  (segment (start 189.421596 64.02068) (end 189.421596 64.020679) (width 0.16) (layer "In9.Cu") (net 276))
  (segment (start 193.196901 66.304564) (end 193.754566 65.746904) (width 0.16) (layer "In9.Cu") (net 276))
  (segment (start 193.9 68.6) (end 193.9 72) (width 0.16) (layer "In9.Cu") (net 276))
  (segment (start 191.95 64.71684) (end 191.95 64.85) (width 0.16) (layer "In9.Cu") (net 276))
  (segment (start 189.987285 64.586369) (end 189.987285 64.586368) (width 0.16) (layer "In9.Cu") (net 276))
  (segment (start 191.55 64.85) (end 191.55 64.71684) (width 0.16) (layer "In9.Cu") (net 276))
  (segment (start 189.488292 63.10545) (end 189.554992 63.038751) (width 0.16) (layer "In9.Cu") (net 276))
  (segment (start 193.9 72) (end 192.5 73.4) (width 0.16) (layer "In9.Cu") (net 276))
  (segment (start 191.15 65.05) (end 191.35 65.05) (width 0.16) (layer "In9.Cu") (net 276))
  (segment (start 192.914058 66.021721) (end 192.914058 66.021722) (width 0.16) (layer "In9.Cu") (net 276))
  (segment (start 194.125 67.025) (end 194.275 67.025) (width 0.16) (layer "In9.Cu") (net 276))
  (arc (start 190.686371 64.170129) (mid 190.827793 64.111551) (end 190.969214 64.17013) (width 0.16) (layer "In9.Cu") (net 276))
  (arc (start 192.1 74.8) (mid 191.958579 74.858579) (end 191.9 75) (width 0.16) (layer "In9.Cu") (net 276))
  (arc (start 190.902514 64.519672) (mid 190.843936 64.661094) (end 190.902515 64.802515) (width 0.16) (layer "In9.Cu") (net 276))
  (arc (start 192.3 75.2) (mid 192.441421 75.258579) (end 192.5 75.4) (width 0.16) (layer "In9.Cu") (net 276))
  (arc (start 193.754566 65.746903) (mid 193.895988 65.688325) (end 194.037409 65.746904) (width 0.16) (layer "In9.Cu") (net 276))
  (arc (start 192.9 74.4) (mid 193.041421 74.458579) (end 193.1 74.6) (width 0.16) (layer "In9.Cu") (net 276))
  (arc (start 194.275 67.925) (mid 194.434099 67.990901) (end 194.5 68.15) (width 0.16) (layer "In9.Cu") (net 276))
  (arc (start 193.47172 65.181215) (mid 193.530299 65.322636) (end 193.471721 65.464058) (width 0.16) (layer "In9.Cu") (net 276))
  (arc (start 193.3 67.7) (mid 193.365901 67.859099) (end 193.525 67.925) (width 0.16) (layer "In9.Cu") (net 276))
  (arc (start 189.837835 63.038752) (mid 189.896413 63.180173) (end 189.837835 63.321594) (width 0.16) (layer "In9.Cu") (net 276))
  (arc (start 189.421595 63.737837) (mid 189.363017 63.879259) (end 189.421596 64.02068) (width 0.16) (layer "In9.Cu") (net 276))
  (arc (start 189.987285 64.586368) (mid 190.128707 64.644947) (end 190.270127 64.586368) (width 0.16) (layer "In9.Cu") (net 276))
  (arc (start 193.525 67.475) (mid 193.365901 67.540901) (end 193.3 67.7) (width 0.16) (layer "In9.Cu") (net 276))
  (arc (start 192.914058 66.304563) (mid 193.055479 66.363142) (end 193.196901 66.304564) (width 0.16) (layer "In9.Cu") (net 276))
  (arc (start 189.987284 64.303526) (mid 189.928706 64.444948) (end 189.987285 64.586369) (width 0.16) (layer "In9.Cu") (net 276))
  (arc (start 190.969213 64.170129) (mid 191.027792 64.31155) (end 190.969214 64.452972) (width 0.16) (layer "In9.Cu") (net 276))
  (arc (start 194.5 68.15) (mid 194.434099 68.309099) (end 194.275 68.375) (width 0.16) (layer "In9.Cu") (net 276))
  (arc (start 190.120681 63.604439) (mid 190.262103 63.545861) (end 190.403524 63.60444) (width 0.16) (layer "In9.Cu") (net 276))
  (arc (start 194.03741 65.746904) (mid 194.095988 65.888326) (end 194.037409 66.029747) (width 0.16) (layer "In9.Cu") (net 276))
  (arc (start 191.75 64.51684) (mid 191.891421 64.575419) (end 191.95 64.71684) (width 0.16) (layer "In9.Cu") (net 276))
  (arc (start 189.205449 63.105449) (mid 189.34687 63.164028) (end 189.488292 63.10545) (width 0.16) (layer "In9.Cu") (net 276))
  (arc (start 194.125 68.375) (mid 193.965901 68.440901) (end 193.9 68.6) (width 0.16) (layer "In9.Cu") (net 276))
  (arc (start 191.9 74.2) (mid 191.958579 74.341421) (end 192.1 74.4) (width 0.16) (layer "In9.Cu") (net 276))
  (arc (start 192.1 74) (mid 191.958579 74.058579) (end 191.9 74.2) (width 0.16) (layer "In9.Cu") (net 276))
  (arc (start 193.899999 66.167157) (mid 193.841421 66.308579) (end 193.9 66.45) (width 0.16) (layer "In9.Cu") (net 276))
  (arc (start 191.95 64.85) (mid 192.008579 64.991421) (end 192.15 65.05) (width 0.16) (layer "In9.Cu") (net 276))
  (arc (start 193.188878 65.181214) (mid 193.3303 65.122636) (end 193.471721 65.181215) (width 0.16) (layer "In9.Cu") (net 276))
  (arc (start 189.421596 64.020679) (mid 189.563018 64.079258) (end 189.704438 64.020679) (width 0.16) (layer "In9.Cu") (net 276))
  (arc (start 194.275 67.025) (mid 194.434099 67.090901) (end 194.5 67.25) (width 0.16) (layer "In9.Cu") (net 276))
  (arc (start 191.55 64.71684) (mid 191.608579 64.575419) (end 191.75 64.51684) (width 0.16) (layer "In9.Cu") (net 276))
  (arc (start 189.554992 63.03875) (mid 189.696414 62.980172) (end 189.837835 63.038751) (width 0.16) (layer "In9.Cu") (net 276))
  (arc (start 192.5 73.8) (mid 192.441421 73.941421) (end 192.3 74) (width 0.16) (layer "In9.Cu") (net 276))
  (arc (start 190.403524 63.604441) (mid 190.462102 63.745862) (end 190.403524 63.887283) (width 0.16) (layer "In9.Cu") (net 276))
  (arc (start 194.5 67.25) (mid 194.434099 67.409099) (end 194.275 67.475) (width 0.16) (layer "In9.Cu") (net 276))
  (arc (start 191.9 75) (mid 191.958579 75.141421) (end 192.1 75.2) (width 0.16) (layer "In9.Cu") (net 276))
  (arc (start 193.9 66.8) (mid 193.965901 66.959099) (end 194.125 67.025) (width 0.16) (layer "In9.Cu") (net 276))
  (arc (start 192.914058 66.021722) (mid 192.85548 66.163144) (end 192.914059 66.304565) (width 0.16) (layer "In9.Cu") (net 276))
  (arc (start 193.1 74.6) (mid 193.041421 74.741421) (end 192.9 74.8) (width 0.16) (layer "In9.Cu") (net 276))
  (arc (start 191.35 65.05) (mid 191.491421 64.991421) (end 191.55 64.85) (width 0.16) (layer "In9.Cu") (net 276))
  (arc (start 192.768625 65.318625) (mid 192.910047 65.377203) (end 193.051468 65.318624) (width 0.16) (layer "In9.Cu") (net 276))
  (segment (start 196.636328 79.060008) (end 196.655836 79.060008) (width 0.127) (layer "F.Cu") (net 277))
  (segment (start 219.436328 59.660008) (end 219.436328 60.960008) (width 0.2) (layer "F.Cu") (net 277))
  (segment (start 196.136328 79.560008) (end 196.636328 79.060008) (width 0.127) (layer "F.Cu") (net 277))
  (via blind (at 219.436328 60.960008) (size 0.5) (drill 0.2) (layers "F.Cu" "In2.Cu") (net 277))
  (via blind (at 196.655836 79.060008) (size 0.5) (drill 0.2) (layers "F.Cu" "In2.Cu") (net 277))
  (segment (start 198.2 79.060008) (end 199.9 79.060008) (width 0.16) (layer "In2.Cu") (net 277))
  (segment (start 207.681984 75.448344) (end 207.681984 75.448345) (width 0.16) (layer "In2.Cu") (net 277))
  (segment (start 213.501698 69.545881) (end 213.501698 69.545882) (width 0.16) (layer "In2.Cu") (net 277))
  (segment (start 204.818199 76.862563) (end 204.818198 76.862564) (width 0.16) (layer "In2.Cu") (net 277))
  (segment (start 207.611273 74.988725) (end 210.749999 71.849999) (width 0.16) (layer "In2.Cu") (net 277))
  (segment (start 211.109572 71.042846) (end 211.109572 71.042847) (width 0.16) (layer "In2.Cu") (net 277))
  (segment (start 213.501698 69.545882) (end 213.47236 69.516544) (width 0.16) (layer "In2.Cu") (net 277))
  (segment (start 206.762746 75.306926) (end 206.762746 75.306925) (width 0.16) (layer "In2.Cu") (net 277))
  (segment (start 211.946062 71.101518) (end 211.49848 70.653936) (width 0.16) (layer "In2.Cu") (net 277))
  (segment (start 205.348527 77.781801) (end 204.818198 77.251472) (width 0.16) (layer "In2.Cu") (net 277))
  (segment (start 206.904165 76.226163) (end 206.904165 76.226164) (width 0.16) (layer "In2.Cu") (net 277))
  (segment (start 210.749999 71.461091) (end 210.720662 71.431754) (width 0.16) (layer "In2.Cu") (net 277))
  (segment (start 200.660008 78.3) (end 204.3 78.3) (width 0.16) (layer "In2.Cu") (net 277))
  (segment (start 205.207108 76.862563) (end 205.737438 77.392892) (width 0.16) (layer "In2.Cu") (net 277))
  (segment (start 207.611272 74.988725) (end 207.611273 74.988725) (width 0.16) (layer "In2.Cu") (net 277))
  (segment (start 212.72388 70.3237) (end 212.276298 69.876118) (width 0.16) (layer "In2.Cu") (net 277))
  (segment (start 219.436328 63.163672) (end 219.436328 60.960008) (width 0.16) (layer "In2.Cu") (net 277))
  (segment (start 213.472361 69.127635) (end 213.47236 69.127636) (width 0.16) (layer "In2.Cu") (net 277))
  (segment (start 205.984927 76.084745) (end 205.984927 76.084744) (width 0.16) (layer "In2.Cu") (net 277))
  (segment (start 213.501697 69.934791) (end 213.501698 69.934791) (width 0.16) (layer "In2.Cu") (net 277))
  (segment (start 196.655836 79.060008) (end 198.2 79.060008) (width 0.1) (layer "In2.Cu") (net 277))
  (segment (start 210.720663 71.042845) (end 210.720662 71.042846) (width 0.16) (layer "In2.Cu") (net 277))
  (segment (start 212.665207 69.487209) (end 213.112789 69.934791) (width 0.16) (layer "In2.Cu") (net 277))
  (segment (start 207.681984 75.448345) (end 207.611273 75.377634) (width 0.16) (layer "In2.Cu") (net 277))
  (segment (start 206.126346 77.003982) (end 206.126346 77.003983) (width 0.16) (layer "In2.Cu") (net 277))
  (segment (start 211.946062 71.101517) (end 211.946062 71.101518) (width 0.16) (layer "In2.Cu") (net 277))
  (segment (start 204.888908 78.1) (end 204.959618 78.17071) (width 0.16) (layer "In2.Cu") (net 277))
  (segment (start 212.723879 70.712609) (end 212.72388 70.712609) (width 0.16) (layer "In2.Cu") (net 277))
  (segment (start 205.596018 76.084744) (end 205.596017 76.084745) (width 0.16) (layer "In2.Cu") (net 277))
  (segment (start 211.887389 70.265027) (end 212.334971 70.712609) (width 0.16) (layer "In2.Cu") (net 277))
  (segment (start 213.47236 69.127636) (end 219.436328 63.163672) (width 0.16) (layer "In2.Cu") (net 277))
  (segment (start 211.109572 71.042847) (end 211.557153 71.490427) (width 0.16) (layer "In2.Cu") (net 277))
  (segment (start 205.348527 78.170711) (end 205.348527 78.17071) (width 0.16) (layer "In2.Cu") (net 277))
  (segment (start 206.126346 77.003983) (end 205.596017 76.473653) (width 0.16) (layer "In2.Cu") (net 277))
  (segment (start 206.126347 77.392891) (end 206.126346 77.392892) (width 0.16) (layer "In2.Cu") (net 277))
  (segment (start 205.984927 76.084744) (end 206.515257 76.615073) (width 0.16) (layer "In2.Cu") (net 277))
  (segment (start 212.665209 69.48721) (end 212.665207 69.487209) (width 0.16) (layer "In2.Cu") (net 277))
  (segment (start 212.276298 69.48721) (end 212.276299 69.487208) (width 0.16) (layer "In2.Cu") (net 277))
  (segment (start 207.681985 75.837253) (end 207.681984 75.837254) (width 0.16) (layer "In2.Cu") (net 277))
  (segment (start 211.49848 70.265028) (end 211.498481 70.265026) (width 0.16) (layer "In2.Cu") (net 277))
  (segment (start 205.207108 76.862564) (end 205.207108 76.862563) (width 0.16) (layer "In2.Cu") (net 277))
  (segment (start 205.348527 77.7818) (end 205.348527 77.781801) (width 0.16) (layer "In2.Cu") (net 277))
  (segment (start 206.762746 75.306925) (end 207.293076 75.837254) (width 0.16) (layer "In2.Cu") (net 277))
  (segment (start 206.904166 76.615072) (end 206.904165 76.615073) (width 0.16) (layer "In2.Cu") (net 277))
  (segment (start 206.373837 75.306925) (end 206.373836 75.306926) (width 0.16) (layer "In2.Cu") (net 277))
  (segment (start 206.904165 76.226164) (end 206.373836 75.695834) (width 0.16) (layer "In2.Cu") (net 277))
  (segment (start 212.72388 70.323699) (end 212.72388 70.3237) (width 0.16) (layer "In2.Cu") (net 277))
  (segment (start 204.3 78.3) (end 204.5 78.1) (width 0.16) (layer "In2.Cu") (net 277))
  (segment (start 199.9 79.060008) (end 200.660008 78.3) (width 0.16) (layer "In2.Cu") (net 277))
  (segment (start 211.946061 71.490427) (end 211.946062 71.490427) (width 0.16) (layer "In2.Cu") (net 277))
  (segment (start 211.887391 70.265028) (end 211.887389 70.265027) (width 0.16) (layer "In2.Cu") (net 277))
  (arc (start 206.515257 76.615073) (mid 206.709712 76.695618) (end 206.904166 76.615072) (width 0.16) (layer "In2.Cu") (net 277))
  (arc (start 212.276298 69.876118) (mid 212.195754 69.681663) (end 212.276298 69.48721) (width 0.16) (layer "In2.Cu") (net 277))
  (arc (start 211.946062 71.490427) (mid 212.026608 71.295972) (end 211.946062 71.101517) (width 0.16) (layer "In2.Cu") (net 277))
  (arc (start 213.47236 69.516544) (mid 213.391815 69.322089) (end 213.472361 69.127635) (width 0.16) (layer "In2.Cu") (net 277))
  (arc (start 213.112789 69.934791) (mid 213.307243 70.015336) (end 213.501697 69.934791) (width 0.16) (layer "In2.Cu") (net 277))
  (arc (start 211.557153 71.490427) (mid 211.751607 71.570972) (end 211.946061 71.490427) (width 0.16) (layer "In2.Cu") (net 277))
  (arc (start 204.818198 77.251472) (mid 204.737653 77.057017) (end 204.818199 76.862563) (width 0.16) (layer "In2.Cu") (net 277))
  (arc (start 207.293076 75.837254) (mid 207.487531 75.917799) (end 207.681985 75.837253) (width 0.16) (layer "In2.Cu") (net 277))
  (arc (start 205.348527 78.17071) (mid 205.429073 77.976255) (end 205.348527 77.7818) (width 0.16) (layer "In2.Cu") (net 277))
  (arc (start 207.611273 75.377634) (mid 207.530727 75.18318) (end 207.611272 74.988725) (width 0.16) (layer "In2.Cu") (net 277))
  (arc (start 210.749999 71.849999) (mid 210.830545 71.655546) (end 210.749999 71.461091) (width 0.16) (layer "In2.Cu") (net 277))
  (arc (start 213.501698 69.934791) (mid 213.582244 69.740336) (end 213.501698 69.545881) (width 0.16) (layer "In2.Cu") (net 277))
  (arc (start 212.276299 69.487208) (mid 212.470753 69.406663) (end 212.665209 69.48721) (width 0.16) (layer "In2.Cu") (net 277))
  (arc (start 206.373836 75.695834) (mid 206.293291 75.501379) (end 206.373837 75.306925) (width 0.16) (layer "In2.Cu") (net 277))
  (arc (start 205.737438 77.392892) (mid 205.931893 77.473437) (end 206.126347 77.392891) (width 0.16) (layer "In2.Cu") (net 277))
  (arc (start 204.818198 76.862564) (mid 205.012654 76.782017) (end 205.207108 76.862564) (width 0.16) (layer "In2.Cu") (net 277))
  (arc (start 211.498481 70.265026) (mid 211.692935 70.184481) (end 211.887391 70.265028) (width 0.16) (layer "In2.Cu") (net 277))
  (arc (start 211.49848 70.653936) (mid 211.417936 70.459481) (end 211.49848 70.265028) (width 0.16) (layer "In2.Cu") (net 277))
  (arc (start 206.904165 76.615073) (mid 206.984711 76.420618) (end 206.904165 76.226163) (width 0.16) (layer "In2.Cu") (net 277))
  (arc (start 210.720662 71.431754) (mid 210.640117 71.237299) (end 210.720663 71.042845) (width 0.16) (layer "In2.Cu") (net 277))
  (arc (start 204.959618 78.17071) (mid 205.154072 78.251256) (end 205.348527 78.170711) (width 0.16) (layer "In2.Cu") (net 277))
  (arc (start 212.334971 70.712609) (mid 212.529425 70.793154) (end 212.723879 70.712609) (width 0.16) (layer "In2.Cu") (net 277))
  (arc (start 205.596017 76.084745) (mid 205.790473 76.004198) (end 205.984927 76.084745) (width 0.16) (layer "In2.Cu") (net 277))
  (arc (start 206.126346 77.392892) (mid 206.206892 77.198437) (end 206.126346 77.003982) (width 0.16) (layer "In2.Cu") (net 277))
  (arc (start 212.72388 70.712609) (mid 212.804426 70.518154) (end 212.72388 70.323699) (width 0.16) (layer "In2.Cu") (net 277))
  (arc (start 205.596017 76.473653) (mid 205.515472 76.279198) (end 205.596018 76.084744) (width 0.16) (layer "In2.Cu") (net 277))
  (arc (start 206.373836 75.306926) (mid 206.568292 75.226379) (end 206.762746 75.306926) (width 0.16) (layer "In2.Cu") (net 277))
  (arc (start 204.5 78.1) (mid 204.694454 78.019455) (end 204.888908 78.1) (width 0.16) (layer "In2.Cu") (net 277))
  (arc (start 207.681984 75.837254) (mid 207.76253 75.642799) (end 207.681984 75.448344) (width 0.16) (layer "In2.Cu") (net 277))
  (arc (start 210.720662 71.042846) (mid 210.915118 70.962301) (end 211.109572 71.042846) (width 0.16) (layer "In2.Cu") (net 277))
  (segment (start 206.686328 59.660008) (end 206.686328 60.960008) (width 0.2) (layer "F.Cu") (net 278))
  (segment (start 181.136328 86.560008) (end 180.636328 86.060008) (width 0.127) (layer "F.Cu") (net 278))
  (via (at 206.686328 60.960008) (size 0.5) (drill 0.2) (layers "F.Cu" "B.Cu") (net 278))
  (via (at 180.636328 86.060008) (size 0.5) (drill 0.2) (layers "F.Cu" "B.Cu") (net 278))
  (segment (start 181.45 85.55) (end 181.95 85.55) (width 0.127) (layer "In7.Cu") (net 278))
  (segment (start 189.73 73.075709) (end 189.73 73.724291) (width 0.196) (layer "In7.Cu") (net 278))
  (segment (start 191.23 73.724291) (end 191.23 73.075709) (width 0.196) (layer "In7.Cu") (net 278))
  (segment (start 181.202828 85.797172) (end 181.45 85.55) (width 0.127) (layer "In7.Cu") (net 278))
  (segment (start 187.73 73.15) (end 187.73 73.724291) (width 0.196) (layer "In7.Cu") (net 278))
  (segment (start 181.83 75.59) (end 181.83 74.26) (width 0.196) (layer "In7.Cu") (net 278))
  (segment (start 181.95 85.55) (end 182.15 85.35) (width 0.127) (layer "In7.Cu") (net 278))
  (segment (start 188.23 73.724291) (end 188.23 73.075709) (width 0.196) (layer "In7.Cu") (net 278))
  (segment (start 192.73 73.075709) (end 192.73 73.15) (width 0.196) (layer "In7.Cu") (net 278))
  (segment (start 181.202828 85.897172) (end 181.202828 85.797172) (width 0.127) (layer "In7.Cu") (net 278))
  (segment (start 189.23 73.724291) (end 189.23 73.075709) (width 0.196) (layer "In7.Cu") (net 278))
  (segment (start 182.15 77.15) (end 181.83 76.83) (width 0.127) (layer "In7.Cu") (net 278))
  (segment (start 192.98 73.4) (end 200.84 73.4) (width 0.196) (layer "In7.Cu") (net 278))
  (segment (start 191.73 73.075709) (end 191.73 73.724291) (width 0.196) (layer "In7.Cu") (net 278))
  (segment (start 187.73 73.075709) (end 187.73 73.15) (width 0.196) (layer "In7.Cu") (net 278))
  (segment (start 206.686328 67.553672) (end 206.686328 60.960008) (width 0.196) (layer "In7.Cu") (net 278))
  (segment (start 200.84 73.4) (end 206.686328 67.553672) (width 0.196) (layer "In7.Cu") (net 278))
  (segment (start 190.23 73.724291) (end 190.23 73.075709) (width 0.196) (layer "In7.Cu") (net 278))
  (segment (start 180.636328 86.060008) (end 181.039992 86.060008) (width 0.127) (layer "In7.Cu") (net 278))
  (segment (start 182.15 85.35) (end 182.15 77.15) (width 0.127) (layer "In7.Cu") (net 278))
  (segment (start 182.69 73.4) (end 186.98 73.4) (width 0.196) (layer "In7.Cu") (net 278))
  (segment (start 190.73 73.075709) (end 190.73 73.724291) (width 0.196) (layer "In7.Cu") (net 278))
  (segment (start 192.23 73.724291) (end 192.23 73.075709) (width 0.196) (layer "In7.Cu") (net 278))
  (segment (start 181.83 76.83) (end 181.83 75.59) (width 0.127) (layer "In7.Cu") (net 278))
  (segment (start 188.73 73.075709) (end 188.73 73.724291) (width 0.196) (layer "In7.Cu") (net 278))
  (segment (start 187.23 73.15) (end 187.23 73.075709) (width 0.196) (layer "In7.Cu") (net 278))
  (segment (start 181.83 74.26) (end 182.69 73.4) (width 0.196) (layer "In7.Cu") (net 278))
  (segment (start 181.039992 86.060008) (end 181.202828 85.897172) (width 0.127) (layer "In7.Cu") (net 278))
  (arc (start 187.73 73.724291) (mid 187.803223 73.901068) (end 187.98 73.974291) (width 0.196) (layer "In7.Cu") (net 278))
  (arc (start 187.23 73.075709) (mid 187.303223 72.898932) (end 187.48 72.825709) (width 0.196) (layer "In7.Cu") (net 278))
  (arc (start 191.73 73.724291) (mid 191.803223 73.901068) (end 191.98 73.974291) (width 0.196) (layer "In7.Cu") (net 278))
  (arc (start 189.73 73.724291) (mid 189.803223 73.901068) (end 189.98 73.974291) (width 0.196) (layer "In7.Cu") (net 278))
  (arc (start 189.98 73.974291) (mid 190.156777 73.901068) (end 190.23 73.724291) (width 0.196) (layer "In7.Cu") (net 278))
  (arc (start 192.73 73.15) (mid 192.803223 73.326777) (end 192.98 73.4) (width 0.196) (layer "In7.Cu") (net 278))
  (arc (start 192.23 73.075709) (mid 192.303223 72.898932) (end 192.48 72.825709) (width 0.196) (layer "In7.Cu") (net 278))
  (arc (start 188.23 73.075709) (mid 188.303223 72.898932) (end 188.48 72.825709) (width 0.196) (layer "In7.Cu") (net 278))
  (arc (start 189.48 72.825709) (mid 189.656777 72.898932) (end 189.73 73.075709) (width 0.196) (layer "In7.Cu") (net 278))
  (arc (start 190.98 73.974291) (mid 191.156777 73.901068) (end 191.23 73.724291) (width 0.196) (layer "In7.Cu") (net 278))
  (arc (start 189.23 73.075709) (mid 189.303223 72.898932) (end 189.48 72.825709) (width 0.196) (layer "In7.Cu") (net 278))
  (arc (start 188.48 72.825709) (mid 188.656777 72.898932) (end 188.73 73.075709) (width 0.196) (layer "In7.Cu") (net 278))
  (arc (start 187.48 72.825709) (mid 187.656777 72.898932) (end 187.73 73.075709) (width 0.196) (layer "In7.Cu") (net 278))
  (arc (start 188.98 73.974291) (mid 189.156777 73.901068) (end 189.23 73.724291) (width 0.196) (layer "In7.Cu") (net 278))
  (arc (start 188.73 73.724291) (mid 188.803223 73.901068) (end 188.98 73.974291) (width 0.196) (layer "In7.Cu") (net 278))
  (arc (start 191.98 73.974291) (mid 192.156777 73.901068) (end 192.23 73.724291) (width 0.196) (layer "In7.Cu") (net 278))
  (arc (start 190.23 73.075709) (mid 190.303223 72.898932) (end 190.48 72.825709) (width 0.196) (layer "In7.Cu") (net 278))
  (arc (start 186.98 73.4) (mid 187.156777 73.326777) (end 187.23 73.15) (width 0.196) (layer "In7.Cu") (net 278))
  (arc (start 191.23 73.075709) (mid 191.303223 72.898932) (end 191.48 72.825709) (width 0.196) (layer "In7.Cu") (net 278))
  (arc (start 190.73 73.724291) (mid 190.803223 73.901068) (end 190.98 73.974291) (width 0.196) (layer "In7.Cu") (net 278))
  (arc (start 192.48 72.825709) (mid 192.656777 72.898932) (end 192.73 73.075709) (width 0.196) (layer "In7.Cu") (net 278))
  (arc (start 191.48 72.825709) (mid 191.656777 72.898932) (end 191.73 73.075709) (width 0.196) (layer "In7.Cu") (net 278))
  (arc (start 187.98 73.974291) (mid 188.156777 73.901068) (end 188.23 73.724291) (width 0.196) (layer "In7.Cu") (net 278))
  (arc (start 190.48 72.825709) (mid 190.656777 72.898932) (end 190.73 73.075709) (width 0.196) (layer "In7.Cu") (net 278))
  (segment (start 210.086328 59.660008) (end 210.086328 60.960008) (width 0.2) (layer "F.Cu") (net 279))
  (segment (start 191.636328 78.060008) (end 191.655836 78.060008) (width 0.127) (layer "F.Cu") (net 279))
  (segment (start 191.136328 78.560008) (end 191.636328 78.060008) (width 0.127) (layer "F.Cu") (net 279))
  (via blind (at 210.086328 60.960008) (size 0.5) (drill 0.2) (layers "F.Cu" "In5.Cu") (net 279))
  (via blind (at 191.655836 78.060008) (size 0.5) (drill 0.2) (layers "F.Cu" "In5.Cu") (net 279))
  (segment (start 190.764982 73.225) (end 191.535018 73.225) (width 0.146) (layer "In5.Cu") (net 279))
  (segment (start 191.655836 77.705836) (end 191.655836 78.060008) (width 0.09) (layer "In5.Cu") (net 279))
  (segment (start 190.764982 72.325) (end 191.535018 72.325) (width 0.146) (layer "In5.Cu") (net 279))
  (segment (start 191.15 75.5) (end 191.15 77.2) (width 0.09) (layer "In5.Cu") (net 279))
  (segment (start 190.764982 74.575) (end 191.535018 74.575) (width 0.146) (layer "In5.Cu") (net 279))
  (segment (start 191.15 70.75) (end 191.15 69.25) (width 0.146) (layer "In5.Cu") (net 279))
  (segment (start 191.15 77.2) (end 191.655836 77.705836) (width 0.09) (layer "In5.Cu") (net 279))
  (segment (start 195.8 64.6) (end 207.22 64.6) (width 0.146) (layer "In5.Cu") (net 279))
  (segment (start 190.764982 71.875) (end 191.535018 71.875) (width 0.146) (layer "In5.Cu") (net 279))
  (segment (start 191.15 75.5) (end 191.15 75.25) (width 0.146) (layer "In5.Cu") (net 279))
  (segment (start 190.764982 73.675) (end 191.535018 73.675) (width 0.146) (layer "In5.Cu") (net 279))
  (segment (start 190.764982 74.125) (end 191.535018 74.125) (width 0.146) (layer "In5.Cu") (net 279))
  (segment (start 190.764982 72.775) (end 191.535018 72.775) (width 0.146) (layer "In5.Cu") (net 279))
  (segment (start 190.764982 71.425) (end 191.535018 71.425) (width 0.146) (layer "In5.Cu") (net 279))
  (segment (start 207.22 64.6) (end 210.086328 61.733672) (width 0.146) (layer "In5.Cu") (net 279))
  (segment (start 190.925 75.025) (end 190.764982 75.025) (width 0.146) (layer "In5.Cu") (net 279))
  (segment (start 191.15 69.25) (end 195.8 64.6) (width 0.146) (layer "In5.Cu") (net 279))
  (segment (start 210.086328 61.733672) (end 210.086328 60.960008) (width 0.146) (layer "In5.Cu") (net 279))
  (segment (start 190.764982 70.975) (end 190.925 70.975) (width 0.146) (layer "In5.Cu") (net 279))
  (arc (start 190.764982 73.225) (mid 190.605883 73.159099) (end 190.539982 73) (width 0.146) (layer "In5.Cu") (net 279))
  (arc (start 190.539982 72.1) (mid 190.605883 71.940901) (end 190.764982 71.875) (width 0.146) (layer "In5.Cu") (net 279))
  (arc (start 191.535018 72.775) (mid 191.694117 72.709099) (end 191.760018 72.55) (width 0.146) (layer "In5.Cu") (net 279))
  (arc (start 190.539982 71.2) (mid 190.605883 71.040901) (end 190.764982 70.975) (width 0.146) (layer "In5.Cu") (net 279))
  (arc (start 190.764982 74.125) (mid 190.605883 74.059099) (end 190.539982 73.9) (width 0.146) (layer "In5.Cu") (net 279))
  (arc (start 191.760018 73.45) (mid 191.694117 73.290901) (end 191.535018 73.225) (width 0.146) (layer "In5.Cu") (net 279))
  (arc (start 190.764982 71.425) (mid 190.605883 71.359099) (end 190.539982 71.2) (width 0.146) (layer "In5.Cu") (net 279))
  (arc (start 191.535018 71.875) (mid 191.694117 71.809099) (end 191.760018 71.65) (width 0.146) (layer "In5.Cu") (net 279))
  (arc (start 190.764982 72.325) (mid 190.605883 72.259099) (end 190.539982 72.1) (width 0.146) (layer "In5.Cu") (net 279))
  (arc (start 191.760018 74.35) (mid 191.694117 74.190901) (end 191.535018 74.125) (width 0.146) (layer "In5.Cu") (net 279))
  (arc (start 190.539982 73.9) (mid 190.605883 73.740901) (end 190.764982 73.675) (width 0.146) (layer "In5.Cu") (net 279))
  (arc (start 190.925 70.975) (mid 191.084099 70.909099) (end 191.15 70.75) (width 0.146) (layer "In5.Cu") (net 279))
  (arc (start 191.535018 74.575) (mid 191.694117 74.509099) (end 191.760018 74.35) (width 0.146) (layer "In5.Cu") (net 279))
  (arc (start 191.535018 73.675) (mid 191.694117 73.609099) (end 191.760018 73.45) (width 0.146) (layer "In5.Cu") (net 279))
  (arc (start 191.760018 71.65) (mid 191.694117 71.490901) (end 191.535018 71.425) (width 0.146) (layer "In5.Cu") (net 279))
  (arc (start 191.760018 72.55) (mid 191.694117 72.390901) (end 191.535018 72.325) (width 0.146) (layer "In5.Cu") (net 279))
  (arc (start 190.539982 74.8) (mid 190.605883 74.640901) (end 190.764982 74.575) (width 0.146) (layer "In5.Cu") (net 279))
  (arc (start 190.539982 73) (mid 190.605883 72.840901) (end 190.764982 72.775) (width 0.146) (layer "In5.Cu") (net 279))
  (arc (start 190.764982 75.025) (mid 190.605883 74.959099) (end 190.539982 74.8) (width 0.146) (layer "In5.Cu") (net 279))
  (arc (start 191.15 75.25) (mid 191.084099 75.090901) (end 190.925 75.025) (width 0.146) (layer "In5.Cu") (net 279))
  (segment (start 188.14632 77.560008) (end 188.636328 77.07) (width 0.127) (layer "F.Cu") (net 280))
  (segment (start 193.936328 59.660008) (end 193.936328 60.960008) (width 0.2) (layer "F.Cu") (net 280))
  (segment (start 188.136328 77.560008) (end 188.14632 77.560008) (width 0.127) (layer "F.Cu") (net 280))
  (via blind (at 188.636328 77.07) (size 0.5) (drill 0.2) (layers "F.Cu" "In2.Cu") (net 280))
  (via blind (at 193.936328 60.960008) (size 0.5) (drill 0.2) (layers "F.Cu" "In2.Cu") (net 280))
  (segment (start 193.381583 68.673009) (end 193.381583 68.673008) (width 0.16) (layer "In2.Cu") (net 280))
  (segment (start 191.45 71.4) (end 191.35 71.4) (width 0.16) (layer "In2.Cu") (net 280))
  (segment (start 189 72.7) (end 189 75.59) (width 0.16) (layer "In2.Cu") (net 280))
  (segment (start 190.675 71.125) (end 190.675 71.175) (width 0.16) (layer "In2.Cu") (net 280))
  (segment (start 190.45 71.4) (end 190.3 71.4) (width 0.16) (layer "In2.Cu") (net 280))
  (segment (start 194.415685 69.883883) (end 194.415683 69.883884) (width 0.16) (layer "In2.Cu") (net 280))
  (segment (start 189 75.59) (end 189 75.8) (width 0.1) (layer "In2.Cu") (net 280))
  (segment (start 193.708577 71.085967) (end 191.764033 69.141423) (width 0.16) (layer "In2.Cu") (net 280))
  (segment (start 194.451039 69.282843) (end 194.451041 69.282844) (width 0.16) (layer "In2.Cu") (net 280))
  (segment (start 192.080668 71.862221) (end 192.080669 71.862223) (width 0.16) (layer "In2.Cu") (net 280))
  (segment (start 190.3 71.4) (end 189 72.7) (width 0.16) (layer "In2.Cu") (net 280))
  (segment (start 192.646356 71.65009) (end 192.646355 71.650091) (width 0.16) (layer "In2.Cu") (net 280))
  (segment (start 193.072181 71.722363) (end 192.999909 71.650091) (width 0.16) (layer "In2.Cu") (net 280))
  (segment (start 193.936328 65.161328) (end 194.15 65.375) (width 0.16) (layer "In2.Cu") (net 280))
  (segment (start 192.080668 71.50867) (end 192.080669 71.508669) (width 0.16) (layer "In2.Cu") (net 280))
  (segment (start 192.646355 71.650091) (end 192.434221 71.862222) (width 0.16) (layer "In2.Cu") (net 280))
  (segment (start 193.936328 63.763672) (end 193.936328 63.813672) (width 0.16) (layer "In2.Cu") (net 280))
  (segment (start 193.95 67.55) (end 193.631566 67.55) (width 0.16) (layer "In2.Cu") (net 280))
  (segment (start 193.936328 64.713672) (end 193.936328 65.161328) (width 0.16) (layer "In2.Cu") (net 280))
  (segment (start 194.132843 69.3182) (end 194.168197 69.282843) (width 0.16) (layer "In2.Cu") (net 280))
  (segment (start 192.497701 68.602299) (end 192.400429 68.505027) (width 0.16) (layer "In2.Cu") (net 280))
  (segment (start 192.292799 70.942982) (end 192.292801 70.942983) (width 0.16) (layer "In2.Cu") (net 280))
  (segment (start 193.486328 61.886328) (end 193.736328 61.886328) (width 0.16) (layer "In2.Cu") (net 280))
  (segment (start 194.132842 70.237439) (end 193.134096 69.238693) (width 0.16) (layer "In2.Cu") (net 280))
  (segment (start 193.063385 68.35481) (end 192.815899 68.602299) (width 0.16) (layer "In2.Cu") (net 280))
  (segment (start 193.736328 61.486328) (end 193.486328 61.486328) (width 0.16) (layer "In2.Cu") (net 280))
  (segment (start 193.936328 60.960008) (end 193.936328 61.286328) (width 0.16) (layer "In2.Cu") (net 280))
  (segment (start 192.080669 71.508669) (end 192.2928 71.296535) (width 0.16) (layer "In2.Cu") (net 280))
  (segment (start 193.134096 68.920495) (end 193.381583 68.673009) (width 0.16) (layer "In2.Cu") (net 280))
  (segment (start 194.15 65.375) (end 194.15 67.35) (width 0.16) (layer "In2.Cu") (net 280))
  (segment (start 193.631566 67.95) (end 193.95 67.95) (width 0.16) (layer "In2.Cu") (net 280))
  (segment (start 192.082231 68.823225) (end 194.026775 70.767769) (width 0.16) (layer "In2.Cu") (net 280))
  (segment (start 191.125 71.175) (end 191.125 71.125) (width 0.16) (layer "In2.Cu") (net 280))
  (segment (start 194.415683 69.883884) (end 194.45104 69.919241) (width 0.16) (layer "In2.Cu") (net 280))
  (segment (start 192.292801 70.942983) (end 192.259009 70.909191) (width 0.16) (layer "In2.Cu") (net 280))
  (segment (start 194.451038 69.565687) (end 194.415684 69.60104) (width 0.16) (layer "In2.Cu") (net 280))
  (segment (start 191.940811 70.909191) (end 191.45 71.4) (width 0.16) (layer "In2.Cu") (net 280))
  (segment (start 194.15 68.7) (end 193.85 69) (width 0.16) (layer "In2.Cu") (net 280))
  (segment (start 194.132843 69.318199) (end 194.132843 69.3182) (width 0.16) (layer "In2.Cu") (net 280))
  (segment (start 194.15 68.15) (end 194.15 68.7) (width 0.16) (layer "In2.Cu") (net 280))
  (segment (start 191.445835 69.459621) (end 193.390379 71.404165) (width 0.16) (layer "In2.Cu") (net 280))
  (segment (start 193.936328 62.086328) (end 193.936328 62.863672) (width 0.16) (layer "In2.Cu") (net 280))
  (segment (start 189 75.8) (end 188.636328 76.163672) (width 0.1) (layer "In2.Cu") (net 280))
  (segment (start 188.636328 76.163672) (end 188.636328 77.07) (width 0.1) (layer "In2.Cu") (net 280))
  (arc (start 191.125 71.125) (mid 191.059099 70.965901) (end 190.9 70.9) (width 0.16) (layer "In2.Cu") (net 280))
  (arc (start 193.390379 71.722363) (mid 193.23128 71.788264) (end 193.072181 71.722363) (width 0.16) (layer "In2.Cu") (net 280))
  (arc (start 192.259009 70.909191) (mid 192.09991 70.84329) (end 191.940811 70.909191) (width 0.16) (layer "In2.Cu") (net 280))
  (arc (start 193.431566 67.75) (mid 193.490145 67.891421) (end 193.631566 67.95) (width 0.16) (layer "In2.Cu") (net 280))
  (arc (start 193.286328 61.686328) (mid 193.344907 61.827749) (end 193.486328 61.886328) (width 0.16) (layer "In2.Cu") (net 280))
  (arc (start 193.936328 61.286328) (mid 193.877749 61.427749) (end 193.736328 61.486328) (width 0.16) (layer "In2.Cu") (net 280))
  (arc (start 193.736328 61.886328) (mid 193.877749 61.944907) (end 193.936328 62.086328) (width 0.16) (layer "In2.Cu") (net 280))
  (arc (start 193.381583 68.35481) (mid 193.222484 68.288909) (end 193.063385 68.35481) (width 0.16) (layer "In2.Cu") (net 280))
  (arc (start 190.9 70.9) (mid 190.740901 70.965901) (end 190.675 71.125) (width 0.16) (layer "In2.Cu") (net 280))
  (arc (start 194.168197 69.282843) (mid 194.309619 69.224266) (end 194.451039 69.282843) (width 0.16) (layer "In2.Cu") (net 280))
  (arc (start 193.390379 71.404165) (mid 193.45628 71.563264) (end 193.390379 71.722363) (width 0.16) (layer "In2.Cu") (net 280))
  (arc (start 193.95 67.95) (mid 194.091421 68.008579) (end 194.15 68.15) (width 0.16) (layer "In2.Cu") (net 280))
  (arc (start 191.764033 69.141423) (mid 191.604934 69.075522) (end 191.445835 69.141423) (width 0.16) (layer "In2.Cu") (net 280))
  (arc (start 194.451041 69.282844) (mid 194.509617 69.424266) (end 194.451038 69.565687) (width 0.16) (layer "In2.Cu") (net 280))
  (arc (start 193.486328 64.263672) (mid 193.552229 64.422771) (end 193.711328 64.488672) (width 0.16) (layer "In2.Cu") (net 280))
  (arc (start 194.45104 70.237439) (mid 194.291941 70.30334) (end 194.132842 70.237439) (width 0.16) (layer "In2.Cu") (net 280))
  (arc (start 193.134096 69.238693) (mid 193.068195 69.079594) (end 193.134096 68.920495) (width 0.16) (layer "In2.Cu") (net 280))
  (arc (start 192.400429 68.505027) (mid 192.24133 68.439126) (end 192.082231 68.505027) (width 0.16) (layer "In2.Cu") (net 280))
  (arc (start 193.381583 68.673008) (mid 193.447484 68.513908) (end 193.381583 68.35481) (width 0.16) (layer "In2.Cu") (net 280))
  (arc (start 192.080669 71.862223) (mid 192.007445 71.685447) (end 192.080668 71.50867) (width 0.16) (layer "In2.Cu") (net 280))
  (arc (start 194.415684 69.60104) (mid 194.357106 69.742462) (end 194.415685 69.883883) (width 0.16) (layer "In2.Cu") (net 280))
  (arc (start 193.486328 63.313672) (mid 193.552229 63.472771) (end 193.711328 63.538672) (width 0.16) (layer "In2.Cu") (net 280))
  (arc (start 192.082231 68.505027) (mid 192.01633 68.664126) (end 192.082231 68.823225) (width 0.16) (layer "In2.Cu") (net 280))
  (arc (start 194.15 67.35) (mid 194.091421 67.491421) (end 193.95 67.55) (width 0.16) (layer "In2.Cu") (net 280))
  (arc (start 193.85 69) (mid 193.784098 69.159101) (end 193.85 69.3182) (width 0.16) (layer "In2.Cu") (net 280))
  (arc (start 192.999909 71.650091) (mid 192.823133 71.576867) (end 192.646356 71.65009) (width 0.16) (layer "In2.Cu") (net 280))
  (arc (start 193.486328 61.486328) (mid 193.344907 61.544907) (end 193.286328 61.686328) (width 0.16) (layer "In2.Cu") (net 280))
  (arc (start 192.2928 71.296535) (mid 192.366023 71.119758) (end 192.292799 70.942982) (width 0.16) (layer "In2.Cu") (net 280))
  (arc (start 192.815899 68.602299) (mid 192.6568 68.6682) (end 192.497701 68.602299) (width 0.16) (layer "In2.Cu") (net 280))
  (arc (start 190.675 71.175) (mid 190.609099 71.334099) (end 190.45 71.4) (width 0.16) (layer "In2.Cu") (net 280))
  (arc (start 193.711328 63.538672) (mid 193.870427 63.604573) (end 193.936328 63.763672) (width 0.16) (layer "In2.Cu") (net 280))
  (arc (start 191.445835 69.141423) (mid 191.379934 69.300522) (end 191.445835 69.459621) (width 0.16) (layer "In2.Cu") (net 280))
  (arc (start 193.936328 63.813672) (mid 193.870427 63.972771) (end 193.711328 64.038672) (width 0.16) (layer "In2.Cu") (net 280))
  (arc (start 192.434221 71.862222) (mid 192.257444 71.935445) (end 192.080668 71.862221) (width 0.16) (layer "In2.Cu") (net 280))
  (arc (start 194.026775 71.085967) (mid 193.867676 71.151868) (end 193.708577 71.085967) (width 0.16) (layer "In2.Cu") (net 280))
  (arc (start 194.45104 69.919241) (mid 194.516941 70.07834) (end 194.45104 70.237439) (width 0.16) (layer "In2.Cu") (net 280))
  (arc (start 193.711328 64.488672) (mid 193.870427 64.554573) (end 193.936328 64.713672) (width 0.16) (layer "In2.Cu") (net 280))
  (arc (start 193.711328 63.088672) (mid 193.552229 63.154573) (end 193.486328 63.313672) (width 0.16) (layer "In2.Cu") (net 280))
  (arc (start 191.35 71.4) (mid 191.190901 71.334099) (end 191.125 71.175) (width 0.16) (layer "In2.Cu") (net 280))
  (arc (start 193.711328 64.038672) (mid 193.552229 64.104573) (end 193.486328 64.263672) (width 0.16) (layer "In2.Cu") (net 280))
  (arc (start 193.936328 62.863672) (mid 193.870427 63.022771) (end 193.711328 63.088672) (width 0.16) (layer "In2.Cu") (net 280))
  (arc (start 193.631566 67.55) (mid 193.490145 67.608579) (end 193.431566 67.75) (width 0.16) (layer "In2.Cu") (net 280))
  (arc (start 194.026775 70.767769) (mid 194.092676 70.926868) (end 194.026775 71.085967) (width 0.16) (layer "In2.Cu") (net 280))
  (arc (start 193.85 69.3182) (mid 193.991422 69.376778) (end 194.132843 69.318199) (width 0.16) (layer "In2.Cu") (net 280))
  (segment (start 195.136328 83.560008) (end 195.636328 83.060008) (width 0.127) (layer "F.Cu") (net 281))
  (segment (start 223.686328 59.660008) (end 223.686328 60.960008) (width 0.2) (layer "F.Cu") (net 281))
  (segment (start 195.636328 83.060008) (end 195.655836 83.060008) (width 0.127) (layer "F.Cu") (net 281))
  (via blind (at 223.686328 60.960008) (size 0.5) (drill 0.2) (layers "F.Cu" "In2.Cu") (net 281))
  (via blind (at 195.655836 83.060008) (size 0.5) (drill 0.2) (layers "F.Cu" "In2.Cu") (net 281))
  (segment (start 210.15 81.525736) (end 210.114645 81.490381) (width 0.16) (layer "In2.Cu") (net 281))
  (segment (start 214 78.1) (end 214.000003 78.1) (width 0.16) (layer "In2.Cu") (net 281))
  (segment (start 214.424267 78.1) (end 214.424267 78.099999) (width 0.16) (layer "In2.Cu") (net 281))
  (segment (start 217.426063 74.673939) (end 223.686328 68.413672) (width 0.16) (layer "In2.Cu") (net 281))
  (segment (start 196.075836 84.149836) (end 196.075836 83.480008) (width 0.1) (layer "In2.Cu") (net 281))
  (segment (start 212.30668 80.288292) (end 212.30668 80.288293) (width 0.16) (layer "In2.Cu") (net 281))
  (segment (start 210.538911 81.066116) (end 211.033885 81.561089) (width 0.16) (layer "In2.Cu") (net 281))
  (segment (start 212.271324 79.828673) (end 212.808804 79.291196) (width 0.16) (layer "In2.Cu") (net 281))
  (segment (start 197.8 84.01) (end 197.278 84.532) (width 0.1) (layer "In2.Cu") (net 281))
  (segment (start 212.808804 79.291196) (end 214 78.1) (width 0.16) (layer "In2.Cu") (net 281))
  (segment (start 211.458149 81.136824) (end 210.963176 80.64185) (width 0.16) (layer "In2.Cu") (net 281))
  (segment (start 212.30668 80.288293) (end 212.271324 80.252937) (width 0.16) (layer "In2.Cu") (net 281))
  (segment (start 215.272798 76.827209) (end 217.426063 74.673939) (width 0.16) (layer "In2.Cu") (net 281))
  (segment (start 198.81 83.49) (end 200 82.3) (width 0.16) (layer "In2.Cu") (net 281))
  (segment (start 211.458149 81.136823) (end 211.458149 81.136824) (width 0.16) (layer "In2.Cu") (net 281))
  (segment (start 211.387442 80.217586) (end 211.387442 80.217585) (width 0.16) (layer "In2.Cu") (net 281))
  (segment (start 196.075836 83.480008) (end 195.655836 83.060008) (width 0.1) (layer "In2.Cu") (net 281))
  (segment (start 214.760372 76.739045) (end 214.760371 76.739046) (width 0.16) (layer "In2.Cu") (net 281))
  (segment (start 210.538911 81.066117) (end 210.538911 81.066116) (width 0.16) (layer "In2.Cu") (net 281))
  (segment (start 197.91 83.49) (end 197.8 83.6) (width 0.1) (layer "In2.Cu") (net 281))
  (segment (start 214.936693 77.763895) (end 214.936692 77.763896) (width 0.16) (layer "In2.Cu") (net 281))
  (segment (start 214.424267 78.099999) (end 214.512429 78.188161) (width 0.16) (layer "In2.Cu") (net 281))
  (segment (start 197.278 84.532) (end 196.458 84.532) (width 0.1) (layer "In2.Cu") (net 281))
  (segment (start 223.686328 68.413672) (end 223.686328 60.960008) (width 0.16) (layer "In2.Cu") (net 281))
  (segment (start 198.09 83.49) (end 198.81 83.49) (width 0.16) (layer "In2.Cu") (net 281))
  (segment (start 209.8 82.3) (end 210.15 81.95) (width 0.16) (layer "In2.Cu") (net 281))
  (segment (start 198.09 83.49) (end 197.91 83.49) (width 0.1) (layer "In2.Cu") (net 281))
  (segment (start 211.387442 80.217585) (end 211.882416 80.712558) (width 0.16) (layer "In2.Cu") (net 281))
  (segment (start 196.458 84.532) (end 196.075836 84.149836) (width 0.1) (layer "In2.Cu") (net 281))
  (segment (start 200 82.3) (end 209.8 82.3) (width 0.16) (layer "In2.Cu") (net 281))
  (segment (start 214.936692 77.763896) (end 214.336106 77.163309) (width 0.16) (layer "In2.Cu") (net 281))
  (segment (start 214.760371 76.739046) (end 214.848534 76.827209) (width 0.16) (layer "In2.Cu") (net 281))
  (segment (start 197.8 83.6) (end 197.8 84.01) (width 0.1) (layer "In2.Cu") (net 281))
  (arc (start 214.336106 76.739045) (mid 214.548238 76.651178) (end 214.760372 76.739045) (width 0.16) (layer "In2.Cu") (net 281))
  (arc (start 214.512429 78.188161) (mid 214.724561 78.276029) (end 214.936693 78.188161) (width 0.16) (layer "In2.Cu") (net 281))
  (arc (start 211.033885 81.561089) (mid 211.246017 81.648957) (end 211.458149 81.561089) (width 0.16) (layer "In2.Cu") (net 281))
  (arc (start 210.963176 80.64185) (mid 210.875308 80.429718) (end 210.963176 80.217586) (width 0.16) (layer "In2.Cu") (net 281))
  (arc (start 214.000003 78.1) (mid 214.212135 78.012132) (end 214.424267 78.1) (width 0.16) (layer "In2.Cu") (net 281))
  (arc (start 214.936693 78.188161) (mid 215.024561 77.976028) (end 214.936693 77.763895) (width 0.16) (layer "In2.Cu") (net 281))
  (arc (start 210.114645 81.066117) (mid 210.326779 80.978248) (end 210.538911 81.066117) (width 0.16) (layer "In2.Cu") (net 281))
  (arc (start 214.336106 77.163309) (mid 214.248238 76.951177) (end 214.336106 76.739045) (width 0.16) (layer "In2.Cu") (net 281))
  (arc (start 214.848534 76.827209) (mid 215.060666 76.915077) (end 215.272798 76.827209) (width 0.16) (layer "In2.Cu") (net 281))
  (arc (start 210.114645 81.490381) (mid 210.026777 81.278249) (end 210.114645 81.066117) (width 0.16) (layer "In2.Cu") (net 281))
  (arc (start 211.458149 81.561089) (mid 211.546017 81.348956) (end 211.458149 81.136823) (width 0.16) (layer "In2.Cu") (net 281))
  (arc (start 210.15 81.95) (mid 210.237868 81.737868) (end 210.15 81.525736) (width 0.16) (layer "In2.Cu") (net 281))
  (arc (start 210.963176 80.217586) (mid 211.17531 80.129717) (end 211.387442 80.217586) (width 0.16) (layer "In2.Cu") (net 281))
  (arc (start 211.882416 80.712558) (mid 212.094548 80.800426) (end 212.30668 80.712558) (width 0.16) (layer "In2.Cu") (net 281))
  (arc (start 212.271324 80.252937) (mid 212.183456 80.040805) (end 212.271324 79.828673) (width 0.16) (layer "In2.Cu") (net 281))
  (arc (start 212.30668 80.712558) (mid 212.394548 80.500425) (end 212.30668 80.288292) (width 0.16) (layer "In2.Cu") (net 281))
  (segment (start 200.736328 59.660008) (end 200.736328 60.960008) (width 0.2) (layer "F.Cu") (net 282))
  (segment (start 175.136328 87.560008) (end 175.636328 87.060008) (width 0.1) (layer "F.Cu") (net 282))
  (via (at 200.736328 60.960008) (size 0.5) (drill 0.2) (layers "F.Cu" "B.Cu") (net 282))
  (via (at 175.636328 87.060008) (size 0.5) (drill 0.2) (layers "F.Cu" "B.Cu") (net 282))
  (segment (start 184.36 65.48018) (end 184.36 64.91982) (width 0.196) (layer "In7.Cu") (net 282))
  (segment (start 182.36 65.48018) (end 182.36 64.91982) (width 0.196) (layer "In7.Cu") (net 282))
  (segment (start 185.86 64.91982) (end 185.86 65.48018) (width 0.196) (layer "In7.Cu") (net 282))
  (segment (start 185.36 65.48018) (end 185.36 64.91982) (width 0.196) (layer "In7.Cu") (net 282))
  (segment (start 180.34 65.2) (end 181.11 65.2) (width 0.196) (layer "In7.Cu") (net 282))
  (segment (start 200.736328 63.303672) (end 200.736328 60.960008) (width 0.196) (layer "In7.Cu") (net 282))
  (segment (start 175.806492 82.493508) (end 175.3 83) (width 0.127) (layer "In7.Cu") (net 282))
  (segment (start 175.3 85.7) (end 175.636328 86.036328) (width 0.127) (layer "In7.Cu") (net 282))
  (segment (start 181.36 64.95) (end 181.36 64.91982) (width 0.196) (layer "In7.Cu") (net 282))
  (segment (start 186.61 65.2) (end 198.84 65.2) (width 0.196) (layer "In7.Cu") (net 282))
  (segment (start 181.86 64.95) (end 181.86 65.48018) (width 0.196) (layer "In7.Cu") (net 282))
  (segment (start 175.636328 86.036328) (end 175.636328 87.060008) (width 0.127) (layer "In7.Cu") (net 282))
  (segment (start 176.7 75.04) (end 176.7 68.84) (width 0.196) (layer "In7.Cu") (net 282))
  (segment (start 176.5 75.54) (end 176.5 81.809398) (width 0.127) (layer "In7.Cu") (net 282))
  (segment (start 198.84 65.2) (end 200.736328 63.303672) (width 0.196) (layer "In7.Cu") (net 282))
  (segment (start 176.7 68.84) (end 180.34 65.2) (width 0.196) (layer "In7.Cu") (net 282))
  (segment (start 182.86 64.91982) (end 182.86 65.48018) (width 0.196) (layer "In7.Cu") (net 282))
  (segment (start 176.5 75.24) (end 176.7 75.04) (width 0.196) (layer "In7.Cu") (net 282))
  (segment (start 183.36 65.48018) (end 183.36 64.91982) (width 0.196) (layer "In7.Cu") (net 282))
  (segment (start 176.5 81.809398) (end 175.81589 82.493508) (width 0.127) (layer "In7.Cu") (net 282))
  (segment (start 175.3 83) (end 175.3 85.7) (width 0.127) (layer "In7.Cu") (net 282))
  (segment (start 184.86 64.91982) (end 184.86 65.48018) (width 0.196) (layer "In7.Cu") (net 282))
  (segment (start 183.86 64.91982) (end 183.86 65.48018) (width 0.196) (layer "In7.Cu") (net 282))
  (segment (start 176.5 75.54) (end 176.5 75.24) (width 0.196) (layer "In7.Cu") (net 282))
  (segment (start 186.36 65.48018) (end 186.36 65.45) (width 0.196) (layer "In7.Cu") (net 282))
  (segment (start 181.86 64.91982) (end 181.86 64.95) (width 0.196) (layer "In7.Cu") (net 282))
  (segment (start 175.81589 82.493508) (end 175.806492 82.493508) (width 0.127) (layer "In7.Cu") (net 282))
  (arc (start 186.11 65.73018) (mid 186.286777 65.656957) (end 186.36 65.48018) (width 0.196) (layer "In7.Cu") (net 282))
  (arc (start 183.11 65.73018) (mid 183.286777 65.656957) (end 183.36 65.48018) (width 0.196) (layer "In7.Cu") (net 282))
  (arc (start 185.11 65.73018) (mid 185.286777 65.656957) (end 185.36 65.48018) (width 0.196) (layer "In7.Cu") (net 282))
  (arc (start 183.61 64.66982) (mid 183.786777 64.743043) (end 183.86 64.91982) (width 0.196) (layer "In7.Cu") (net 282))
  (arc (start 185.86 65.48018) (mid 185.933223 65.656957) (end 186.11 65.73018) (width 0.196) (layer "In7.Cu") (net 282))
  (arc (start 184.61 64.66982) (mid 184.786777 64.743043) (end 184.86 64.91982) (width 0.196) (layer "In7.Cu") (net 282))
  (arc (start 181.11 65.2) (mid 181.286777 65.126777) (end 181.36 64.95) (width 0.196) (layer "In7.Cu") (net 282))
  (arc (start 181.86 65.48018) (mid 181.933223 65.656957) (end 182.11 65.73018) (width 0.196) (layer "In7.Cu") (net 282))
  (arc (start 182.36 64.91982) (mid 182.433223 64.743043) (end 182.61 64.66982) (width 0.196) (layer "In7.Cu") (net 282))
  (arc (start 183.86 65.48018) (mid 183.933223 65.656957) (end 184.11 65.73018) (width 0.196) (layer "In7.Cu") (net 282))
  (arc (start 183.36 64.91982) (mid 183.433223 64.743043) (end 183.61 64.66982) (width 0.196) (layer "In7.Cu") (net 282))
  (arc (start 181.61 64.66982) (mid 181.786777 64.743043) (end 181.86 64.91982) (width 0.196) (layer "In7.Cu") (net 282))
  (arc (start 182.61 64.66982) (mid 182.786777 64.743043) (end 182.86 64.91982) (width 0.196) (layer "In7.Cu") (net 282))
  (arc (start 182.11 65.73018) (mid 182.286777 65.656957) (end 182.36 65.48018) (width 0.196) (layer "In7.Cu") (net 282))
  (arc (start 185.36 64.91982) (mid 185.433223 64.743043) (end 185.61 64.66982) (width 0.196) (layer "In7.Cu") (net 282))
  (arc (start 182.86 65.48018) (mid 182.933223 65.656957) (end 183.11 65.73018) (width 0.196) (layer "In7.Cu") (net 282))
  (arc (start 181.36 64.91982) (mid 181.433223 64.743043) (end 181.61 64.66982) (width 0.196) (layer "In7.Cu") (net 282))
  (arc (start 184.36 64.91982) (mid 184.433223 64.743043) (end 184.61 64.66982) (width 0.196) (layer "In7.Cu") (net 282))
  (arc (start 184.86 65.48018) (mid 184.933223 65.656957) (end 185.11 65.73018) (width 0.196) (layer "In7.Cu") (net 282))
  (arc (start 184.11 65.73018) (mid 184.286777 65.656957) (end 184.36 65.48018) (width 0.196) (layer "In7.Cu") (net 282))
  (arc (start 186.36 65.45) (mid 186.433223 65.273223) (end 186.61 65.2) (width 0.196) (layer "In7.Cu") (net 282))
  (arc (start 185.61 64.66982) (mid 185.786777 64.743043) (end 185.86 64.91982) (width 0.196) (layer "In7.Cu") (net 282))
  (segment (start 190.136328 81.560008) (end 190.636328 81.060008) (width 0.127) (layer "F.Cu") (net 283))
  (segment (start 191.386328 59.660008) (end 191.386328 60.710008) (width 0.2) (layer "F.Cu") (net 283))
  (segment (start 190.636328 81.060008) (end 190.655836 81.060008) (width 0.127) (layer "F.Cu") (net 283))
  (segment (start 191.386328 60.710008) (end 191.636328 60.960008) (width 0.2) (layer "F.Cu") (net 283))
  (via (at 190.655836 81.060008) (size 0.5) (drill 0.2) (layers "F.Cu" "B.Cu") (net 283))
  (via (at 191.636328 60.960008) (size 0.5) (drill 0.2) (layers "F.Cu" "B.Cu") (net 283))
  (segment (start 191.1 78.6) (end 190.98 78.48) (width 0.1) (layer "In9.Cu") (net 283))
  (segment (start 190.641874 78.48) (end 190.235836 78.886038) (width 0.1) (layer "In9.Cu") (net 283))
  (segment (start 192.006336 60.59) (end 191.636328 60.960008) (width 0.16) (layer "In9.Cu") (net 283))
  (segment (start 190.235836 80.640008) (end 190.655836 81.060008) (width 0.1) (layer "In9.Cu") (net 283))
  (segment (start 196.8 75.5) (end 196.8 74.7) (width 0.16) (layer "In9.Cu") (net 283))
  (segment (start 196.8 74.7) (end 198.9 72.6) (width 0.16) (layer "In9.Cu") (net 283))
  (segment (start 198.9 64.45) (end 195.04 60.59) (width 0.16) (layer "In9.Cu") (net 283))
  (segment (start 198.485892 69.4) (end 199.314108 69.4) (width 0.16) (layer "In9.Cu") (net 283))
  (segment (start 198.485892 71.8) (end 199.314108 71.8) (width 0.16) (layer "In9.Cu") (net 283))
  (segment (start 198.7 72.2) (end 198.485892 72.2) (width 0.16) (layer "In9.Cu") (net 283))
  (segment (start 199.314108 71.4) (end 198.485892 71.4) (width 0.16) (layer "In9.Cu") (net 283))
  (segment (start 198.9 68.4) (end 198.9 64.45) (width 0.16) (layer "In9.Cu") (net 283))
  (segment (start 199.314108 70.6) (end 198.485892 70.6) (width 0.16) (layer "In9.Cu") (net 283))
  (segment (start 196.8 75.65) (end 193.85 78.6) (width 0.1) (layer "In9.Cu") (net 283))
  (segment (start 196.8 75.5) (end 196.8 75.65) (width 0.1) (layer "In9.Cu") (net 283))
  (segment (start 190.98 78.48) (end 190.641874 78.48) (width 0.1) (layer "In9.Cu") (net 283))
  (segment (start 190.235836 78.886038) (end 190.235836 80.640008) (width 0.1) (layer "In9.Cu") (net 283))
  (segment (start 198.485892 70.2) (end 199.314108 70.2) (width 0.16) (layer "In9.Cu") (net 283))
  (segment (start 198.485892 68.6) (end 198.7 68.6) (width 0.16) (layer "In9.Cu") (net 283))
  (segment (start 198.9 72.6) (end 198.9 72.4) (width 0.16) (layer "In9.Cu") (net 283))
  (segment (start 198.485892 71) (end 199.314108 71) (width 0.16) (layer "In9.Cu") (net 283))
  (segment (start 199.314108 69) (end 198.485892 69) (width 0.16) (layer "In9.Cu") (net 283))
  (segment (start 199.314108 69.8) (end 198.485892 69.8) (width 0.16) (layer "In9.Cu") (net 283))
  (segment (start 193.85 78.6) (end 191.1 78.6) (width 0.1) (layer "In9.Cu") (net 283))
  (segment (start 195.04 60.59) (end 192.006336 60.59) (width 0.16) (layer "In9.Cu") (net 283))
  (arc (start 198.285892 68.8) (mid 198.344471 68.658579) (end 198.485892 68.6) (width 0.16) (layer "In9.Cu") (net 283))
  (arc (start 198.285892 69.6) (mid 198.344471 69.458579) (end 198.485892 69.4) (width 0.16) (layer "In9.Cu") (net 283))
  (arc (start 198.285892 70.4) (mid 198.344471 70.258579) (end 198.485892 70.2) (width 0.16) (layer "In9.Cu") (net 283))
  (arc (start 198.9 72.4) (mid 198.841421 72.258579) (end 198.7 72.2) (width 0.16) (layer "In9.Cu") (net 283))
  (arc (start 199.314108 70.2) (mid 199.455529 70.141421) (end 199.514108 70) (width 0.16) (layer "In9.Cu") (net 283))
  (arc (start 198.485892 70.6) (mid 198.344471 70.541421) (end 198.285892 70.4) (width 0.16) (layer "In9.Cu") (net 283))
  (arc (start 199.514108 70) (mid 199.455529 69.858579) (end 199.314108 69.8) (width 0.16) (layer "In9.Cu") (net 283))
  (arc (start 198.7 68.6) (mid 198.841421 68.541421) (end 198.9 68.4) (width 0.16) (layer "In9.Cu") (net 283))
  (arc (start 199.314108 71.8) (mid 199.455529 71.741421) (end 199.514108 71.6) (width 0.16) (layer "In9.Cu") (net 283))
  (arc (start 198.485892 69) (mid 198.344471 68.941421) (end 198.285892 68.8) (width 0.16) (layer "In9.Cu") (net 283))
  (arc (start 199.514108 69.2) (mid 199.455529 69.058579) (end 199.314108 69) (width 0.16) (layer "In9.Cu") (net 283))
  (arc (start 199.514108 71.6) (mid 199.455529 71.458579) (end 199.314108 71.4) (width 0.16) (layer "In9.Cu") (net 283))
  (arc (start 199.314108 71) (mid 199.455529 70.941421) (end 199.514108 70.8) (width 0.16) (layer "In9.Cu") (net 283))
  (arc (start 198.285892 72) (mid 198.344471 71.858579) (end 198.485892 71.8) (width 0.16) (layer "In9.Cu") (net 283))
  (arc (start 198.485892 72.2) (mid 198.344471 72.141421) (end 198.285892 72) (width 0.16) (layer "In9.Cu") (net 283))
  (arc (start 199.314108 69.4) (mid 199.455529 69.341421) (end 199.514108 69.2) (width 0.16) (layer "In9.Cu") (net 283))
  (arc (start 198.285892 71.2) (mid 198.344471 71.058579) (end 198.485892 71) (width 0.16) (layer "In9.Cu") (net 283))
  (arc (start 198.485892 71.4) (mid 198.344471 71.341421) (end 198.285892 71.2) (width 0.16) (layer "In9.Cu") (net 283))
  (arc (start 198.485892 69.8) (mid 198.344471 69.741421) (end 198.285892 69.6) (width 0.16) (layer "In9.Cu") (net 283))
  (arc (start 199.514108 70.8) (mid 199.455529 70.658579) (end 199.314108 70.6) (width 0.16) (layer "In9.Cu") (net 283))
  (segment (start 190.536328 60.810008) (end 190.386328 60.960008) (width 0.2) (layer "F.Cu") (net 284))
  (segment (start 190.136328 77.560008) (end 190.636328 77.060008) (width 0.127) (layer "F.Cu") (net 284))
  (segment (start 190.636328 77.060008) (end 190.655836 77.060008) (width 0.127) (layer "F.Cu") (net 284))
  (segment (start 190.536328 59.660008) (end 190.536328 60.810008) (width 0.2) (layer "F.Cu") (net 284))
  (via (at 190.386328 60.960008) (size 0.5) (drill 0.2) (layers "F.Cu" "B.Cu") (net 284))
  (via (at 190.655836 77.060008) (size 0.5) (drill 0.2) (layers "F.Cu" "B.Cu") (net 284))
  (segment (start 195.666726 72.786826) (end 195.63137 72.75147) (width 0.16) (layer "In9.Cu") (net 284))
  (segment (start 195.5 68.8) (end 196.3 68.8) (width 0.16) (layer "In9.Cu") (net 284))
  (segment (start 193.4 76.4) (end 192.3 77.5) (width 0.1) (layer "In9.Cu") (net 284))
  (segment (start 195.824999 65.292157) (end 195.825 65.292157) (width 0.16) (layer "In9.Cu") (net 284))
  (segment (start 195.9 65.65) (end 195.825 65.575) (width 0.16) (layer "In9.Cu") (net 284))
  (segment (start 196.3 66.4) (end 196.1 66.4) (width 0.16) (layer "In9.Cu") (net 284))
  (segment (start 195.5 68.4) (end 196.3 68.4) (width 0.16) (layer "In9.Cu") (net 284))
  (segment (start 194.864936 65.120846) (end 194.864936 65.120845) (width 0.16) (layer "In9.Cu") (net 284))
  (segment (start 194.4 75.9) (end 193.9 76.4) (width 0.1) (layer "In9.Cu") (net 284))
  (segment (start 195.10104 73.635354) (end 195.10104 73.635355) (width 0.16) (layer "In9.Cu") (net 284))
  (segment (start 195.5 66.8) (end 196.3 66.8) (width 0.16) (layer "In9.Cu") (net 284))
  (segment (start 195.10104 73.352511) (end 195.10104 73.352512) (width 0.16) (layer "In9.Cu") (net 284))
  (segment (start 194.782842 73.6) (end 194.818197 73.635355) (width 0.16) (layer "In9.Cu") (net 284))
  (segment (start 192.3 77.5) (end 191.482766 77.5) (width 0.1) (layer "In9.Cu") (net 284))
  (segment (start 195.5 68) (end 196.3 68) (width 0.16) (layer "In9.Cu") (net 284))
  (segment (start 195.9 66.2) (end 195.9 65.65) (width 0.16) (layer "In9.Cu") (net 284))
  (segment (start 195.9 72.2) (end 195.9 69.4) (width 0.16) (layer "In9.Cu") (net 284))
  (segment (start 193.7 63.45) (end 191.65 63.45) (width 0.16) (layer "In9.Cu") (net 284))
  (segment (start 195.10104 73.352512) (end 194.782843 73.034315) (width 0.16) (layer "In9.Cu") (net 284))
  (segment (start 195.901177 64.933135) (end 195.901178 64.933136) (width 0.16) (layer "In9.Cu") (net 284))
  (segment (start 194.486959 63.801759) (end 194.486959 63.80176) (width 0.16) (layer "In9.Cu") (net 284))
  (segment (start 194.127937 63.877937) (end 194.127938 63.877938) (width 0.16) (layer "In9.Cu") (net 284))
  (segment (start 195.666726 73.06967) (end 195.666726 73.069669) (width 0.16) (layer "In9.Cu") (net 284))
  (segment (start 194.782843 72.751473) (end 194.782844 72.751471) (width 0.16) (layer "In9.Cu") (net 284))
  (segment (start 195.065686 72.751472) (end 195.383883 73.069669) (width 0.16) (layer "In9.Cu") (net 284))
  (segment (start 194.769802 63.801761) (end 194.769802 63.80176) (width 0.16) (layer "In9.Cu") (net 284))
  (segment (start 194.127938 63.877938) (end 193.7 63.45) (width 0.16) (layer "In9.Cu") (net 284))
  (segment (start 191.042774 77.060008) (end 190.655836 77.060008) (width 0.1) (layer "In9.Cu") (net 284))
  (segment (start 195.052647 64.367447) (end 195.052647 64.367448) (width 0.16) (layer "In9.Cu") (net 284))
  (segment (start 195.065688 72.751471) (end 195.065686 72.751472) (width 0.16) (layer "In9.Cu") (net 284))
  (segment (start 195.5 67.2) (end 196.3 67.2) (width 0.16) (layer "In9.Cu") (net 284))
  (segment (start 196.1 69.2) (end 196.3 69.2) (width 0.16) (layer "In9.Cu") (net 284))
  (segment (start 194.4 75.6) (end 194.4 75.9) (width 0.1) (layer "In9.Cu") (net 284))
  (segment (start 195.631371 72.468627) (end 195.63137 72.468627) (width 0.16) (layer "In9.Cu") (net 284))
  (segment (start 194.864936 65.403689) (end 194.864937 65.403689) (width 0.16) (layer "In9.Cu") (net 284))
  (segment (start 195.63137 72.468627) (end 195.9 72.2) (width 0.16) (layer "In9.Cu") (net 284))
  (segment (start 194.4 75.6) (end 194.4 73.7) (width 0.16) (layer "In9.Cu") (net 284))
  (segment (start 195.825 65.292157) (end 195.901178 65.215978) (width 0.16) (layer "In9.Cu") (net 284))
  (segment (start 191.482766 77.5) (end 191.042774 77.060008) (width 0.1) (layer "In9.Cu") (net 284))
  (segment (start 194.864936 65.120845) (end 195.33549 64.650291) (width 0.16) (layer "In9.Cu") (net 284))
  (segment (start 193.9 76.4) (end 193.4 76.4) (width 0.1) (layer "In9.Cu") (net 284))
  (segment (start 195.5 67.6) (end 196.3 67.6) (width 0.16) (layer "In9.Cu") (net 284))
  (segment (start 194.299248 64.838001) (end 194.299249 64.838001) (width 0.16) (layer "In9.Cu") (net 284))
  (segment (start 194.486959 63.80176) (end 194.41078 63.877938) (width 0.16) (layer "In9.Cu") (net 284))
  (segment (start 195.666726 72.786825) (end 195.666726 72.786826) (width 0.16) (layer "In9.Cu") (net 284))
  (segment (start 195.618335 64.933136) (end 195.147779 65.403688) (width 0.16) (layer "In9.Cu") (net 284))
  (segment (start 194.299248 64.555157) (end 194.769802 64.084603) (width 0.16) (layer "In9.Cu") (net 284))
  (segment (start 195.618335 64.933135) (end 195.618335 64.933136) (width 0.16) (layer "In9.Cu") (net 284))
  (segment (start 194.4 73.7) (end 194.5 73.6) (width 0.16) (layer "In9.Cu") (net 284))
  (segment (start 194.299248 64.555158) (end 194.299248 64.555157) (width 0.16) (layer "In9.Cu") (net 284))
  (segment (start 195.052647 64.367448) (end 194.582091 64.838) (width 0.16) (layer "In9.Cu") (net 284))
  (segment (start 190.386328 62.186328) (end 190.386328 60.960008) (width 0.16) (layer "In9.Cu") (net 284))
  (segment (start 191.65 63.45) (end 190.386328 62.186328) (width 0.16) (layer "In9.Cu") (net 284))
  (segment (start 195.33549 64.367449) (end 195.33549 64.367448) (width 0.16) (layer "In9.Cu") (net 284))
  (arc (start 195.147779 65.403688) (mid 195.006358 65.462267) (end 194.864936 65.403689) (width 0.16) (layer "In9.Cu") (net 284))
  (arc (start 194.769802 63.80176) (mid 194.628381 63.743181) (end 194.486959 63.801759) (width 0.16) (layer "In9.Cu") (net 284))
  (arc (start 195.901178 64.933136) (mid 195.759757 64.874557) (end 195.618335 64.933135) (width 0.16) (layer "In9.Cu") (net 284))
  (arc (start 195.33549 64.650291) (mid 195.394068 64.50887) (end 195.33549 64.367449) (width 0.16) (layer "In9.Cu") (net 284))
  (arc (start 194.582091 64.838) (mid 194.44067 64.896579) (end 194.299248 64.838001) (width 0.16) (layer "In9.Cu") (net 284))
  (arc (start 196.3 66.8) (mid 196.441421 66.741421) (end 196.5 66.6) (width 0.16) (layer "In9.Cu") (net 284))
  (arc (start 195.33549 64.367448) (mid 195.194069 64.308869) (end 195.052647 64.367447) (width 0.16) (layer "In9.Cu") (net 284))
  (arc (start 196.1 66.4) (mid 195.958579 66.341421) (end 195.9 66.2) (width 0.16) (layer "In9.Cu") (net 284))
  (arc (start 194.299249 64.838001) (mid 194.24067 64.69658) (end 194.299248 64.555158) (width 0.16) (layer "In9.Cu") (net 284))
  (arc (start 196.5 68.2) (mid 196.441421 68.058579) (end 196.3 68) (width 0.16) (layer "In9.Cu") (net 284))
  (arc (start 195.901178 65.215978) (mid 195.959756 65.074556) (end 195.901177 64.933135) (width 0.16) (layer "In9.Cu") (net 284))
  (arc (start 196.5 69) (mid 196.441421 68.858579) (end 196.3 68.8) (width 0.16) (layer "In9.Cu") (net 284))
  (arc (start 195.63137 72.75147) (mid 195.572792 72.610048) (end 195.631371 72.468627) (width 0.16) (layer "In9.Cu") (net 284))
  (arc (start 194.5 73.6) (mid 194.641421 73.541422) (end 194.782842 73.6) (width 0.16) (layer "In9.Cu") (net 284))
  (arc (start 196.3 68.4) (mid 196.441421 68.341421) (end 196.5 68.2) (width 0.16) (layer "In9.Cu") (net 284))
  (arc (start 195.825 65.575) (mid 195.766421 65.433579) (end 195.824999 65.292157) (width 0.16) (layer "In9.Cu") (net 284))
  (arc (start 194.769802 64.084603) (mid 194.82838 63.943182) (end 194.769802 63.801761) (width 0.16) (layer "In9.Cu") (net 284))
  (arc (start 195.666726 73.069669) (mid 195.725305 72.928247) (end 195.666726 72.786825) (width 0.16) (layer "In9.Cu") (net 284))
  (arc (start 195.5 67.2) (mid 195.358579 67.141421) (end 195.3 67) (width 0.16) (layer "In9.Cu") (net 284))
  (arc (start 196.3 67.6) (mid 196.441421 67.541421) (end 196.5 67.4) (width 0.16) (layer "In9.Cu") (net 284))
  (arc (start 195.383883 73.069669) (mid 195.525304 73.128248) (end 195.666726 73.06967) (width 0.16) (layer "In9.Cu") (net 284))
  (arc (start 196.5 67.4) (mid 196.441421 67.258579) (end 196.3 67.2) (width 0.16) (layer "In9.Cu") (net 284))
  (arc (start 195.5 68) (mid 195.358579 67.941421) (end 195.3 67.8) (width 0.16) (layer "In9.Cu") (net 284))
  (arc (start 195.3 67) (mid 195.358579 66.858579) (end 195.5 66.8) (width 0.16) (layer "In9.Cu") (net 284))
  (arc (start 195.3 67.8) (mid 195.358579 67.658579) (end 195.5 67.6) (width 0.16) (layer "In9.Cu") (net 284))
  (arc (start 194.818197 73.635355) (mid 194.959619 73.693933) (end 195.10104 73.635354) (width 0.16) (layer "In9.Cu") (net 284))
  (arc (start 195.9 69.4) (mid 195.958579 69.258579) (end 196.1 69.2) (width 0.16) (layer "In9.Cu") (net 284))
  (arc (start 196.3 69.2) (mid 196.441421 69.141421) (end 196.5 69) (width 0.16) (layer "In9.Cu") (net 284))
  (arc (start 194.41078 63.877938) (mid 194.269358 63.936516) (end 194.127937 63.877937) (width 0.16) (layer "In9.Cu") (net 284))
  (arc (start 196.5 66.6) (mid 196.441421 66.458579) (end 196.3 66.4) (width 0.16) (layer "In9.Cu") (net 284))
  (arc (start 195.10104 73.635355) (mid 195.159619 73.493933) (end 195.10104 73.352511) (width 0.16) (layer "In9.Cu") (net 284))
  (arc (start 195.5 68.8) (mid 195.358579 68.741421) (end 195.3 68.6) (width 0.16) (layer "In9.Cu") (net 284))
  (arc (start 195.3 68.6) (mid 195.358579 68.458579) (end 195.5 68.4) (width 0.16) (layer "In9.Cu") (net 284))
  (arc (start 194.782844 72.751471) (mid 194.924265 72.692893) (end 195.065688 72.751471) (width 0.16) (layer "In9.Cu") (net 284))
  (arc (start 194.864937 65.403689) (mid 194.806358 65.262268) (end 194.864936 65.120846) (width 0.16) (layer "In9.Cu") (net 284))
  (arc (start 194.782843 73.034315) (mid 194.724266 72.892893) (end 194.782843 72.751473) (width 0.16) (layer "In9.Cu") (net 284))
  (segment (start 195.636328 77.060008) (end 195.655836 77.060008) (width 0.127) (layer "F.Cu") (net 285))
  (segment (start 195.136328 77.560008) (end 195.636328 77.060008) (width 0.127) (layer "F.Cu") (net 285))
  (segment (start 216.036328 59.660008) (end 216.036328 60.960008) (width 0.2) (layer "F.Cu") (net 285))
  (via blind (at 216.036328 60.960008) (size 0.5) (drill 0.2) (layers "F.Cu" "In5.Cu") (net 285))
  (via blind (at 195.655836 77.060008) (size 0.5) (drill 0.2) (layers "F.Cu" "In5.Cu") (net 285))
  (segment (start 196.45 75.525) (end 196.45 75.9) (width 0.09) (layer "In5.Cu") (net 285))
  (segment (start 199.310596 71.589407) (end 199.6 71.3) (width 0.146) (layer "In5.Cu") (net 285))
  (segment (start 209.15 71.3) (end 216.07 64.38) (width 0.146) (layer "In5.Cu") (net 285))
  (segment (start 196.45 75.525) (end 196.45 74.45) (width 0.146) (layer "In5.Cu") (net 285))
  (segment (start 216.07 64.38) (end 216.07 60.99368) (width 0.146) (layer "In5.Cu") (net 285))
  (segment (start 196.983854 73.399257) (end 197.500744 73.916146) (width 0.146) (layer "In5.Cu") (net 285))
  (segment (start 198.256652 72.12646) (end 198.256652 72.126459) (width 0.146) (layer "In5.Cu") (net 285))
  (segment (start 196.983854 73.399258) (end 196.983854 73.399257) (width 0.146) (layer "In5.Cu") (net 285))
  (segment (start 197.620253 72.762858) (end 198.137143 73.279747) (width 0.146) (layer "In5.Cu") (net 285))
  (segment (start 216.07 60.99368) (end 216.036328 60.960008) (width 0.146) (layer "In5.Cu") (net 285))
  (segment (start 199.09174 72.325148) (end 199.09174 72.325149) (width 0.146) (layer "In5.Cu") (net 285))
  (segment (start 197.620253 72.762859) (end 197.620253 72.762858) (width 0.146) (layer "In5.Cu") (net 285))
  (segment (start 195.655836 76.694164) (end 195.655836 77.060008) (width 0.09) (layer "In5.Cu") (net 285))
  (segment (start 199.6 71.3) (end 209.15 71.3) (width 0.146) (layer "In5.Cu") (net 285))
  (segment (start 198.455341 72.961548) (end 197.938452 72.444658) (width 0.146) (layer "In5.Cu") (net 285))
  (segment (start 197.818942 73.597946) (end 197.818942 73.597947) (width 0.146) (layer "In5.Cu") (net 285))
  (segment (start 198.893051 71.49006) (end 198.992398 71.589407) (width 0.146) (layer "In5.Cu") (net 285))
  (segment (start 196.765 73.816802) (end 196.665654 73.717456) (width 0.146) (layer "In5.Cu") (net 285))
  (segment (start 196.45 74.45) (end 196.765 74.135) (width 0.146) (layer "In5.Cu") (net 285))
  (segment (start 196.45 75.9) (end 195.655836 76.694164) (width 0.09) (layer "In5.Cu") (net 285))
  (segment (start 199.09174 72.325149) (end 198.574851 71.808259) (width 0.146) (layer "In5.Cu") (net 285))
  (segment (start 198.256652 72.126459) (end 198.773542 72.643348) (width 0.146) (layer "In5.Cu") (net 285))
  (segment (start 198.893051 71.490061) (end 198.893051 71.49006) (width 0.146) (layer "In5.Cu") (net 285))
  (segment (start 198.455341 72.961547) (end 198.455341 72.961548) (width 0.146) (layer "In5.Cu") (net 285))
  (segment (start 197.818942 73.597947) (end 197.302053 73.081057) (width 0.146) (layer "In5.Cu") (net 285))
  (arc (start 197.938452 72.12646) (mid 198.097553 72.060558) (end 198.256652 72.12646) (width 0.146) (layer "In5.Cu") (net 285))
  (arc (start 198.992398 71.589407) (mid 199.151497 71.655308) (end 199.310596 71.589407) (width 0.146) (layer "In5.Cu") (net 285))
  (arc (start 196.665654 73.717456) (mid 196.599753 73.558357) (end 196.665654 73.399258) (width 0.146) (layer "In5.Cu") (net 285))
  (arc (start 196.665654 73.399258) (mid 196.824755 73.333356) (end 196.983854 73.399258) (width 0.146) (layer "In5.Cu") (net 285))
  (arc (start 198.455341 73.279747) (mid 198.521242 73.120647) (end 198.455341 72.961547) (width 0.146) (layer "In5.Cu") (net 285))
  (arc (start 198.574851 71.490061) (mid 198.733952 71.424159) (end 198.893051 71.490061) (width 0.146) (layer "In5.Cu") (net 285))
  (arc (start 198.773542 72.643348) (mid 198.932641 72.709249) (end 199.09174 72.643348) (width 0.146) (layer "In5.Cu") (net 285))
  (arc (start 197.938452 72.444658) (mid 197.872551 72.285559) (end 197.938452 72.12646) (width 0.146) (layer "In5.Cu") (net 285))
  (arc (start 198.137143 73.279747) (mid 198.296242 73.345648) (end 198.455341 73.279747) (width 0.146) (layer "In5.Cu") (net 285))
  (arc (start 197.500744 73.916146) (mid 197.659843 73.982047) (end 197.818942 73.916146) (width 0.146) (layer "In5.Cu") (net 285))
  (arc (start 198.574851 71.808259) (mid 198.50895 71.64916) (end 198.574851 71.490061) (width 0.146) (layer "In5.Cu") (net 285))
  (arc (start 199.09174 72.643348) (mid 199.157641 72.484248) (end 199.09174 72.325148) (width 0.146) (layer "In5.Cu") (net 285))
  (arc (start 197.818942 73.916146) (mid 197.884843 73.757046) (end 197.818942 73.597946) (width 0.146) (layer "In5.Cu") (net 285))
  (arc (start 197.302053 73.081057) (mid 197.236152 72.921958) (end 197.302053 72.762859) (width 0.146) (layer "In5.Cu") (net 285))
  (arc (start 197.302053 72.762859) (mid 197.461154 72.696957) (end 197.620253 72.762859) (width 0.146) (layer "In5.Cu") (net 285))
  (arc (start 196.765 74.135) (mid 196.830901 73.975901) (end 196.765 73.816802) (width 0.146) (layer "In5.Cu") (net 285))
  (segment (start 196.136328 78.560008) (end 196.636328 78.060008) (width 0.127) (layer "F.Cu") (net 286))
  (segment (start 196.636328 78.060008) (end 196.655836 78.060008) (width 0.127) (layer "F.Cu") (net 286))
  (segment (start 217.736328 59.660008) (end 217.736328 60.960008) (width 0.2) (layer "F.Cu") (net 286))
  (via blind (at 217.736328 60.960008) (size 0.5) (drill 0.2) (layers "F.Cu" "In2.Cu") (net 286))
  (via blind (at 196.655836 78.060008) (size 0.5) (drill 0.2) (layers "F.Cu" "In2.Cu") (net 286))
  (segment (start 204.829899 75.418629) (end 204.829899 75.418628) (width 0.16) (layer "In2.Cu") (net 286))
  (segment (start 204.052081 76.196447) (end 204.052081 76.196446) (width 0.16) (layer "In2.Cu") (net 286))
  (segment (start 206.385535 73.862993) (end 206.385535 73.862992) (width 0.16) (layer "In2.Cu") (net 286))
  (segment (start 204.052081 75.807537) (end 203.592463 75.347919) (width 0.16) (layer "In2.Cu") (net 286))
  (segment (start 204.75919 74.181192) (end 205.218808 74.64081) (width 0.16) (layer "In2.Cu") (net 286))
  (segment (start 205.925916 72.625556) (end 205.925918 72.625555) (width 0.16) (layer "In2.Cu") (net 286))
  (segment (start 206.939856 72.460144) (end 209.2 70.2) (width 0.16) (layer "In2.Cu") (net 286))
  (segment (start 211.321328 67.654409) (end 211.745592 68.078672) (width 0.16) (layer "In2.Cu") (net 286))
  (segment (start 202.85 76.161092) (end 202.814645 76.125737) (width 0.16) (layer "In2.Cu") (net 286))
  (segment (start 204.052081 75.807536) (end 204.052081 75.807537) (width 0.16) (layer "In2.Cu") (net 286))
  (segment (start 213.199998 65.775736) (end 213.199999 65.775735) (width 0.16) (layer "In2.Cu") (net 286))
  (segment (start 210.472797 68.502941) (end 210.472797 68.50294) (width 0.16) (layer "In2.Cu") (net 286))
  (segment (start 214.488091 65.366769) (end 214.472791 65.351469) (width 0.16) (layer "In2.Cu") (net 286))
  (segment (start 203.203554 75.736828) (end 203.663172 76.196446) (width 0.16) (layer "In2.Cu") (net 286))
  (segment (start 202.814646 75.736828) (end 202.814646 75.736827) (width 0.16) (layer "In2.Cu") (net 286))
  (segment (start 213.538255 65.265462) (end 214.063827 65.791033) (width 0.16) (layer "In2.Cu") (net 286))
  (segment (start 213.199999 65.775735) (end 213.113989 65.689725) (width 0.16) (layer "In2.Cu") (net 286))
  (segment (start 210.472794 69.351469) (end 210.048531 68.927205) (width 0.16) (layer "In2.Cu") (net 286))
  (segment (start 214.488091 65.791033) (end 214.488091 65.791034) (width 0.16) (layer "In2.Cu") (net 286))
  (segment (start 212.169856 67.654406) (end 212.169856 67.654407) (width 0.16) (layer "In2.Cu") (net 286))
  (segment (start 205.148098 73.403374) (end 205.1481 73.403373) (width 0.16) (layer "In2.Cu") (net 286))
  (segment (start 204.37028 74.181192) (end 204.370282 74.181191) (width 0.16) (layer "In2.Cu") (net 286))
  (segment (start 205.607717 74.2519) (end 205.607717 74.251901) (width 0.16) (layer "In2.Cu") (net 286))
  (segment (start 205.53701 73.403373) (end 205.537008 73.403374) (width 0.16) (layer "In2.Cu") (net 286))
  (segment (start 204.759192 74.181191) (end 204.75919 74.181192) (width 0.16) (layer "In2.Cu") (net 286))
  (segment (start 209.624266 69.351472) (end 209.624266 69.351471) (width 0.16) (layer "In2.Cu") (net 286))
  (segment (start 196.655836 78.060008) (end 198.2 78.060008) (width 0.1) (layer "In2.Cu") (net 286))
  (segment (start 214.472791 64.927205) (end 215.391792 64.008208) (width 0.16) (layer "In2.Cu") (net 286))
  (segment (start 205.537008 73.403374) (end 205.996626 73.862992) (width 0.16) (layer "In2.Cu") (net 286))
  (segment (start 206.314828 72.625555) (end 206.314826 72.625556) (width 0.16) (layer "In2.Cu") (net 286))
  (segment (start 206.739091 72.660911) (end 206.739092 72.660911) (width 0.16) (layer "In2.Cu") (net 286))
  (segment (start 204.829899 75.029719) (end 204.370281 74.570101) (width 0.16) (layer "In2.Cu") (net 286))
  (segment (start 198.2 78.060008) (end 198.860008 78.060008) (width 0.16) (layer "In2.Cu") (net 286))
  (segment (start 211.321328 67.65441) (end 211.321328 67.654409) (width 0.16) (layer "In2.Cu") (net 286))
  (segment (start 206.385535 73.474083) (end 205.925917 73.014465) (width 0.16) (layer "In2.Cu") (net 286))
  (segment (start 212.169856 67.230142) (end 213.199999 66.199999) (width 0.16) (layer "In2.Cu") (net 286))
  (segment (start 198.860008 78.060008) (end 200.220016 76.7) (width 0.16) (layer "In2.Cu") (net 286))
  (segment (start 217.736328 61.663672) (end 217.736328 60.960008) (width 0.16) (layer "In2.Cu") (net 286))
  (segment (start 206.314826 72.625556) (end 206.350182 72.660912) (width 0.16) (layer "In2.Cu") (net 286))
  (segment (start 206.739092 72.660911) (end 206.939856 72.460144) (width 0.16) (layer "In2.Cu") (net 286))
  (segment (start 210.472794 69.351468) (end 210.472794 69.351469) (width 0.16) (layer "In2.Cu") (net 286))
  (segment (start 212.169855 67.230142) (end 212.169856 67.230142) (width 0.16) (layer "In2.Cu") (net 286))
  (segment (start 209.200001 69.351471) (end 209.2 69.351472) (width 0.16) (layer "In2.Cu") (net 286))
  (segment (start 211.321325 68.502938) (end 210.897062 68.078674) (width 0.16) (layer "In2.Cu") (net 286))
  (segment (start 209.624266 69.351471) (end 210.04853 69.775734) (width 0.16) (layer "In2.Cu") (net 286))
  (segment (start 211.321325 68.502937) (end 211.321325 68.502938) (width 0.16) (layer "In2.Cu") (net 286))
  (segment (start 200.220016 76.7) (end 202.7 76.7) (width 0.16) (layer "In2.Cu") (net 286))
  (segment (start 206.385535 73.474082) (end 206.385535 73.474083) (width 0.16) (layer "In2.Cu") (net 286))
  (segment (start 203.203556 75.736827) (end 203.203554 75.736828) (width 0.16) (layer "In2.Cu") (net 286))
  (segment (start 205.607717 74.640811) (end 205.607717 74.64081) (width 0.16) (layer "In2.Cu") (net 286))
  (segment (start 204.829899 75.029718) (end 204.829899 75.029719) (width 0.16) (layer "In2.Cu") (net 286))
  (segment (start 203.592462 74.95901) (end 203.592464 74.959009) (width 0.16) (layer "In2.Cu") (net 286))
  (segment (start 203.981374 74.959009) (end 203.981372 74.95901) (width 0.16) (layer "In2.Cu") (net 286))
  (segment (start 203.981372 74.95901) (end 204.44099 75.418628) (width 0.16) (layer "In2.Cu") (net 286))
  (segment (start 205.607717 74.251901) (end 205.148099 73.792283) (width 0.16) (layer "In2.Cu") (net 286))
  (segment (start 210.472797 68.50294) (end 210.897061 68.927203) (width 0.16) (layer "In2.Cu") (net 286))
  (segment (start 215.391792 64.008208) (end 217.736328 61.663672) (width 0.16) (layer "In2.Cu") (net 286))
  (segment (start 202.7 76.7) (end 202.85 76.55) (width 0.16) (layer "In2.Cu") (net 286))
  (segment (start 214.488092 65.366769) (end 214.488091 65.366769) (width 0.16) (layer "In2.Cu") (net 286))
  (segment (start 213.538254 65.26546) (end 213.538255 65.265462) (width 0.16) (layer "In2.Cu") (net 286))
  (arc (start 204.370281 74.570101) (mid 204.289735 74.375647) (end 204.37028 74.181192) (width 0.16) (layer "In2.Cu") (net 286))
  (arc (start 205.1481 73.403373) (mid 205.342554 73.322828) (end 205.53701 73.403373) (width 0.16) (layer "In2.Cu") (net 286))
  (arc (start 203.592463 75.347919) (mid 203.511917 75.153465) (end 203.592462 74.95901) (width 0.16) (layer "In2.Cu") (net 286))
  (arc (start 210.897061 68.927203) (mid 211.109193 69.015071) (end 211.321325 68.927203) (width 0.16) (layer "In2.Cu") (net 286))
  (arc (start 206.385535 73.862992) (mid 206.466081 73.668537) (end 206.385535 73.474082) (width 0.16) (layer "In2.Cu") (net 286))
  (arc (start 214.488091 65.791034) (mid 214.57596 65.578902) (end 214.488092 65.366769) (width 0.16) (layer "In2.Cu") (net 286))
  (arc (start 204.44099 75.418628) (mid 204.635444 75.499174) (end 204.829899 75.418629) (width 0.16) (layer "In2.Cu") (net 286))
  (arc (start 205.925918 72.625555) (mid 206.120372 72.54501) (end 206.314828 72.625555) (width 0.16) (layer "In2.Cu") (net 286))
  (arc (start 206.350182 72.660912) (mid 206.544637 72.741457) (end 206.739091 72.660911) (width 0.16) (layer "In2.Cu") (net 286))
  (arc (start 209.2 69.351472) (mid 209.412134 69.263603) (end 209.624266 69.351472) (width 0.16) (layer "In2.Cu") (net 286))
  (arc (start 214.472791 65.351469) (mid 214.384923 65.139337) (end 214.472791 64.927205) (width 0.16) (layer "In2.Cu") (net 286))
  (arc (start 202.814646 75.736827) (mid 203.0091 75.656282) (end 203.203556 75.736827) (width 0.16) (layer "In2.Cu") (net 286))
  (arc (start 212.169856 67.654407) (mid 212.081987 67.442275) (end 212.169855 67.230142) (width 0.16) (layer "In2.Cu") (net 286))
  (arc (start 204.052081 76.196446) (mid 204.132627 76.001991) (end 204.052081 75.807536) (width 0.16) (layer "In2.Cu") (net 286))
  (arc (start 210.048531 68.927205) (mid 209.960663 68.715073) (end 210.048531 68.502941) (width 0.16) (layer "In2.Cu") (net 286))
  (arc (start 205.607717 74.64081) (mid 205.688263 74.446355) (end 205.607717 74.2519) (width 0.16) (layer "In2.Cu") (net 286))
  (arc (start 210.472794 69.775734) (mid 210.560662 69.563601) (end 210.472794 69.351468) (width 0.16) (layer "In2.Cu") (net 286))
  (arc (start 211.745592 68.078672) (mid 211.957724 68.16654) (end 212.169856 68.078672) (width 0.16) (layer "In2.Cu") (net 286))
  (arc (start 209.2 70.2) (mid 209.287868 69.987868) (end 209.2 69.775736) (width 0.16) (layer "In2.Cu") (net 286))
  (arc (start 202.85 76.55) (mid 202.930546 76.355545) (end 202.85 76.161092) (width 0.16) (layer "In2.Cu") (net 286))
  (arc (start 203.663172 76.196446) (mid 203.857626 76.276992) (end 204.052081 76.196447) (width 0.16) (layer "In2.Cu") (net 286))
  (arc (start 214.063827 65.791033) (mid 214.275959 65.878901) (end 214.488091 65.791033) (width 0.16) (layer "In2.Cu") (net 286))
  (arc (start 210.897062 67.65441) (mid 211.109196 67.566541) (end 211.321328 67.65441) (width 0.16) (layer "In2.Cu") (net 286))
  (arc (start 204.829899 75.418628) (mid 204.910445 75.224173) (end 204.829899 75.029718) (width 0.16) (layer "In2.Cu") (net 286))
  (arc (start 210.048531 68.502941) (mid 210.260665 68.415072) (end 210.472797 68.502941) (width 0.16) (layer "In2.Cu") (net 286))
  (arc (start 205.218808 74.64081) (mid 205.413262 74.721356) (end 205.607717 74.640811) (width 0.16) (layer "In2.Cu") (net 286))
  (arc (start 203.592464 74.959009) (mid 203.786918 74.878464) (end 203.981374 74.959009) (width 0.16) (layer "In2.Cu") (net 286))
  (arc (start 210.897062 68.078674) (mid 210.809194 67.866542) (end 210.897062 67.65441) (width 0.16) (layer "In2.Cu") (net 286))
  (arc (start 212.169856 68.078672) (mid 212.257724 67.866539) (end 212.169856 67.654406) (width 0.16) (layer "In2.Cu") (net 286))
  (arc (start 210.04853 69.775734) (mid 210.260662 69.863602) (end 210.472794 69.775734) (width 0.16) (layer "In2.Cu") (net 286))
  (arc (start 213.113989 65.689725) (mid 213.026121 65.477593) (end 213.113989 65.265461) (width 0.16) (layer "In2.Cu") (net 286))
  (arc (start 205.148099 73.792283) (mid 205.067553 73.597829) (end 205.148098 73.403374) (width 0.16) (layer "In2.Cu") (net 286))
  (arc (start 209.2 69.775736) (mid 209.112133 69.563602) (end 209.200001 69.351471) (width 0.16) (layer "In2.Cu") (net 286))
  (arc (start 205.996626 73.862992) (mid 206.19108 73.943538) (end 206.385535 73.862993) (width 0.16) (layer "In2.Cu") (net 286))
  (arc (start 202.814645 76.125737) (mid 202.7341 75.931282) (end 202.814646 75.736828) (width 0.16) (layer "In2.Cu") (net 286))
  (arc (start 205.925917 73.014465) (mid 205.845371 72.820011) (end 205.925916 72.625556) (width 0.16) (layer "In2.Cu") (net 286))
  (arc (start 213.113989 65.265461) (mid 213.326122 65.177593) (end 213.538254 65.26546) (width 0.16) (layer "In2.Cu") (net 286))
  (arc (start 211.321325 68.927203) (mid 211.409193 68.71507) (end 211.321325 68.502937) (width 0.16) (layer "In2.Cu") (net 286))
  (arc (start 204.370282 74.181191) (mid 204.564736 74.100646) (end 204.759192 74.181191) (width 0.16) (layer "In2.Cu") (net 286))
  (arc (start 213.199999 66.199999) (mid 213.287867 65.987868) (end 213.199998 65.775736) (width 0.16) (layer "In2.Cu") (net 286))
  (segment (start 208.386328 59.660008) (end 208.386328 60.960008) (width 0.2) (layer "F.Cu") (net 287))
  (segment (start 191.636328 79.060008) (end 191.655836 79.060008) (width 0.127) (layer "F.Cu") (net 287))
  (segment (start 191.136328 79.560008) (end 191.636328 79.060008) (width 0.127) (layer "F.Cu") (net 287))
  (via blind (at 191.655836 79.060008) (size 0.5) (drill 0.2) (layers "F.Cu" "In5.Cu") (net 287))
  (via blind (at 208.386328 60.960008) (size 0.5) (drill 0.2) (layers "F.Cu" "In5.Cu") (net 287))
  (segment (start 189.2 70.86) (end 189.2 68.2) (width 0.146) (layer "In5.Cu") (net 287))
  (segment (start 190.125 78.3) (end 190.45 78.625) (width 0.09) (layer "In5.Cu") (net 287))
  (segment (start 189.2 75.7) (end 189.2 76.925) (width 0.09) (layer "In5.Cu") (net 287))
  (segment (start 188.910613 71.61) (end 189.489387 71.61) (width 0.146) (layer "In5.Cu") (net 287))
  (segment (start 188.910613 71.11) (end 188.95 71.11) (width 0.146) (layer "In5.Cu") (net 287))
  (segment (start 188.910613 72.11) (end 189.489387 72.11) (width 0.146) (layer "In5.Cu") (net 287))
  (segment (start 189.489387 74.61) (end 189.45 74.61) (width 0.146) (layer "In5.Cu") (net 287))
  (segment (start 188.910613 74.11) (end 189.489387 74.11) (width 0.146) (layer "In5.Cu") (net 287))
  (segment (start 190.125 77.85) (end 190.125 78.3) (width 0.09) (layer "In5.Cu") (net 287))
  (segment (start 189.2 68.2) (end 194.7 62.7) (width 0.146) (layer "In5.Cu") (net 287))
  (segment (start 189.45 74.61) (end 188.910613 74.61) (width 0.146) (layer "In5.Cu") (net 287))
  (segment (start 188.910613 72.61) (end 189.489387 72.61) (width 0.146) (layer "In5.Cu") (net 287))
  (segment (start 188.910613 73.11) (end 189.489387 73.11) (width 0.146) (layer "In5.Cu") (net 287))
  (segment (start 190.45 78.625) (end 190.875 78.625) (width 0.09) (layer "In5.Cu") (net 287))
  (segment (start 189.2 76.925) (end 190.125 77.85) (width 0.09) (layer "In5.Cu") (net 287))
  (segment (start 188.910613 73.61) (end 189.489387 73.61) (width 0.146) (layer "In5.Cu") (net 287))
  (segment (start 189.2 75.7) (end 189.2 75.36) (width 0.146) (layer "In5.Cu") (net 287))
  (segment (start 189.45 75.11) (end 189.489387 75.11) (width 0.146) (layer "In5.Cu") (net 287))
  (segment (start 194.7 62.7) (end 206.646336 62.7) (width 0.146) (layer "In5.Cu") (net 287))
  (segment (start 190.875 78.625) (end 191.310008 79.060008) (width 0.09) (layer "In5.Cu") (net 287))
  (segment (start 191.310008 79.060008) (end 191.655836 79.060008) (width 0.09) (layer "In5.Cu") (net 287))
  (segment (start 206.646336 62.7) (end 208.386328 60.960008) (width 0.146) (layer "In5.Cu") (net 287))
  (arc (start 188.910613 71.61) (mid 188.733836 71.536777) (end 188.660613 71.36) (width 0.146) (layer "In5.Cu") (net 287))
  (arc (start 188.660613 74.36) (mid 188.733836 74.183223) (end 188.910613 74.11) (width 0.146) (layer "In5.Cu") (net 287))
  (arc (start 188.910613 73.61) (mid 188.733836 73.536777) (end 188.660613 73.36) (width 0.146) (layer "In5.Cu") (net 287))
  (arc (start 188.660613 71.36) (mid 188.733836 71.183223) (end 188.910613 71.11) (width 0.146) (layer "In5.Cu") (net 287))
  (arc (start 188.95 71.11) (mid 189.126777 71.036777) (end 189.2 70.86) (width 0.146) (layer "In5.Cu") (net 287))
  (arc (start 189.489387 73.11) (mid 189.666164 73.036777) (end 189.739387 72.86) (width 0.146) (layer "In5.Cu") (net 287))
  (arc (start 189.739387 73.86) (mid 189.666164 73.683223) (end 189.489387 73.61) (width 0.146) (layer "In5.Cu") (net 287))
  (arc (start 189.739387 74.86) (mid 189.666164 74.683223) (end 189.489387 74.61) (width 0.146) (layer "In5.Cu") (net 287))
  (arc (start 189.739387 71.86) (mid 189.666164 71.683223) (end 189.489387 71.61) (width 0.146) (layer "In5.Cu") (net 287))
  (arc (start 189.739387 72.86) (mid 189.666164 72.683223) (end 189.489387 72.61) (width 0.146) (layer "In5.Cu") (net 287))
  (arc (start 188.660613 72.36) (mid 188.733836 72.183223) (end 188.910613 72.11) (width 0.146) (layer "In5.Cu") (net 287))
  (arc (start 188.910613 72.61) (mid 188.733836 72.536777) (end 188.660613 72.36) (width 0.146) (layer "In5.Cu") (net 287))
  (arc (start 189.489387 72.11) (mid 189.666164 72.036777) (end 189.739387 71.86) (width 0.146) (layer "In5.Cu") (net 287))
  (arc (start 189.489387 74.11) (mid 189.666164 74.036777) (end 189.739387 73.86) (width 0.146) (layer "In5.Cu") (net 287))
  (arc (start 188.910613 74.61) (mid 188.733836 74.536777) (end 188.660613 74.36) (width 0.146) (layer "In5.Cu") (net 287))
  (arc (start 189.2 75.36) (mid 189.273223 75.183223) (end 189.45 75.11) (width 0.146) (layer "In5.Cu") (net 287))
  (arc (start 189.489387 75.11) (mid 189.666164 75.036777) (end 189.739387 74.86) (width 0.146) (layer "In5.Cu") (net 287))
  (arc (start 188.660613 73.36) (mid 188.733836 73.183223) (end 188.910613 73.11) (width 0.146) (layer "In5.Cu") (net 287))
  (segment (start 191.636328 85.060008) (end 191.655836 85.060008) (width 0.127) (layer "F.Cu") (net 288))
  (segment (start 242.386328 59.660008) (end 242.386328 60.960008) (width 0.2) (layer "F.Cu") (net 288))
  (segment (start 191.136328 85.560008) (end 191.636328 85.060008) (width 0.127) (layer "F.Cu") (net 288))
  (via (at 242.386328 60.960008) (size 0.5) (drill 0.2) (layers "F.Cu" "B.Cu") (net 288))
  (via (at 191.655836 85.060008) (size 0.5) (drill 0.2) (layers "F.Cu" "B.Cu") (net 288))
  (segment (start 212.251908 81.288116) (end 212.251908 81.288115) (width 0.16) (layer "In9.Cu") (net 288))
  (segment (start 206.78 85.65) (end 206.83 85.65) (width 0.16) (layer "In9.Cu") (net 288))
  (segment (start 204.1 84.9) (end 204.45 85.25) (width 0.16) (layer "In9.Cu") (net 288))
  (segment (start 214.272882 80.127095) (end 214.216991 80.071204) (width 0.16) (layer "In9.Cu") (net 288))
  (segment (start 204.98 85.65) (end 205.03 85.65) (width 0.16) (layer "In9.Cu") (net 288))
  (segment (start 206.58 85.05) (end 206.58 85.45) (width 0.16) (layer "In9.Cu") (net 288))
  (segment (start 210.89 83.08) (end 211.035 82.935) (width 0.16) (layer "In9.Cu") (net 288))
  (segment (start 214.216991 79.753006) (end 214.5 79.469997) (width 0.16) (layer "In9.Cu") (net 288))
  (segment (start 242.386328 67.413672) (end 242.386328 60.960008) (width 0.16) (layer "In9.Cu") (net 288))
  (segment (start 205.68 85.05) (end 205.68 85.45) (width 0.16) (layer "In9.Cu") (net 288))
  (segment (start 207.23 85.25) (end 207.5 85.25) (width 0.16) (layer "In9.Cu") (net 288))
  (segment (start 212.363685 82.036291) (end 212.363685 82.036292) (width 0.16) (layer "In9.Cu") (net 288))
  (segment (start 194.535 84.9) (end 193.865 85.57) (width 0.1) (layer "In9.Cu") (net 288))
  (segment (start 211.615509 81.924514) (end 212.045487 82.354491) (width 0.16) (layer "In9.Cu") (net 288))
  (segment (start 211.615509 81.924515) (end 211.615509 81.924514) (width 0.16) (layer "In9.Cu") (net 288))
  (segment (start 212.251908 81.288115) (end 212.681886 81.718092) (width 0.16) (layer "In9.Cu") (net 288))
  (segment (start 213.524706 80.015318) (end 213.524706 80.015317) (width 0.16) (layer "In9.Cu") (net 288))
  (segment (start 205.88 85.65) (end 205.93 85.65) (width 0.16) (layer "In9.Cu") (net 288))
  (segment (start 213.000084 81.399893) (end 212.570107 80.969915) (width 0.16) (layer "In9.Cu") (net 288))
  (segment (start 198.2 84.9) (end 194.535 84.9) (width 0.1) (layer "In9.Cu") (net 288))
  (segment (start 213.636483 80.763493) (end 213.636483 80.763494) (width 0.16) (layer "In9.Cu") (net 288))
  (segment (start 192.165828 85.57) (end 191.655836 85.060008) (width 0.1) (layer "In9.Cu") (net 288))
  (segment (start 205.23 85.45) (end 205.23 85.05) (width 0.16) (layer "In9.Cu") (net 288))
  (segment (start 214.5 79.469997) (end 214.5 78.88) (width 0.16) (layer "In9.Cu") (net 288))
  (segment (start 211.353198 82.935) (end 211.409088 82.99089) (width 0.16) (layer "In9.Cu") (net 288))
  (segment (start 212.363685 82.036292) (end 211.933708 81.606314) (width 0.16) (layer "In9.Cu") (net 288))
  (segment (start 213.636483 80.763494) (end 213.206506 80.333516) (width 0.16) (layer "In9.Cu") (net 288))
  (segment (start 213.524706 80.015317) (end 213.954684 80.445294) (width 0.16) (layer "In9.Cu") (net 288))
  (segment (start 214.272882 80.127094) (end 214.272882 80.127095) (width 0.16) (layer "In9.Cu") (net 288))
  (segment (start 212.888307 80.651716) (end 213.318285 81.081693) (width 0.16) (layer "In9.Cu") (net 288))
  (segment (start 206.13 85.45) (end 206.13 85.05) (width 0.16) (layer "In9.Cu") (net 288))
  (segment (start 212.888307 80.651717) (end 212.888307 80.651716) (width 0.16) (layer "In9.Cu") (net 288))
  (segment (start 207.5 85.25) (end 209.67 83.08) (width 0.16) (layer "In9.Cu") (net 288))
  (segment (start 198.2 84.9) (end 204.1 84.9) (width 0.16) (layer "In9.Cu") (net 288))
  (segment (start 236.8 73) (end 242.386328 67.413672) (width 0.16) (layer "In9.Cu") (net 288))
  (segment (start 206.33 84.85) (end 206.38 84.85) (width 0.16) (layer "In9.Cu") (net 288))
  (segment (start 193.865 85.57) (end 192.165828 85.57) (width 0.1) (layer "In9.Cu") (net 288))
  (segment (start 213.000084 81.399892) (end 213.000084 81.399893) (width 0.16) (layer "In9.Cu") (net 288))
  (segment (start 204.45 85.25) (end 204.58 85.25) (width 0.16) (layer "In9.Cu") (net 288))
  (segment (start 209.67 83.08) (end 210.89 83.08) (width 0.16) (layer "In9.Cu") (net 288))
  (segment (start 214.5 78.88) (end 220.38 73) (width 0.16) (layer "In9.Cu") (net 288))
  (segment (start 211.727286 82.67269) (end 211.727286 82.672691) (width 0.16) (layer "In9.Cu") (net 288))
  (segment (start 205.43 84.85) (end 205.48 84.85) (width 0.16) (layer "In9.Cu") (net 288))
  (segment (start 220.38 73) (end 236.8 73) (width 0.16) (layer "In9.Cu") (net 288))
  (segment (start 211.727286 82.672691) (end 211.297309 82.242713) (width 0.16) (layer "In9.Cu") (net 288))
  (arc (start 213.636483 81.081693) (mid 213.702384 80.922593) (end 213.636483 80.763493) (width 0.16) (layer "In9.Cu") (net 288))
  (arc (start 212.681886 81.718092) (mid 212.840985 81.783993) (end 213.000084 81.718092) (width 0.16) (layer "In9.Cu") (net 288))
  (arc (start 204.58 85.25) (mid 204.721421 85.308579) (end 204.78 85.45) (width 0.16) (layer "In9.Cu") (net 288))
  (arc (start 205.23 85.05) (mid 205.288579 84.908579) (end 205.43 84.85) (width 0.16) (layer "In9.Cu") (net 288))
  (arc (start 213.206506 80.333516) (mid 213.140605 80.174417) (end 213.206506 80.015318) (width 0.16) (layer "In9.Cu") (net 288))
  (arc (start 206.38 84.85) (mid 206.521421 84.908579) (end 206.58 85.05) (width 0.16) (layer "In9.Cu") (net 288))
  (arc (start 212.570107 80.651717) (mid 212.729208 80.585815) (end 212.888307 80.651717) (width 0.16) (layer "In9.Cu") (net 288))
  (arc (start 211.297309 82.242713) (mid 211.231408 82.083614) (end 211.297309 81.924515) (width 0.16) (layer "In9.Cu") (net 288))
  (arc (start 205.68 85.45) (mid 205.738579 85.591421) (end 205.88 85.65) (width 0.16) (layer "In9.Cu") (net 288))
  (arc (start 213.206506 80.015318) (mid 213.365607 79.949416) (end 213.524706 80.015318) (width 0.16) (layer "In9.Cu") (net 288))
  (arc (start 206.13 85.05) (mid 206.188579 84.908579) (end 206.33 84.85) (width 0.16) (layer "In9.Cu") (net 288))
  (arc (start 212.045487 82.354491) (mid 212.204586 82.420392) (end 212.363685 82.354491) (width 0.16) (layer "In9.Cu") (net 288))
  (arc (start 213.318285 81.081693) (mid 213.477384 81.147594) (end 213.636483 81.081693) (width 0.16) (layer "In9.Cu") (net 288))
  (arc (start 205.48 84.85) (mid 205.621421 84.908579) (end 205.68 85.05) (width 0.16) (layer "In9.Cu") (net 288))
  (arc (start 214.272882 80.445294) (mid 214.338783 80.286194) (end 214.272882 80.127094) (width 0.16) (layer "In9.Cu") (net 288))
  (arc (start 211.409088 82.99089) (mid 211.568187 83.056791) (end 211.727286 82.99089) (width 0.16) (layer "In9.Cu") (net 288))
  (arc (start 205.03 85.65) (mid 205.171421 85.591421) (end 205.23 85.45) (width 0.16) (layer "In9.Cu") (net 288))
  (arc (start 213.954684 80.445294) (mid 214.113783 80.511195) (end 214.272882 80.445294) (width 0.16) (layer "In9.Cu") (net 288))
  (arc (start 205.93 85.65) (mid 206.071421 85.591421) (end 206.13 85.45) (width 0.16) (layer "In9.Cu") (net 288))
  (arc (start 211.933708 81.606314) (mid 211.867807 81.447215) (end 211.933708 81.288116) (width 0.16) (layer "In9.Cu") (net 288))
  (arc (start 211.297309 81.924515) (mid 211.45641 81.858613) (end 211.615509 81.924515) (width 0.16) (layer "In9.Cu") (net 288))
  (arc (start 211.933708 81.288116) (mid 212.092809 81.222214) (end 212.251908 81.288116) (width 0.16) (layer "In9.Cu") (net 288))
  (arc (start 213.000084 81.718092) (mid 213.065985 81.558992) (end 213.000084 81.399892) (width 0.16) (layer "In9.Cu") (net 288))
  (arc (start 211.035 82.935) (mid 211.194099 82.869099) (end 211.353198 82.935) (width 0.16) (layer "In9.Cu") (net 288))
  (arc (start 204.78 85.45) (mid 204.838579 85.591421) (end 204.98 85.65) (width 0.16) (layer "In9.Cu") (net 288))
  (arc (start 206.58 85.45) (mid 206.638579 85.591421) (end 206.78 85.65) (width 0.16) (layer "In9.Cu") (net 288))
  (arc (start 212.363685 82.354491) (mid 212.429586 82.195391) (end 212.363685 82.036291) (width 0.16) (layer "In9.Cu") (net 288))
  (arc (start 207.03 85.45) (mid 207.088579 85.308579) (end 207.23 85.25) (width 0.16) (layer "In9.Cu") (net 288))
  (arc (start 214.216991 80.071204) (mid 214.151089 79.912104) (end 214.216991 79.753006) (width 0.16) (layer "In9.Cu") (net 288))
  (arc (start 211.727286 82.99089) (mid 211.793187 82.83179) (end 211.727286 82.67269) (width 0.16) (layer "In9.Cu") (net 288))
  (arc (start 212.570107 80.969915) (mid 212.504206 80.810816) (end 212.570107 80.651717) (width 0.16) (layer "In9.Cu") (net 288))
  (arc (start 206.83 85.65) (mid 206.971421 85.591421) (end 207.03 85.45) (width 0.16) (layer "In9.Cu") (net 288))
  (segment (start 188.636328 80.060008) (end 188.655836 80.060008) (width 0.127) (layer "F.Cu") (net 289))
  (segment (start 187.986328 60.859998) (end 188.086338 60.960008) (width 0.2) (layer "F.Cu") (net 289))
  (segment (start 187.986328 59.660008) (end 187.986328 60.859998) (width 0.2) (layer "F.Cu") (net 289))
  (segment (start 188.136328 80.560008) (end 188.636328 80.060008) (width 0.127) (layer "F.Cu") (net 289))
  (via (at 188.086338 60.960008) (size 0.5) (drill 0.2) (layers "F.Cu" "B.Cu") (net 289))
  (via (at 188.655836 80.060008) (size 0.5) (drill 0.2) (layers "F.Cu" "B.Cu") (net 289))
  (segment (start 192.520281 72.957536) (end 192.52028 72.957536) (width 0.16) (layer "In9.Cu") (net 289))
  (segment (start 192.475 70.475) (end 193.325 70.475) (width 0.16) (layer "In9.Cu") (net 289))
  (segment (start 190.3 75.9) (end 188.97 77.23) (width 0.1) (layer "In9.Cu") (net 289))
  (segment (start 192.21245 66.242145) (end 192.186395 66.268197) (width 0.16) (layer "In9.Cu") (net 289))
  (segment (start 192.675 68.225) (end 192.475 68.225) (width 0.16) (layer "In9.Cu") (net 289))
  (segment (start 191 75.8) (end 190.9 75.9) (width 0.1) (layer "In9.Cu") (net 289))
  (segment (start 188.235836 79.640008) (end 188.655836 80.060008) (width 0.1) (layer "In9.Cu") (net 289))
  (segment (start 191.2 74.3) (end 191.35 74.3) (width 0.16) (layer "In9.Cu") (net 289))
  (segment (start 192.025307 72.179719) (end 192.520281 72.674693) (width 0.16) (layer "In9.Cu") (net 289))
  (segment (start 190.65 75.1) (end 190.8 75.1) (width 0.16) (layer "In9.Cu") (net 289))
  (segment (start 191.671752 73.523222) (end 191.176778 73.028249) (width 0.16) (layer "In9.Cu") (net 289))
  (segment (start 193.325 69.125) (end 192.475 69.125) (width 0.16) (layer "In9.Cu") (net 289))
  (segment (start 192.414217 72.002943) (end 192.30815 71.896876) (width 0.16) (layer "In9.Cu") (net 289))
  (segment (start 192.475 68.675) (end 193.325 68.675) (width 0.16) (layer "In9.Cu") (net 289))
  (segment (start 188.97 77.23) (end 188.46 77.23) (width 0.1) (layer "In9.Cu") (net 289))
  (segment (start 192.186395 66.586395) (end 192.186396 66.586396) (width 0.16) (layer "In9.Cu") (net 289))
  (segment (start 193.325 70.925) (end 192.475 70.925) (width 0.16) (layer "In9.Cu") (net 289))
  (segment (start 191 75.3) (end 191 75.6) (width 0.16) (layer "In9.Cu") (net 289))
  (segment (start 191.954595 73.240379) (end 191.954595 73.240378) (width 0.16) (layer "In9.Cu") (net 289))
  (segment (start 192.9 71.6) (end 192.9 71.8) (width 0.16) (layer "In9.Cu") (net 289))
  (segment (start 192.9 71.8) (end 192.69706 72.002942) (width 0.16) (layer "In9.Cu") (net 289))
  (segment (start 192.475 69.575) (end 193.325 69.575) (width 0.16) (layer "In9.Cu") (net 289))
  (segment (start 191.742464 72.462562) (end 191.742466 72.462561) (width 0.16) (layer "In9.Cu") (net 289))
  (segment (start 191.868198 65.95) (end 191.894252 65.923947) (width 0.16) (layer "In9.Cu") (net 289))
  (segment (start 188.235836 78.635836) (end 188.235836 79.640008) (width 0.1) (layer "In9.Cu") (net 289))
  (segment (start 191.459621 72.745405) (end 191.954595 73.240379) (width 0.16) (layer "In9.Cu") (net 289))
  (segment (start 192.212449 66.242146) (end 192.21245 66.242145) (width 0.16) (layer "In9.Cu") (net 289))
  (segment (start 190.893934 73.311092) (end 191 73.417158) (width 0.16) (layer "In9.Cu") (net 289))
  (segment (start 188.086338 63.086338) (end 190.95 65.95) (width 0.16) (layer "In9.Cu") (net 289))
  (segment (start 187.87 78.27) (end 188.235836 78.635836) (width 0.1) (layer "In9.Cu") (net 289))
  (segment (start 191.176778 73.028249) (end 191.176778 73.02825) (width 0.16) (layer "In9.Cu") (net 289))
  (segment (start 192.025308 71.896875) (end 192.025307 71.896877) (width 0.16) (layer "In9.Cu") (net 289))
  (segment (start 191.459622 72.462561) (end 191.459621 72.462563) (width 0.16) (layer "In9.Cu") (net 289))
  (segment (start 191 75.6) (end 191 75.8) (width 0.1) (layer "In9.Cu") (net 289))
  (segment (start 191.868199 65.949999) (end 191.868198 65.95) (width 0.16) (layer "In9.Cu") (net 289))
  (segment (start 192.475 71.375) (end 192.675 71.375) (width 0.16) (layer "In9.Cu") (net 289))
  (segment (start 191.35 74.7) (end 190.65 74.7) (width 0.16) (layer "In9.Cu") (net 289))
  (segment (start 190.95 65.95) (end 191.55 65.95) (width 0.16) (layer "In9.Cu") (net 289))
  (segment (start 188.46 77.23) (end 187.87 77.82) (width 0.1) (layer "In9.Cu") (net 289))
  (segment (start 191 73.7) (end 191 74.1) (width 0.16) (layer "In9.Cu") (net 289))
  (segment (start 188.086338 60.960008) (end 188.086338 63.086338) (width 0.16) (layer "In9.Cu") (net 289))
  (segment (start 191.954595 73.523222) (end 191.954594 73.523222) (width 0.16) (layer "In9.Cu") (net 289))
  (segment (start 192.520281 72.674693) (end 192.520281 72.674692) (width 0.16) (layer "In9.Cu") (net 289))
  (segment (start 190.9 75.9) (end 190.3 75.9) (width 0.1) (layer "In9.Cu") (net 289))
  (segment (start 193.325 70.025) (end 192.475 70.025) (width 0.16) (layer "In9.Cu") (net 289))
  (segment (start 192.237438 72.957536) (end 191.742464 72.462562) (width 0.16) (layer "In9.Cu") (net 289))
  (segment (start 190.893934 73.02825) (end 190.893935 73.028249) (width 0.16) (layer "In9.Cu") (net 289))
  (segment (start 187.87 77.82) (end 187.87 78.27) (width 0.1) (layer "In9.Cu") (net 289))
  (segment (start 192.9 67.3) (end 192.9 68) (width 0.16) (layer "In9.Cu") (net 289))
  (segment (start 192.186396 66.586396) (end 192.9 67.3) (width 0.16) (layer "In9.Cu") (net 289))
  (segment (start 192.30815 71.896876) (end 192.308152 71.896875) (width 0.16) (layer "In9.Cu") (net 289))
  (arc (start 193.325 69.575) (mid 193.484099 69.640901) (end 193.55 69.8) (width 0.16) (layer "In9.Cu") (net 289))
  (arc (start 190.893935 73.028249) (mid 190.835356 73.16967) (end 190.893934 73.311092) (width 0.16) (layer "In9.Cu") (net 289))
  (arc (start 191.954595 73.240378) (mid 192.013174 73.3818) (end 191.954595 73.523222) (width 0.16) (layer "In9.Cu") (net 289))
  (arc (start 192.475 69.125) (mid 192.315901 69.190901) (end 192.25 69.35) (width 0.16) (layer "In9.Cu") (net 289))
  (arc (start 192.475 70.925) (mid 192.315901 70.990901) (end 192.25 71.15) (width 0.16) (layer "In9.Cu") (net 289))
  (arc (start 192.52028 72.957536) (mid 192.378859 73.016114) (end 192.237438 72.957536) (width 0.16) (layer "In9.Cu") (net 289))
  (arc (start 193.55 69.8) (mid 193.484099 69.959099) (end 193.325 70.025) (width 0.16) (layer "In9.Cu") (net 289))
  (arc (start 191.176778 73.02825) (mid 191.035357 72.96967) (end 190.893934 73.02825) (width 0.16) (layer "In9.Cu") (net 289))
  (arc (start 190.65 74.7) (mid 190.508579 74.758579) (end 190.45 74.9) (width 0.16) (layer "In9.Cu") (net 289))
  (arc (start 192.69706 72.002942) (mid 192.555639 72.061521) (end 192.414217 72.002943) (width 0.16) (layer "In9.Cu") (net 289))
  (arc (start 191.954594 73.523222) (mid 191.813173 73.5818) (end 191.671752 73.523222) (width 0.16) (layer "In9.Cu") (net 289))
  (arc (start 191.742466 72.462561) (mid 191.601043 72.403983) (end 191.459622 72.462561) (width 0.16) (layer "In9.Cu") (net 289))
  (arc (start 192.25 69.35) (mid 192.315901 69.509099) (end 192.475 69.575) (width 0.16) (layer "In9.Cu") (net 289))
  (arc (start 192.186395 66.268197) (mid 192.120494 66.427296) (end 192.186395 66.586395) (width 0.16) (layer "In9.Cu") (net 289))
  (arc (start 191.35 74.3) (mid 191.491421 74.358579) (end 191.55 74.5) (width 0.16) (layer "In9.Cu") (net 289))
  (arc (start 193.55 70.7) (mid 193.484099 70.859099) (end 193.325 70.925) (width 0.16) (layer "In9.Cu") (net 289))
  (arc (start 190.8 75.1) (mid 190.941421 75.158579) (end 191 75.3) (width 0.16) (layer "In9.Cu") (net 289))
  (arc (start 192.25 68.45) (mid 192.315901 68.609099) (end 192.475 68.675) (width 0.16) (layer "In9.Cu") (net 289))
  (arc (start 192.9 68) (mid 192.834099 68.159099) (end 192.675 68.225) (width 0.16) (layer "In9.Cu") (net 289))
  (arc (start 192.520281 72.674692) (mid 192.57886 72.816114) (end 192.520281 72.957536) (width 0.16) (layer "In9.Cu") (net 289))
  (arc (start 193.325 68.675) (mid 193.484099 68.740901) (end 193.55 68.9) (width 0.16) (layer "In9.Cu") (net 289))
  (arc (start 190.45 74.9) (mid 190.508579 75.041421) (end 190.65 75.1) (width 0.16) (layer "In9.Cu") (net 289))
  (arc (start 192.475 70.025) (mid 192.315901 70.090901) (end 192.25 70.25) (width 0.16) (layer "In9.Cu") (net 289))
  (arc (start 191.459621 72.462563) (mid 191.401044 72.603983) (end 191.459621 72.745405) (width 0.16) (layer "In9.Cu") (net 289))
  (arc (start 192.675 71.375) (mid 192.834099 71.440901) (end 192.9 71.6) (width 0.16) (layer "In9.Cu") (net 289))
  (arc (start 191.894252 65.923947) (mid 192.053351 65.858046) (end 192.21245 65.923947) (width 0.16) (layer "In9.Cu") (net 289))
  (arc (start 192.25 70.25) (mid 192.315901 70.409099) (end 192.475 70.475) (width 0.16) (layer "In9.Cu") (net 289))
  (arc (start 191 73.417158) (mid 191.058579 73.558578) (end 191 73.7) (width 0.16) (layer "In9.Cu") (net 289))
  (arc (start 192.025307 71.896877) (mid 191.96673 72.038297) (end 192.025307 72.179719) (width 0.16) (layer "In9.Cu") (net 289))
  (arc (start 193.325 70.475) (mid 193.484099 70.540901) (end 193.55 70.7) (width 0.16) (layer "In9.Cu") (net 289))
  (arc (start 193.55 68.9) (mid 193.484099 69.059099) (end 193.325 69.125) (width 0.16) (layer "In9.Cu") (net 289))
  (arc (start 191.55 74.5) (mid 191.491421 74.641421) (end 191.35 74.7) (width 0.16) (layer "In9.Cu") (net 289))
  (arc (start 191.55 65.95) (mid 191.709101 66.015902) (end 191.868199 65.949999) (width 0.16) (layer "In9.Cu") (net 289))
  (arc (start 192.475 68.225) (mid 192.315901 68.290901) (end 192.25 68.45) (width 0.16) (layer "In9.Cu") (net 289))
  (arc (start 191 74.1) (mid 191.058579 74.241421) (end 191.2 74.3) (width 0.16) (layer "In9.Cu") (net 289))
  (arc (start 192.25 71.15) (mid 192.315901 71.309099) (end 192.475 71.375) (width 0.16) (layer "In9.Cu") (net 289))
  (arc (start 192.21245 65.923947) (mid 192.27835 66.083046) (end 192.212449 66.242146) (width 0.16) (layer "In9.Cu") (net 289))
  (arc (start 192.308152 71.896875) (mid 192.166729 71.838297) (end 192.025308 71.896875) (width 0.16) (layer "In9.Cu") (net 289))
  (segment (start 197.336328 59.660008) (end 197.336328 60.960008) (width 0.2) (layer "F.Cu") (net 290))
  (segment (start 190.136328 82.560008) (end 189.636328 82.060008) (width 0.127) (layer "F.Cu") (net 290))
  (via blind (at 189.636328 82.060008) (size 0.5) (drill 0.2) (layers "F.Cu" "In2.Cu") (net 290))
  (via blind (at 197.336328 60.960008) (size 0.5) (drill 0.2) (layers "F.Cu" "In2.Cu") (net 290))
  (segment (start 192.275 73.8) (end 191.7 73.8) (width 0.16) (layer "In2.Cu") (net 290))
  (segment (start 195.988602 72.168197) (end 196.339482 72.519078) (width 0.16) (layer "In2.Cu") (net 290))
  (segment (start 196.306801 71.85) (end 196.27412 71.817319) (width 0.16) (layer "In2.Cu") (net 290))
  (segment (start 196.3068 71.85) (end 196.306801 71.85) (width 0.16) (layer "In2.Cu") (net 290))
  (segment (start 189.58 76.34603) (end 189.82603 76.1) (width 0.1) (layer "In2.Cu") (net 290))
  (segment (start 195.637724 72.453716) (end 196.021284 72.837276) (width 0.16) (layer "In2.Cu") (net 290))
  (segment (start 196.85 61.446336) (end 196.85 62) (width 0.16) (layer "In2.Cu") (net 290))
  (segment (start 197.336328 60.960008) (end 196.85 61.446336) (width 0.16) (layer "In2.Cu") (net 290))
  (segment (start 196.45 64.75) (end 197.2 64.75) (width 0.16) (layer "In2.Cu") (net 290))
  (segment (start 194.3 74.025) (end 194.3 74.071217) (width 0.16) (layer "In2.Cu") (net 290))
  (segment (start 192.5 73.528783) (end 192.5 73.575) (width 0.16) (layer "In2.Cu") (net 290))
  (segment (start 189.82603 76.1) (end 190.45 76.1) (width 0.1) (layer "In2.Cu") (net 290))
  (segment (start 191.7 73.8) (end 190.8 74.7) (width 0.16) (layer "In2.Cu") (net 290))
  (segment (start 195.319526 72.771914) (end 195.703086 73.155474) (width 0.16) (layer "In2.Cu") (net 290))
  (segment (start 196.6 62.25) (end 196.45 62.25) (width 0.16) (layer "In2.Cu") (net 290))
  (segment (start 190.075836 77.475836) (end 189.58 76.98) (width 0.1) (layer "In2.Cu") (net 290))
  (segment (start 197.2 63.25) (end 196.45 63.25) (width 0.16) (layer "In2.Cu") (net 290))
  (segment (start 190.8 75.75) (end 190.8 75.55) (width 0.1) (layer "In2.Cu") (net 290))
  (segment (start 197.2 64.25) (end 196.45 64.25) (width 0.16) (layer "In2.Cu") (net 290))
  (segment (start 196.6 70.15) (end 197.1 70.15) (width 0.16) (layer "In2.Cu") (net 290))
  (segment (start 196.85 71.625) (end 196.625 71.85) (width 0.16) (layer "In2.Cu") (net 290))
  (segment (start 193.85 74.025) (end 193.85 73.528783) (width 0.16) (layer "In2.Cu") (net 290))
  (segment (start 197.35 69.3) (end 197.35 69.35) (width 0.16) (layer "In2.Cu") (net 290))
  (segment (start 197.2 65.25) (end 197.1 65.25) (width 0.16) (layer "In2.Cu") (net 290))
  (segment (start 192.95 74.071217) (end 192.95 73.528783) (width 0.16) (layer "In2.Cu") (net 290))
  (segment (start 195.03401 73.440992) (end 194.675 73.8) (width 0.16) (layer "In2.Cu") (net 290))
  (segment (start 196.35 69.85) (end 196.35 69.9) (width 0.16) (layer "In2.Cu") (net 290))
  (segment (start 190.075836 81.6205) (end 190.075836 77.475836) (width 0.1) (layer "In2.Cu") (net 290))
  (segment (start 190.8 74.7) (end 190.8 75.55) (width 0.16) (layer "In2.Cu") (net 290))
  (segment (start 189.636328 82.060008) (end 190.075836 81.6205) (width 0.1) (layer "In2.Cu") (net 290))
  (segment (start 194.675 73.8) (end 194.525 73.8) (width 0.16) (layer "In2.Cu") (net 290))
  (segment (start 196.85 65.5) (end 196.85 68.8) (width 0.16) (layer "In2.Cu") (net 290))
  (segment (start 193.4 73.528783) (end 193.4 74.071217) (width 0.16) (layer "In2.Cu") (net 290))
  (segment (start 196.45 63.75) (end 197.2 63.75) (width 0.16) (layer "In2.Cu") (net 290))
  (segment (start 195.955922 72.135517) (end 195.988602 72.168197) (width 0.16) (layer "In2.Cu") (net 290))
  (segment (start 196.85 71.5) (end 196.85 71.625) (width 0.16) (layer "In2.Cu") (net 290))
  (segment (start 193.85 74.071217) (end 193.85 74.025) (width 0.16) (layer "In2.Cu") (net 290))
  (segment (start 196.35 70.95) (end 196.35 71) (width 0.16) (layer "In2.Cu") (net 290))
  (segment (start 195.384888 73.473672) (end 195.352208 73.440992) (width 0.16) (layer "In2.Cu") (net 290))
  (segment (start 189.58 76.98) (end 189.58 76.34603) (width 0.1) (layer "In2.Cu") (net 290))
  (segment (start 196.45 62.75) (end 197.2 62.75) (width 0.16) (layer "In2.Cu") (net 290))
  (segment (start 190.45 76.1) (end 190.8 75.75) (width 0.1) (layer "In2.Cu") (net 290))
  (segment (start 197.1 70.7) (end 196.6 70.7) (width 0.16) (layer "In2.Cu") (net 290))
  (segment (start 197.35 70.4) (end 197.35 70.45) (width 0.16) (layer "In2.Cu") (net 290))
  (segment (start 197.1 69.6) (end 196.6 69.6) (width 0.16) (layer "In2.Cu") (net 290))
  (arc (start 196.6 69.6) (mid 196.423223 69.673223) (end 196.35 69.85) (width 0.16) (layer "In2.Cu") (net 290))
  (arc (start 197.1 70.15) (mid 197.276777 70.223223) (end 197.35 70.4) (width 0.16) (layer "In2.Cu") (net 290))
  (arc (start 194.525 73.8) (mid 194.365901 73.865901) (end 194.3 74.025) (width 0.16) (layer "In2.Cu") (net 290))
  (arc (start 196.2 63.5) (mid 196.273223 63.676777) (end 196.45 63.75) (width 0.16) (layer "In2.Cu") (net 290))
  (arc (start 197.45 65) (mid 197.376777 65.176777) (end 197.2 65.25) (width 0.16) (layer "In2.Cu") (net 290))
  (arc (start 195.352208 73.440992) (mid 195.193109 73.375091) (end 195.03401 73.440992) (width 0.16) (layer "In2.Cu") (net 290))
  (arc (start 197.35 69.35) (mid 197.276777 69.526777) (end 197.1 69.6) (width 0.16) (layer "In2.Cu") (net 290))
  (arc (start 192.5 73.575) (mid 192.434099 73.734099) (end 192.275 73.8) (width 0.16) (layer "In2.Cu") (net 290))
  (arc (start 197.45 63) (mid 197.376777 63.176777) (end 197.2 63.25) (width 0.16) (layer "In2.Cu") (net 290))
  (arc (start 193.85 73.528783) (mid 193.784099 73.369684) (end 193.625 73.303783) (width 0.16) (layer "In2.Cu") (net 290))
  (arc (start 196.45 63.25) (mid 196.273223 63.323223) (end 196.2 63.5) (width 0.16) (layer "In2.Cu") (net 290))
  (arc (start 192.725 73.303783) (mid 192.565901 73.369684) (end 192.5 73.528783) (width 0.16) (layer "In2.Cu") (net 290))
  (arc (start 193.4 74.071217) (mid 193.334099 74.230316) (end 193.175 74.296217) (width 0.16) (layer "In2.Cu") (net 290))
  (arc (start 196.45 62.25) (mid 196.273223 62.323223) (end 196.2 62.5) (width 0.16) (layer "In2.Cu") (net 290))
  (arc (start 196.2 62.5) (mid 196.273223 62.676777) (end 196.45 62.75) (width 0.16) (layer "In2.Cu") (net 290))
  (arc (start 197.1 69.05) (mid 197.276777 69.123223) (end 197.35 69.3) (width 0.16) (layer "In2.Cu") (net 290))
  (arc (start 196.45 64.25) (mid 196.273223 64.323223) (end 196.2 64.5) (width 0.16) (layer "In2.Cu") (net 290))
  (arc (start 196.85 68.8) (mid 196.923223 68.976777) (end 197.1 69.05) (width 0.16) (layer "In2.Cu") (net 290))
  (arc (start 197.35 70.45) (mid 197.276777 70.626777) (end 197.1 70.7) (width 0.16) (layer "In2.Cu") (net 290))
  (arc (start 196.35 69.9) (mid 196.423223 70.076777) (end 196.6 70.15) (width 0.16) (layer "In2.Cu") (net 290))
  (arc (start 196.6 71.25) (mid 196.776777 71.323223) (end 196.85 71.5) (width 0.16) (layer "In2.Cu") (net 290))
  (arc (start 197.45 64) (mid 197.376777 64.176777) (end 197.2 64.25) (width 0.16) (layer "In2.Cu") (net 290))
  (arc (start 196.27412 71.817319) (mid 196.115021 71.751418) (end 195.955922 71.817319) (width 0.16) (layer "In2.Cu") (net 290))
  (arc (start 193.175 74.296217) (mid 193.015901 74.230316) (end 192.95 74.071217) (width 0.16) (layer "In2.Cu") (net 290))
  (arc (start 195.703086 73.473672) (mid 195.543987 73.539573) (end 195.384888 73.473672) (width 0.16) (layer "In2.Cu") (net 290))
  (arc (start 196.85 62) (mid 196.776777 62.176777) (end 196.6 62.25) (width 0.16) (layer "In2.Cu") (net 290))
  (arc (start 196.339482 72.837276) (mid 196.180383 72.903177) (end 196.021284 72.837276) (width 0.16) (layer "In2.Cu") (net 290))
  (arc (start 197.2 62.75) (mid 197.376777 62.823223) (end 197.45 63) (width 0.16) (layer "In2.Cu") (net 290))
  (arc (start 195.319526 72.453716) (mid 195.253625 72.612815) (end 195.319526 72.771914) (width 0.16) (layer "In2.Cu") (net 290))
  (arc (start 193.625 73.303783) (mid 193.465901 73.369684) (end 193.4 73.528783) (width 0.16) (layer "In2.Cu") (net 290))
  (arc (start 195.703086 73.155474) (mid 195.768987 73.314573) (end 195.703086 73.473672) (width 0.16) (layer "In2.Cu") (net 290))
  (arc (start 196.2 64.5) (mid 196.273223 64.676777) (end 196.45 64.75) (width 0.16) (layer "In2.Cu") (net 290))
  (arc (start 196.625 71.85) (mid 196.4659 71.915901) (end 196.3068 71.85) (width 0.16) (layer "In2.Cu") (net 290))
  (arc (start 194.075 74.296217) (mid 193.915901 74.230316) (end 193.85 74.071217) (width 0.16) (layer "In2.Cu") (net 290))
  (arc (start 196.6 70.7) (mid 196.423223 70.773223) (end 196.35 70.95) (width 0.16) (layer "In2.Cu") (net 290))
  (arc (start 197.1 65.25) (mid 196.923223 65.323223) (end 196.85 65.5) (width 0.16) (layer "In2.Cu") (net 290))
  (arc (start 196.339482 72.519078) (mid 196.405383 72.678177) (end 196.339482 72.837276) (width 0.16) (layer "In2.Cu") (net 290))
  (arc (start 196.35 71) (mid 196.423223 71.176777) (end 196.6 71.25) (width 0.16) (layer "In2.Cu") (net 290))
  (arc (start 197.2 63.75) (mid 197.376777 63.823223) (end 197.45 64) (width 0.16) (layer "In2.Cu") (net 290))
  (arc (start 194.3 74.071217) (mid 194.234099 74.230316) (end 194.075 74.296217) (width 0.16) (layer "In2.Cu") (net 290))
  (arc (start 197.2 64.75) (mid 197.376777 64.823223) (end 197.45 65) (width 0.16) (layer "In2.Cu") (net 290))
  (arc (start 195.955922 71.817319) (mid 195.890021 71.976418) (end 195.955922 72.135517) (width 0.16) (layer "In2.Cu") (net 290))
  (arc (start 195.637724 72.453716) (mid 195.478625 72.387815) (end 195.319526 72.453716) (width 0.16) (layer "In2.Cu") (net 290))
  (arc (start 192.95 73.528783) (mid 192.884099 73.369684) (end 192.725 73.303783) (width 0.16) (layer "In2.Cu") (net 290))
  (segment (start 186.596336 79.1) (end 186.136328 79.560008) (width 0.127) (layer "F.Cu") (net 291))
  (segment (start 186.6245 79.1) (end 186.596336 79.1) (width 0.127) (layer "F.Cu") (net 291))
  (segment (start 186.286328 59.660008) (end 186.286328 60.960008) (width 0.2) (layer "F.Cu") (net 291))
  (via (at 186.286328 60.960008) (size 0.5) (drill 0.2) (layers "F.Cu" "B.Cu") (net 291))
  (via (at 186.6245 79.1) (size 0.5) (drill 0.2) (layers "F.Cu" "B.Cu") (net 291))
  (segment (start 189.116791 72.551104) (end 189.116789 72.551105) (width 0.16) (layer "In9.Cu") (net 291))
  (segment (start 188.38 76.5) (end 187.1 77.78) (width 0.1) (layer "In9.Cu") (net 291))
  (segment (start 188.8 74.2) (end 189.4 74.2) (width 0.16) (layer "In9.Cu") (net 291))
  (segment (start 191.2 71.1) (end 191 71.1) (width 0.16) (layer "In9.Cu") (net 291))
  (segment (start 190.4 68.3) (end 191.2 68.3) (width 0.16) (layer "In9.Cu") (net 291))
  (segment (start 189.1 73.275) (end 189.1 73.6) (width 0.16) (layer "In9.Cu") (net 291))
  (segment (start 190.1 67.5) (end 191.2 67.5) (width 0.16) (layer "In9.Cu") (net 291))
  (segment (start 190.4 70.7) (end 191.2 70.7) (width 0.16) (layer "In9.Cu") (net 291))
  (segment (start 189.1875 73.1875) (end 189.1 73.275) (width 0.16) (layer "In9.Cu") (net 291))
  (segment (start 189.965319 71.985418) (end 189.965319 71.985419) (width 0.16) (layer "In9.Cu") (net 291))
  (segment (start 189.399633 72.551105) (end 189.399635 72.551104) (width 0.16) (layer "In9.Cu") (net 291))
  (segment (start 190.106738 72.692525) (end 190.106738 72.692524) (width 0.16) (layer "In9.Cu") (net 291))
  (segment (start 189.11679 72.833948) (end 189.1875 72.904658) (width 0.16) (layer "In9.Cu") (net 291))
  (segment (start 189.823896 72.975368) (end 189.399633 72.551105) (width 0.16) (layer "In9.Cu") (net 291))
  (segment (start 189.1 75.2) (end 189.1 75.55) (width 0.16) (layer "In9.Cu") (net 291))
  (segment (start 187.1 78.65) (end 186.65 79.1) (width 0.1) (layer "In9.Cu") (net 291))
  (segment (start 188.9 73.8) (end 188.8 73.8) (width 0.16) (layer "In9.Cu") (net 291))
  (segment (start 190.389583 72.409681) (end 189.965319 71.985418) (width 0.16) (layer "In9.Cu") (net 291))
  (segment (start 191.2 68.7) (end 190.4 68.7) (width 0.16) (layer "In9.Cu") (net 291))
  (segment (start 190.8 71.575) (end 190.601713 71.773284) (width 0.16) (layer "In9.Cu") (net 291))
  (segment (start 190.672425 72.409681) (end 190.672426 72.40968) (width 0.16) (layer "In9.Cu") (net 291))
  (segment (start 188.8 75) (end 188.9 75) (width 0.16) (layer "In9.Cu") (net 291))
  (segment (start 191.2 67.9) (end 190.4 67.9) (width 0.16) (layer "In9.Cu") (net 291))
  (segment (start 186.65 79.1) (end 186.6245 79.1) (width 0.1) (layer "In9.Cu") (net 291))
  (segment (start 187.1 77.78) (end 187.1 78.65) (width 0.1) (layer "In9.Cu") (net 291))
  (segment (start 189.1 76.15) (end 188.75 76.5) (width 0.1) (layer "In9.Cu") (net 291))
  (segment (start 190.4 69.9) (end 191.2 69.9) (width 0.16) (layer "In9.Cu") (net 291))
  (segment (start 190.672425 72.126838) (end 190.672425 72.126837) (width 0.16) (layer "In9.Cu") (net 291))
  (segment (start 190.106738 72.975368) (end 190.106739 72.975367) (width 0.16) (layer "In9.Cu") (net 291))
  (segment (start 189.682475 72.268261) (end 190.106738 72.692525) (width 0.16) (layer "In9.Cu") (net 291))
  (segment (start 191.2 70.3) (end 190.4 70.3) (width 0.16) (layer "In9.Cu") (net 291))
  (segment (start 190.601714 72.056127) (end 190.672425 72.126838) (width 0.16) (layer "In9.Cu") (net 291))
  (segment (start 189.4 74.6) (end 188.8 74.6) (width 0.16) (layer "In9.Cu") (net 291))
  (segment (start 188.75 76.5) (end 188.38 76.5) (width 0.1) (layer "In9.Cu") (net 291))
  (segment (start 190.4 69.1) (end 191.2 69.1) (width 0.16) (layer "In9.Cu") (net 291))
  (segment (start 191.2 69.5) (end 190.4 69.5) (width 0.16) (layer "In9.Cu") (net 291))
  (segment (start 190.8 71.3) (end 190.8 71.575) (width 0.16) (layer "In9.Cu") (net 291))
  (segment (start 186.286328 60.960008) (end 186.286328 63.686328) (width 0.16) (layer "In9.Cu") (net 291))
  (segment (start 189.1 75.55) (end 189.1 76.15) (width 0.1) (layer "In9.Cu") (net 291))
  (segment (start 189.682475 71.985419) (end 189.682476 71.985418) (width 0.16) (layer "In9.Cu") (net 291))
  (segment (start 186.286328 63.686328) (end 190.1 67.5) (width 0.16) (layer "In9.Cu") (net 291))
  (arc (start 191.2 70.7) (mid 191.341421 70.758579) (end 191.4 70.9) (width 0.16) (layer "In9.Cu") (net 291))
  (arc (start 191.4 70.9) (mid 191.341421 71.041421) (end 191.2 71.1) (width 0.16) (layer "In9.Cu") (net 291))
  (arc (start 188.9 75) (mid 189.041421 75.058579) (end 189.1 75.2) (width 0.16) (layer "In9.Cu") (net 291))
  (arc (start 190.2 70.5) (mid 190.258579 70.641421) (end 190.4 70.7) (width 0.16) (layer "In9.Cu") (net 291))
  (arc (start 190.2 69.7) (mid 190.258579 69.841421) (end 190.4 69.9) (width 0.16) (layer "In9.Cu") (net 291))
  (arc (start 191.4 68.5) (mid 191.341421 68.641421) (end 191.2 68.7) (width 0.16) (layer "In9.Cu") (net 291))
  (arc (start 191.2 67.5) (mid 191.341421 67.558579) (end 191.4 67.7) (width 0.16) (layer "In9.Cu") (net 291))
  (arc (start 191.4 67.7) (mid 191.341421 67.841421) (end 191.2 67.9) (width 0.16) (layer "In9.Cu") (net 291))
  (arc (start 189.399635 72.551104) (mid 189.258212 72.492526) (end 189.116791 72.551104) (width 0.16) (layer "In9.Cu") (net 291))
  (arc (start 191.2 69.1) (mid 191.341421 69.158579) (end 191.4 69.3) (width 0.16) (layer "In9.Cu") (net 291))
  (arc (start 191.4 69.3) (mid 191.341421 69.441421) (end 191.2 69.5) (width 0.16) (layer "In9.Cu") (net 291))
  (arc (start 188.6 74.8) (mid 188.658579 74.941421) (end 188.8 75) (width 0.16) (layer "In9.Cu") (net 291))
  (arc (start 189.116789 72.551105) (mid 189.058211 72.692527) (end 189.11679 72.833948) (width 0.16) (layer "In9.Cu") (net 291))
  (arc (start 189.6 74.4) (mid 189.541421 74.541421) (end 189.4 74.6) (width 0.16) (layer "In9.Cu") (net 291))
  (arc (start 190.4 67.9) (mid 190.258579 67.958579) (end 190.2 68.1) (width 0.16) (layer "In9.Cu") (net 291))
  (arc (start 190.2 68.1) (mid 190.258579 68.241421) (end 190.4 68.3) (width 0.16) (layer "In9.Cu") (net 291))
  (arc (start 190.4 69.5) (mid 190.258579 69.558579) (end 190.2 69.7) (width 0.16) (layer "In9.Cu") (net 291))
  (arc (start 190.4 70.3) (mid 190.258579 70.358579) (end 190.2 70.5) (width 0.16) (layer "In9.Cu") (net 291))
  (arc (start 190.2 68.9) (mid 190.258579 69.041421) (end 190.4 69.1) (width 0.16) (layer "In9.Cu") (net 291))
  (arc (start 189.682476 71.985418) (mid 189.623897 72.126839) (end 189.682475 72.268261) (width 0.16) (layer "In9.Cu") (net 291))
  (arc (start 191.2 68.3) (mid 191.341421 68.358579) (end 191.4 68.5) (width 0.16) (layer "In9.Cu") (net 291))
  (arc (start 190.106738 72.692524) (mid 190.165317 72.833946) (end 190.106738 72.975368) (width 0.16) (layer "In9.Cu") (net 291))
  (arc (start 191.2 69.9) (mid 191.341421 69.958579) (end 191.4 70.1) (width 0.16) (layer "In9.Cu") (net 291))
  (arc (start 190.106739 72.975367) (mid 189.965318 73.033946) (end 189.823896 72.975368) (width 0.16) (layer "In9.Cu") (net 291))
  (arc (start 190.601713 71.773284) (mid 190.543135 71.914706) (end 190.601714 72.056127) (width 0.16) (layer "In9.Cu") (net 291))
  (arc (start 188.8 73.8) (mid 188.658579 73.858579) (end 188.6 74) (width 0.16) (layer "In9.Cu") (net 291))
  (arc (start 189.1 73.6) (mid 189.041421 73.741421) (end 188.9 73.8) (width 0.16) (layer "In9.Cu") (net 291))
  (arc (start 188.8 74.6) (mid 188.658579 74.658579) (end 188.6 74.8) (width 0.16) (layer "In9.Cu") (net 291))
  (arc (start 190.672425 72.126837) (mid 190.731004 72.268259) (end 190.672425 72.409681) (width 0.16) (layer "In9.Cu") (net 291))
  (arc (start 189.4 74.2) (mid 189.541421 74.258579) (end 189.6 74.4) (width 0.16) (layer "In9.Cu") (net 291))
  (arc (start 190.4 68.7) (mid 190.258579 68.758579) (end 190.2 68.9) (width 0.16) (layer "In9.Cu") (net 291))
  (arc (start 191 71.1) (mid 190.858579 71.158579) (end 190.8 71.3) (width 0.16) (layer "In9.Cu") (net 291))
  (arc (start 190.672426 72.40968) (mid 190.531005 72.468259) (end 190.389583 72.409681) (width 0.16) (layer "In9.Cu") (net 291))
  (arc (start 191.4 70.1) (mid 191.341421 70.241421) (end 191.2 70.3) (width 0.16) (layer "In9.Cu") (net 291))
  (arc (start 189.1875 72.904658) (mid 189.246079 73.046078) (end 189.1875 73.1875) (width 0.16) (layer "In9.Cu") (net 291))
  (arc (start 189.965319 71.985419) (mid 189.823898 71.926839) (end 189.682475 71.985419) (width 0.16) (layer "In9.Cu") (net 291))
  (arc (start 188.6 74) (mid 188.658579 74.141421) (end 188.8 74.2) (width 0.16) (layer "In9.Cu") (net 291))
  (segment (start 191.136328 80.560008) (end 191.636328 80.060008) (width 0.127) (layer "F.Cu") (net 292))
  (segment (start 236.436328 59.660008) (end 236.436328 60.960008) (width 0.2) (layer "F.Cu") (net 292))
  (segment (start 191.636328 80.060008) (end 191.655836 80.060008) (width 0.127) (layer "F.Cu") (net 292))
  (via (at 191.655836 80.060008) (size 0.5) (drill 0.2) (layers "F.Cu" "B.Cu") (net 292))
  (via (at 236.436328 60.960008) (size 0.5) (drill 0.2) (layers "F.Cu" "B.Cu") (net 292))
  (segment (start 236.436328 61.563672) (end 234.35 63.65) (width 0.16) (layer "In9.Cu") (net 292))
  (segment (start 213.707994 65.940899) (end 212.979101 65.212005) (width 0.16) (layer "In9.Cu") (net 292))
  (segment (start 209.867826 67.934372) (end 209.867825 67.934373) (width 0.16) (layer "In9.Cu") (net 292))
  (segment (start 212.152356 67.496537) (end 211.423463 66.767643) (width 0.16) (layer "In9.Cu") (net 292))
  (segment (start 211.374537 68.274356) (end 210.645644 67.545462) (width 0.16) (layer "In9.Cu") (net 292))
  (segment locked (start 234.35 63.65) (end 215.27 63.65) (width 0.16) (layer "In9.Cu") (net 292))
  (segment (start 213.368011 64.823096) (end 214.096905 65.551989) (width 0.16) (layer "In9.Cu") (net 292))
  (segment (start 213.368011 64.823097) (end 213.368011 64.823096) (width 0.16) (layer "In9.Cu") (net 292))
  (segment (start 212.590192 65.600916) (end 212.590192 65.600915) (width 0.16) (layer "In9.Cu") (net 292))
  (segment (start 212.590192 65.600915) (end 213.319086 66.329808) (width 0.16) (layer "In9.Cu") (net 292))
  (segment (start 198.2 79.86) (end 199.06 79.86) (width 0.16) (layer "In9.Cu") (net 292))
  (segment (start 212.201283 65.600915) (end 212.201282 65.600916) (width 0.16) (layer "In9.Cu") (net 292))
  (segment (start 213.707995 66.329807) (end 213.707994 66.329808) (width 0.16) (layer "In9.Cu") (net 292))
  (segment (start 199.06 79.86) (end 209.26 69.66) (width 0.16) (layer "In9.Cu") (net 292))
  (segment (start 210.256735 67.934372) (end 210.985629 68.663265) (width 0.16) (layer "In9.Cu") (net 292))
  (segment (start 211.812373 66.378734) (end 212.541267 67.107627) (width 0.16) (layer "In9.Cu") (net 292))
  (segment (start 214.704731 64.215271) (end 215.27 63.65) (width 0.16) (layer "In9.Cu") (net 292))
  (segment (start 209.478917 68.712191) (end 210.20781 69.441084) (width 0.16) (layer "In9.Cu") (net 292))
  (segment (start 210.256735 67.934373) (end 210.256735 67.934372) (width 0.16) (layer "In9.Cu") (net 292))
  (segment (start 193.229992 79.87) (end 198.19 79.87) (width 0.1) (layer "In9.Cu") (net 292))
  (segment (start 236.436328 60.960008) (end 236.436328 61.563672) (width 0.16) (layer "In9.Cu") (net 292))
  (segment (start 211.034554 67.156554) (end 211.034554 67.156553) (width 0.16) (layer "In9.Cu") (net 292))
  (segment (start 193.229992 79.87) (end 193 79.640008) (width 0.1) (layer "In9.Cu") (net 292))
  (segment (start 192.075836 79.640008) (end 191.655836 80.060008) (width 0.1) (layer "In9.Cu") (net 292))
  (segment (start 211.812373 66.378735) (end 211.812373 66.378734) (width 0.16) (layer "In9.Cu") (net 292))
  (segment (start 209.090007 68.712191) (end 209.090009 68.71219) (width 0.16) (layer "In9.Cu") (net 292))
  (segment (start 214.485813 65.16308) (end 213.75692 64.434186) (width 0.16) (layer "In9.Cu") (net 292))
  (segment (start 198.19 79.87) (end 198.2 79.86) (width 0.1) (layer "In9.Cu") (net 292))
  (segment (start 214.485814 65.551988) (end 214.485813 65.551989) (width 0.16) (layer "In9.Cu") (net 292))
  (segment (start 212.152357 67.885445) (end 212.152356 67.885446) (width 0.16) (layer "In9.Cu") (net 292))
  (segment (start 212.930175 66.718718) (end 212.201282 65.989824) (width 0.16) (layer "In9.Cu") (net 292))
  (segment (start 213.707994 65.940898) (end 213.707994 65.940899) (width 0.16) (layer "In9.Cu") (net 292))
  (segment (start 212.979102 64.823096) (end 212.979101 64.823097) (width 0.16) (layer "In9.Cu") (net 292))
  (segment (start 214.14583 64.045277) (end 214.315823 64.21527) (width 0.16) (layer "In9.Cu") (net 292))
  (segment (start 212.152356 67.496536) (end 212.152356 67.496537) (width 0.16) (layer "In9.Cu") (net 292))
  (segment (start 211.423464 66.378734) (end 211.423463 66.378735) (width 0.16) (layer "In9.Cu") (net 292))
  (segment (start 212.930176 67.107626) (end 212.930175 67.107627) (width 0.16) (layer "In9.Cu") (net 292))
  (segment (start 210.596718 69.052174) (end 210.596718 69.052175) (width 0.16) (layer "In9.Cu") (net 292))
  (segment (start 214.485813 65.163079) (end 214.485813 65.16308) (width 0.16) (layer "In9.Cu") (net 292))
  (segment (start 209.26 69.271092) (end 209.090008 69.1011) (width 0.16) (layer "In9.Cu") (net 292))
  (segment (start 212.930175 66.718717) (end 212.930175 66.718718) (width 0.16) (layer "In9.Cu") (net 292))
  (segment (start 211.034554 67.156553) (end 211.763448 67.885446) (width 0.16) (layer "In9.Cu") (net 292))
  (segment (start 210.596719 69.441083) (end 210.596718 69.441084) (width 0.16) (layer "In9.Cu") (net 292))
  (segment (start 214.704732 64.215271) (end 214.704731 64.215271) (width 0.16) (layer "In9.Cu") (net 292))
  (segment (start 210.596718 69.052175) (end 209.867825 68.323281) (width 0.16) (layer "In9.Cu") (net 292))
  (segment (start 211.374537 68.274355) (end 211.374537 68.274356) (width 0.16) (layer "In9.Cu") (net 292))
  (segment (start 210.645645 67.156553) (end 210.645644 67.156554) (width 0.16) (layer "In9.Cu") (net 292))
  (segment (start 214.14583 64.045278) (end 214.14583 64.045277) (width 0.16) (layer "In9.Cu") (net 292))
  (segment (start 213.756921 64.045277) (end 213.75692 64.045278) (width 0.16) (layer "In9.Cu") (net 292))
  (segment (start 211.374538 68.663264) (end 211.374537 68.663265) (width 0.16) (layer "In9.Cu") (net 292))
  (segment (start 193 79.640008) (end 192.075836 79.640008) (width 0.1) (layer "In9.Cu") (net 292))
  (segment (start 209.478919 68.71219) (end 209.478917 68.712191) (width 0.16) (layer "In9.Cu") (net 292))
  (arc (start 211.423463 66.767643) (mid 211.342918 66.573188) (end 211.423464 66.378734) (width 0.16) (layer "In9.Cu") (net 292))
  (arc (start 212.979101 64.823097) (mid 213.173557 64.74255) (end 213.368011 64.823097) (width 0.16) (layer "In9.Cu") (net 292))
  (arc (start 209.26 69.66) (mid 209.340546 69.465545) (end 209.26 69.271092) (width 0.16) (layer "In9.Cu") (net 292))
  (arc (start 212.979101 65.212005) (mid 212.898556 65.01755) (end 212.979102 64.823096) (width 0.16) (layer "In9.Cu") (net 292))
  (arc (start 214.485813 65.551989) (mid 214.566359 65.357534) (end 214.485813 65.163079) (width 0.16) (layer "In9.Cu") (net 292))
  (arc (start 211.374537 68.663265) (mid 211.455083 68.46881) (end 211.374537 68.274355) (width 0.16) (layer "In9.Cu") (net 292))
  (arc (start 210.596718 69.441084) (mid 210.677264 69.246629) (end 210.596718 69.052174) (width 0.16) (layer "In9.Cu") (net 292))
  (arc (start 209.867825 67.934373) (mid 210.062281 67.853826) (end 210.256735 67.934373) (width 0.16) (layer "In9.Cu") (net 292))
  (arc (start 213.75692 64.434186) (mid 213.676375 64.239731) (end 213.756921 64.045277) (width 0.16) (layer "In9.Cu") (net 292))
  (arc (start 209.090008 69.1011) (mid 209.009462 68.906646) (end 209.090007 68.712191) (width 0.16) (layer "In9.Cu") (net 292))
  (arc (start 210.645644 67.156554) (mid 210.8401 67.076007) (end 211.034554 67.156554) (width 0.16) (layer "In9.Cu") (net 292))
  (arc (start 212.930175 67.107627) (mid 213.010721 66.913172) (end 212.930175 66.718717) (width 0.16) (layer "In9.Cu") (net 292))
  (arc (start 212.201282 65.989824) (mid 212.120737 65.795369) (end 212.201283 65.600915) (width 0.16) (layer "In9.Cu") (net 292))
  (arc (start 211.423463 66.378735) (mid 211.617919 66.298188) (end 211.812373 66.378735) (width 0.16) (layer "In9.Cu") (net 292))
  (arc (start 210.20781 69.441084) (mid 210.402265 69.521629) (end 210.596719 69.441083) (width 0.16) (layer "In9.Cu") (net 292))
  (arc (start 210.985629 68.663265) (mid 211.180084 68.74381) (end 211.374538 68.663264) (width 0.16) (layer "In9.Cu") (net 292))
  (arc (start 209.090009 68.71219) (mid 209.284463 68.631645) (end 209.478919 68.71219) (width 0.16) (layer "In9.Cu") (net 292))
  (arc (start 213.319086 66.329808) (mid 213.513541 66.410353) (end 213.707995 66.329807) (width 0.16) (layer "In9.Cu") (net 292))
  (arc (start 213.707994 66.329808) (mid 213.78854 66.135353) (end 213.707994 65.940898) (width 0.16) (layer "In9.Cu") (net 292))
  (arc (start 214.096905 65.551989) (mid 214.29136 65.632534) (end 214.485814 65.551988) (width 0.16) (layer "In9.Cu") (net 292))
  (arc (start 212.541267 67.107627) (mid 212.735722 67.188172) (end 212.930176 67.107626) (width 0.16) (layer "In9.Cu") (net 292))
  (arc (start 212.201282 65.600916) (mid 212.395738 65.520369) (end 212.590192 65.600916) (width 0.16) (layer "In9.Cu") (net 292))
  (arc (start 210.645644 67.545462) (mid 210.565099 67.351007) (end 210.645645 67.156553) (width 0.16) (layer "In9.Cu") (net 292))
  (arc (start 211.763448 67.885446) (mid 211.957903 67.965991) (end 212.152357 67.885445) (width 0.16) (layer "In9.Cu") (net 292))
  (arc (start 212.152356 67.885446) (mid 212.232902 67.690991) (end 212.152356 67.496536) (width 0.16) (layer "In9.Cu") (net 292))
  (arc (start 214.315823 64.21527) (mid 214.510277 64.295816) (end 214.704732 64.215271) (width 0.16) (layer "In9.Cu") (net 292))
  (arc (start 213.75692 64.045278) (mid 213.951376 63.964731) (end 214.14583 64.045278) (width 0.16) (layer "In9.Cu") (net 292))
  (arc (start 209.867825 68.323281) (mid 209.78728 68.128826) (end 209.867826 67.934372) (width 0.16) (layer "In9.Cu") (net 292))
  (segment (start 233.036328 59.660008) (end 233.036328 60.960008) (width 0.2) (layer "F.Cu") (net 293))
  (segment (start 194.136328 83.560008) (end 194.636328 83.060008) (width 0.127) (layer "F.Cu") (net 293))
  (segment (start 194.636328 83.060008) (end 194.655836 83.060008) (width 0.127) (layer "F.Cu") (net 293))
  (via blind (at 233.036328 60.960008) (size 0.5) (drill 0.2) (layers "F.Cu" "In5.Cu") (net 293))
  (via blind (at 194.655836 83.060008) (size 0.5) (drill 0.2) (layers "F.Cu" "In5.Cu") (net 293))
  (segment (start 215.94 81.88) (end 216.26 81.88) (width 0.146) (layer "In5.Cu") (net 293))
  (segment (start 204.517103 84.14956) (end 204.517103 83.684646) (width 0.146) (layer "In5.Cu") (net 293))
  (segment (start 216.896381 81.567854) (end 216.572146 81.243618) (width 0.146) (layer "In5.Cu") (net 293))
  (segment (start 203.717103 83.717103) (end 203.717103 83.684646) (width 0.146) (layer "In5.Cu") (net 293))
  (segment (start 207.917103 83.917103) (end 209.872897 83.917103) (width 0.146) (layer "In5.Cu") (net 293))
  (segment (start 216.26 81.88) (end 216.31 81.83) (width 0.146) (layer "In5.Cu") (net 293))
  (segment (start 204.117103 83.717103) (end 204.117103 84.14956) (width 0.146) (layer "In5.Cu") (net 293))
  (segment (start 209.872897 83.917103) (end 210.19 83.6) (width 0.146) (layer "In5.Cu") (net 293))
  (segment (start 217.462067 81.285011) (end 217.462068 81.285011) (width 0.146) (layer "In5.Cu") (net 293))
  (segment (start 218.007057 80.132941) (end 218.11 80.029998) (width 0.146) (layer "In5.Cu") (net 293))
  (segment (start 218.027753 80.719325) (end 218.027754 80.719325) (width 0.146) (layer "In5.Cu") (net 293))
  (segment (start 218.027754 80.436482) (end 218.007056 80.415784) (width 0.146) (layer "In5.Cu") (net 293))
  (segment (start 217.462068 81.002167) (end 217.462068 81.002168) (width 0.146) (layer "In5.Cu") (net 293))
  (segment (start 194.461 85.546) (end 197.104 85.546) (width 0.09) (layer "In5.Cu") (net 293))
  (segment (start 198.13 85.12) (end 202.184207 85.12) (width 0.146) (layer "In5.Cu") (net 293))
  (segment (start 216.896381 81.567853) (end 216.896381 81.567854) (width 0.146) (layer "In5.Cu") (net 293))
  (segment (start 202.184207 85.12) (end 203.387103 83.917103) (width 0.146) (layer "In5.Cu") (net 293))
  (segment (start 233.09 61.01368) (end 233.036328 60.960008) (width 0.146) (layer "In5.Cu") (net 293))
  (segment (start 210.19 83.6) (end 214.22 83.6) (width 0.146) (layer "In5.Cu") (net 293))
  (segment (start 206.917103 84.14956) (end 206.917103 83.684646) (width 0.146) (layer "In5.Cu") (net 293))
  (segment (start 197.53 85.12) (end 198.13 85.12) (width 0.09) (layer "In5.Cu") (net 293))
  (segment (start 217.462068 81.002168) (end 217.137832 80.677932) (width 0.146) (layer "In5.Cu") (net 293))
  (segment (start 204.917103 83.684646) (end 204.917103 84.14956) (width 0.146) (layer "In5.Cu") (net 293))
  (segment (start 214.22 83.6) (end 215.94 81.88) (width 0.146) (layer "In5.Cu") (net 293))
  (segment (start 216.854989 80.960775) (end 217.179225 81.285011) (width 0.146) (layer "In5.Cu") (net 293))
  (segment (start 203.387103 83.917103) (end 203.517103 83.917103) (width 0.146) (layer "In5.Cu") (net 293))
  (segment (start 194.15 85.235) (end 194.461 85.546) (width 0.09) (layer "In5.Cu") (net 293))
  (segment (start 218.027754 80.436481) (end 218.027754 80.436482) (width 0.146) (layer "In5.Cu") (net 293))
  (segment (start 205.717103 83.684646) (end 205.717103 84.14956) (width 0.146) (layer "In5.Cu") (net 293))
  (segment (start 233.09 64.73) (end 233.09 61.01368) (width 0.146) (layer "In5.Cu") (net 293))
  (segment (start 194.15 83.565844) (end 194.15 85.235) (width 0.09) (layer "In5.Cu") (net 293))
  (segment (start 218.11 79.71) (end 233.09 64.73) (width 0.146) (layer "In5.Cu") (net 293))
  (segment (start 217.420675 80.395089) (end 217.744911 80.719325) (width 0.146) (layer "In5.Cu") (net 293))
  (segment (start 207.317103 83.684646) (end 207.317103 84.14956) (width 0.146) (layer "In5.Cu") (net 293))
  (segment (start 194.655836 83.060008) (end 194.15 83.565844) (width 0.09) (layer "In5.Cu") (net 293))
  (segment (start 217.420677 80.395088) (end 217.420675 80.395089) (width 0.146) (layer "In5.Cu") (net 293))
  (segment (start 207.717103 84.14956) (end 207.717103 84.117103) (width 0.146) (layer "In5.Cu") (net 293))
  (segment (start 206.117103 84.14956) (end 206.117103 83.684646) (width 0.146) (layer "In5.Cu") (net 293))
  (segment (start 216.896382 81.850696) (end 216.896381 81.850697) (width 0.146) (layer "In5.Cu") (net 293))
  (segment (start 216.592842 81.83) (end 216.613539 81.850697) (width 0.146) (layer "In5.Cu") (net 293))
  (segment (start 216.572146 80.960776) (end 216.572147 80.960774) (width 0.146) (layer "In5.Cu") (net 293))
  (segment (start 216.854991 80.960774) (end 216.854989 80.960775) (width 0.146) (layer "In5.Cu") (net 293))
  (segment (start 204.117103 83.684646) (end 204.117103 83.717103) (width 0.146) (layer "In5.Cu") (net 293))
  (segment (start 217.137832 80.39509) (end 217.137833 80.395088) (width 0.146) (layer "In5.Cu") (net 293))
  (segment (start 218.11 80.029998) (end 218.11 79.71) (width 0.146) (layer "In5.Cu") (net 293))
  (segment (start 197.104 85.546) (end 197.53 85.12) (width 0.09) (layer "In5.Cu") (net 293))
  (segment (start 205.317103 84.14956) (end 205.317103 83.684646) (width 0.146) (layer "In5.Cu") (net 293))
  (segment (start 206.517103 83.684646) (end 206.517103 84.14956) (width 0.146) (layer "In5.Cu") (net 293))
  (arc (start 206.517103 84.14956) (mid 206.575682 84.290981) (end 206.717103 84.34956) (width 0.146) (layer "In5.Cu") (net 293))
  (arc (start 204.517103 83.684646) (mid 204.575682 83.543225) (end 204.717103 83.484646) (width 0.146) (layer "In5.Cu") (net 293))
  (arc (start 218.027754 80.719325) (mid 218.086333 80.577903) (end 218.027754 80.436481) (width 0.146) (layer "In5.Cu") (net 293))
  (arc (start 203.917103 83.484646) (mid 204.058524 83.543225) (end 204.117103 83.684646) (width 0.146) (layer "In5.Cu") (net 293))
  (arc (start 205.317103 83.684646) (mid 205.375682 83.543225) (end 205.517103 83.484646) (width 0.146) (layer "In5.Cu") (net 293))
  (arc (start 206.917103 83.684646) (mid 206.975682 83.543225) (end 207.117103 83.484646) (width 0.146) (layer "In5.Cu") (net 293))
  (arc (start 207.717103 84.117103) (mid 207.775682 83.975682) (end 207.917103 83.917103) (width 0.146) (layer "In5.Cu") (net 293))
  (arc (start 204.917103 84.14956) (mid 204.975682 84.290981) (end 205.117103 84.34956) (width 0.146) (layer "In5.Cu") (net 293))
  (arc (start 204.317103 84.34956) (mid 204.458524 84.290981) (end 204.517103 84.14956) (width 0.146) (layer "In5.Cu") (net 293))
  (arc (start 203.717103 83.684646) (mid 203.775682 83.543225) (end 203.917103 83.484646) (width 0.146) (layer "In5.Cu") (net 293))
  (arc (start 216.31 81.83) (mid 216.451421 81.771422) (end 216.592842 81.83) (width 0.146) (layer "In5.Cu") (net 293))
  (arc (start 216.613539 81.850697) (mid 216.754961 81.909275) (end 216.896382 81.850696) (width 0.146) (layer "In5.Cu") (net 293))
  (arc (start 204.117103 84.14956) (mid 204.175682 84.290981) (end 204.317103 84.34956) (width 0.146) (layer "In5.Cu") (net 293))
  (arc (start 217.137832 80.677932) (mid 217.079255 80.53651) (end 217.137832 80.39509) (width 0.146) (layer "In5.Cu") (net 293))
  (arc (start 206.317103 83.484646) (mid 206.458524 83.543225) (end 206.517103 83.684646) (width 0.146) (layer "In5.Cu") (net 293))
  (arc (start 207.117103 83.484646) (mid 207.258524 83.543225) (end 207.317103 83.684646) (width 0.146) (layer "In5.Cu") (net 293))
  (arc (start 218.007056 80.415784) (mid 217.948478 80.274362) (end 218.007057 80.132941) (width 0.146) (layer "In5.Cu") (net 293))
  (arc (start 205.917103 84.34956) (mid 206.058524 84.290981) (end 206.117103 84.14956) (width 0.146) (layer "In5.Cu") (net 293))
  (arc (start 217.744911 80.719325) (mid 217.886332 80.777903) (end 218.027753 80.719325) (width 0.146) (layer "In5.Cu") (net 293))
  (arc (start 206.717103 84.34956) (mid 206.858524 84.290981) (end 206.917103 84.14956) (width 0.146) (layer "In5.Cu") (net 293))
  (arc (start 217.179225 81.285011) (mid 217.320646 81.343589) (end 217.462067 81.285011) (width 0.146) (layer "In5.Cu") (net 293))
  (arc (start 204.717103 83.484646) (mid 204.858524 83.543225) (end 204.917103 83.684646) (width 0.146) (layer "In5.Cu") (net 293))
  (arc (start 205.117103 84.34956) (mid 205.258524 84.290981) (end 205.317103 84.14956) (width 0.146) (layer "In5.Cu") (net 293))
  (arc (start 207.517103 84.34956) (mid 207.658524 84.290981) (end 207.717103 84.14956) (width 0.146) (layer "In5.Cu") (net 293))
  (arc (start 205.517103 83.484646) (mid 205.658524 83.543225) (end 205.717103 83.684646) (width 0.146) (layer "In5.Cu") (net 293))
  (arc (start 206.117103 83.684646) (mid 206.175682 83.543225) (end 206.317103 83.484646) (width 0.146) (layer "In5.Cu") (net 293))
  (arc (start 216.896381 81.850697) (mid 216.95496 81.709275) (end 216.896381 81.567853) (width 0.146) (layer "In5.Cu") (net 293))
  (arc (start 216.572146 81.243618) (mid 216.513569 81.102196) (end 216.572146 80.960776) (width 0.146) (layer "In5.Cu") (net 293))
  (arc (start 217.137833 80.395088) (mid 217.279254 80.33651) (end 217.420677 80.395088) (width 0.146) (layer "In5.Cu") (net 293))
  (arc (start 216.572147 80.960774) (mid 216.713568 80.902196) (end 216.854991 80.960774) (width 0.146) (layer "In5.Cu") (net 293))
  (arc (start 217.462068 81.285011) (mid 217.520647 81.143589) (end 217.462068 81.002167) (width 0.146) (layer "In5.Cu") (net 293))
  (arc (start 203.517103 83.917103) (mid 203.658524 83.858524) (end 203.717103 83.717103) (width 0.146) (layer "In5.Cu") (net 293))
  (arc (start 207.317103 84.14956) (mid 207.375682 84.290981) (end 207.517103 84.34956) (width 0.146) (layer "In5.Cu") (net 293))
  (arc (start 205.717103 84.14956) (mid 205.775682 84.290981) (end 205.917103 84.34956) (width 0.146) (layer "In5.Cu") (net 293))
  (segment (start 195.136328 85.560008) (end 195.636328 85.060008) (width 0.127) (layer "F.Cu") (net 294))
  (segment (start 195.636328 85.060008) (end 195.655836 85.060008) (width 0.127) (layer "F.Cu") (net 294))
  (segment (start 225.386328 59.660008) (end 225.386328 60.960008) (width 0.2) (layer "F.Cu") (net 294))
  (via blind (at 225.386328 60.960008) (size 0.5) (drill 0.2) (layers "F.Cu" "In2.Cu") (net 294))
  (via blind (at 195.655836 85.060008) (size 0.5) (drill 0.2) (layers "F.Cu" "In2.Cu") (net 294))
  (segment (start 198.11 85.02) (end 199.48 85.02) (width 0.16) (layer "In2.Cu") (net 294))
  (segment (start 217.082187 77.882007) (end 217.082187 77.882006) (width 0.16) (layer "In2.Cu") (net 294))
  (segment (start 216.304369 78.659825) (end 216.304369 78.659824) (width 0.16) (layer "In2.Cu") (net 294))
  (segment (start 213.475736 82.772794) (end 213.475735 82.772795) (width 0.16) (layer "In2.Cu") (net 294))
  (segment (start 215.91546 78.659824) (end 215.915459 78.659825) (width 0.16) (layer "In2.Cu") (net 294))
  (segment (start 212.627206 82.348528) (end 213.051472 82.772794) (width 0.16) (layer "In2.Cu") (net 294))
  (segment (start 217.082187 77.882006) (end 217.105637 77.905456) (width 0.16) (layer "In2.Cu") (net 294))
  (segment (start 225.386328 70.013672) (end 225.386328 60.960008) (width 0.16) (layer "In2.Cu") (net 294))
  (segment (start 211.6 83.8) (end 212.202941 83.197057) (width 0.16) (layer "In2.Cu") (net 294))
  (segment (start 216.351266 79.48454) (end 215.915459 79.048733) (width 0.16) (layer "In2.Cu") (net 294))
  (segment (start 212.202942 82.348528) (end 212.202941 82.348529) (width 0.16) (layer "In2.Cu") (net 294))
  (segment (start 216.693278 77.882006) (end 216.693277 77.882007) (width 0.16) (layer "In2.Cu") (net 294))
  (segment (start 213.475735 81.5) (end 213.475734 81.5) (width 0.16) (layer "In2.Cu") (net 294))
  (segment (start 213.475736 82.34853) (end 213.05147 81.924264) (width 0.16) (layer "In2.Cu") (net 294))
  (segment (start 197.532 85.538) (end 198.05 85.02) (width 0.1) (layer "In2.Cu") (net 294))
  (segment (start 216.351266 79.87345) (end 216.351266 79.873449) (width 0.16) (layer "In2.Cu") (net 294))
  (segment (start 215.938908 79.85) (end 215.962357 79.873449) (width 0.16) (layer "In2.Cu") (net 294))
  (segment (start 195.655836 85.060008) (end 196.133828 85.538) (width 0.1) (layer "In2.Cu") (net 294))
  (segment (start 198.05 85.02) (end 198.11 85.02) (width 0.1) (layer "In2.Cu") (net 294))
  (segment (start 213.05147 81.5) (end 213.05147 81.499999) (width 0.16) (layer "In2.Cu") (net 294))
  (segment (start 200.7 83.8) (end 211.6 83.8) (width 0.16) (layer "In2.Cu") (net 294))
  (segment (start 216.351266 79.484539) (end 216.351266 79.48454) (width 0.16) (layer "In2.Cu") (net 294))
  (segment (start 199.48 85.02) (end 200.7 83.8) (width 0.16) (layer "In2.Cu") (net 294))
  (segment (start 216.304369 78.659824) (end 216.740176 79.095632) (width 0.16) (layer "In2.Cu") (net 294))
  (segment (start 217.129084 78.706723) (end 216.693277 78.270915) (width 0.16) (layer "In2.Cu") (net 294))
  (segment (start 217.129084 78.706722) (end 217.129084 78.706723) (width 0.16) (layer "In2.Cu") (net 294))
  (segment (start 213.9 81.5) (end 215.55 79.85) (width 0.16) (layer "In2.Cu") (net 294))
  (segment (start 196.133828 85.538) (end 197.532 85.538) (width 0.1) (layer "In2.Cu") (net 294))
  (segment (start 217.129085 79.095631) (end 217.129084 79.095632) (width 0.16) (layer "In2.Cu") (net 294))
  (segment (start 217.494545 77.905457) (end 225.386328 70.013672) (width 0.16) (layer "In2.Cu") (net 294))
  (segment (start 217.494546 77.905457) (end 217.494545 77.905457) (width 0.16) (layer "In2.Cu") (net 294))
  (arc (start 216.693277 78.270915) (mid 216.612732 78.07646) (end 216.693278 77.882006) (width 0.16) (layer "In2.Cu") (net 294))
  (arc (start 217.129084 79.095632) (mid 217.20963 78.901177) (end 217.129084 78.706722) (width 0.16) (layer "In2.Cu") (net 294))
  (arc (start 215.55 79.85) (mid 215.744454 79.769455) (end 215.938908 79.85) (width 0.16) (layer "In2.Cu") (net 294))
  (arc (start 213.475734 81.5) (mid 213.687867 81.587868) (end 213.9 81.5) (width 0.16) (layer "In2.Cu") (net 294))
  (arc (start 216.740176 79.095632) (mid 216.934631 79.176177) (end 217.129085 79.095631) (width 0.16) (layer "In2.Cu") (net 294))
  (arc (start 217.105637 77.905456) (mid 217.300091 77.986002) (end 217.494546 77.905457) (width 0.16) (layer "In2.Cu") (net 294))
  (arc (start 212.202941 83.197057) (mid 212.29081 82.984925) (end 212.202942 82.772792) (width 0.16) (layer "In2.Cu") (net 294))
  (arc (start 215.962357 79.873449) (mid 216.156811 79.953995) (end 216.351266 79.87345) (width 0.16) (layer "In2.Cu") (net 294))
  (arc (start 213.05147 81.924264) (mid 212.963602 81.712132) (end 213.05147 81.5) (width 0.16) (layer "In2.Cu") (net 294))
  (arc (start 212.202941 82.348529) (mid 212.415073 82.26066) (end 212.627206 82.348528) (width 0.16) (layer "In2.Cu") (net 294))
  (arc (start 216.351266 79.873449) (mid 216.431812 79.678994) (end 216.351266 79.484539) (width 0.16) (layer "In2.Cu") (net 294))
  (arc (start 213.05147 81.499999) (mid 213.263603 81.412131) (end 213.475735 81.5) (width 0.16) (layer "In2.Cu") (net 294))
  (arc (start 215.915459 78.659825) (mid 216.109915 78.579278) (end 216.304369 78.659825) (width 0.16) (layer "In2.Cu") (net 294))
  (arc (start 213.475735 82.772795) (mid 213.563603 82.560664) (end 213.475736 82.34853) (width 0.16) (layer "In2.Cu") (net 294))
  (arc (start 216.693277 77.882007) (mid 216.887733 77.80146) (end 217.082187 77.882007) (width 0.16) (layer "In2.Cu") (net 294))
  (arc (start 215.915459 79.048733) (mid 215.834914 78.854278) (end 215.91546 78.659824) (width 0.16) (layer "In2.Cu") (net 294))
  (arc (start 212.202942 82.772792) (mid 212.115074 82.56066) (end 212.202942 82.348528) (width 0.16) (layer "In2.Cu") (net 294))
  (arc (start 213.051472 82.772794) (mid 213.263604 82.860662) (end 213.475736 82.772794) (width 0.16) (layer "In2.Cu") (net 294))
  (segment (start 174.136328 87.560008) (end 174.636328 87.060008) (width 0.1) (layer "F.Cu") (net 295))
  (segment (start 199.036328 59.660008) (end 199.036328 60.960008) (width 0.2) (layer "F.Cu") (net 295))
  (via (at 199.036328 60.960008) (size 0.5) (drill 0.2) (layers "F.Cu" "B.Cu") (net 295))
  (via (at 174.636328 87.060008) (size 0.5) (drill 0.2) (layers "F.Cu" "B.Cu") (net 295))
  (segment (start 184.6 63.180509) (end 184.6 62.419491) (width 0.196) (layer "In7.Cu") (net 295))
  (segment (start 186.1 62.419491) (end 186.1 63.180509) (width 0.196) (layer "In7.Cu") (net 295))
  (segment (start 184.1 62.419491) (end 184.1 63.180509) (width 0.196) (layer "In7.Cu") (net 295))
  (segment (start 186.85 62.8) (end 198.04 62.8) (width 0.196) (layer "In7.Cu") (net 295))
  (segment (start 183.6 63.180509) (end 183.6 63.05) (width 0.196) (layer "In7.Cu") (net 295))
  (segment (start 185.1 62.419491) (end 185.1 63.180509) (width 0.196) (layer "In7.Cu") (net 295))
  (segment (start 173.5 82.828) (end 173.5 85.310618) (width 0.127) (layer "In7.Cu") (net 295))
  (segment (start 185.6 63.180509) (end 185.6 62.419491) (width 0.196) (layer "In7.Cu") (net 295))
  (segment (start 186.6 63.180509) (end 186.6 63.05) (width 0.196) (layer "In7.Cu") (net 295))
  (segment (start 198.04 62.8) (end 199.036328 61.803672) (width 0.196) (layer "In7.Cu") (net 295))
  (segment (start 174.8795 76.5205) (end 174.8795 76.9995) (width 0.127) (layer "In7.Cu") (net 295))
  (segment (start 174.8795 76.9995) (end 175.2035 77.3235) (width 0.127) (layer "In7.Cu") (net 295))
  (segment (start 183.1 63.05) (end 183.1 63.180509) (width 0.196) (layer "In7.Cu") (net 295))
  (segment (start 175.2035 66.844648) (end 179.248148 62.8) (width 0.196) (layer "In7.Cu") (net 295))
  (segment (start 175.2035 75.55) (end 175.2035 76.1965) (width 0.127) (layer "In7.Cu") (net 295))
  (segment (start 175.2035 81.1245) (end 173.5 82.828) (width 0.127) (layer "In7.Cu") (net 295))
  (segment (start 175.2035 77.3235) (end 175.2035 81.1245) (width 0.127) (layer "In7.Cu") (net 295))
  (segment (start 174.636328 86.446946) (end 174.636328 87.060008) (width 0.127) (layer "In7.Cu") (net 295))
  (segment (start 183.6 63.05) (end 183.6 62.419491) (width 0.196) (layer "In7.Cu") (net 295))
  (segment (start 173.5 85.310618) (end 174.636328 86.446946) (width 0.127) (layer "In7.Cu") (net 295))
  (segment (start 179.248148 62.8) (end 182.85 62.8) (width 0.196) (layer "In7.Cu") (net 295))
  (segment (start 175.2035 76.1965) (end 174.8795 76.5205) (width 0.127) (layer "In7.Cu") (net 295))
  (segment (start 175.2035 75.55) (end 175.2035 66.844648) (width 0.196) (layer "In7.Cu") (net 295))
  (segment (start 199.036328 61.803672) (end 199.036328 60.960008) (width 0.196) (layer "In7.Cu") (net 295))
  (arc (start 183.85 62.169491) (mid 184.026777 62.242714) (end 184.1 62.419491) (width 0.196) (layer "In7.Cu") (net 295))
  (arc (start 185.6 62.419491) (mid 185.673223 62.242714) (end 185.85 62.169491) (width 0.196) (layer "In7.Cu") (net 295))
  (arc (start 186.35 63.430509) (mid 186.526777 63.357286) (end 186.6 63.180509) (width 0.196) (layer "In7.Cu") (net 295))
  (arc (start 185.1 63.180509) (mid 185.173223 63.357286) (end 185.35 63.430509) (width 0.196) (layer "In7.Cu") (net 295))
  (arc (start 186.6 63.05) (mid 186.673223 62.873223) (end 186.85 62.8) (width 0.196) (layer "In7.Cu") (net 295))
  (arc (start 186.1 63.180509) (mid 186.173223 63.357286) (end 186.35 63.430509) (width 0.196) (layer "In7.Cu") (net 295))
  (arc (start 183.1 63.180509) (mid 183.173223 63.357286) (end 183.35 63.430509) (width 0.196) (layer "In7.Cu") (net 295))
  (arc (start 183.35 63.430509) (mid 183.526777 63.357286) (end 183.6 63.180509) (width 0.196) (layer "In7.Cu") (net 295))
  (arc (start 184.35 63.430509) (mid 184.526777 63.357286) (end 184.6 63.180509) (width 0.196) (layer "In7.Cu") (net 295))
  (arc (start 184.6 62.419491) (mid 184.673223 62.242714) (end 184.85 62.169491) (width 0.196) (layer "In7.Cu") (net 295))
  (arc (start 182.85 62.8) (mid 183.026777 62.873223) (end 183.1 63.05) (width 0.196) (layer "In7.Cu") (net 295))
  (arc (start 185.85 62.169491) (mid 186.026777 62.242714) (end 186.1 62.419491) (width 0.196) (layer "In7.Cu") (net 295))
  (arc (start 184.85 62.169491) (mid 185.026777 62.242714) (end 185.1 62.419491) (width 0.196) (layer "In7.Cu") (net 295))
  (arc (start 184.1 63.180509) (mid 184.173223 63.357286) (end 184.35 63.430509) (width 0.196) (layer "In7.Cu") (net 295))
  (arc (start 185.35 63.430509) (mid 185.526777 63.357286) (end 185.6 63.180509) (width 0.196) (layer "In7.Cu") (net 295))
  (arc (start 183.6 62.419491) (mid 183.673223 62.242714) (end 183.85 62.169491) (width 0.196) (layer "In7.Cu") (net 295))
  (segment (start 193.086328 59.660008) (end 193.086328 60.960008) (width 0.2) (layer "F.Cu") (net 296))
  (segment (start 187.189992 78.560008) (end 187.136328 78.560008) (width 0.127) (layer "F.Cu") (net 296))
  (segment (start 187.713039 78.036961) (end 187.189992 78.560008) (width 0.127) (layer "F.Cu") (net 296))
  (segment (start 187.7345 78.036961) (end 187.713039 78.036961) (width 0.127) (layer "F.Cu") (net 296))
  (via blind (at 193.086328 60.960008) (size 0.5) (drill 0.2) (layers "F.Cu" "In2.Cu") (net 296))
  (via blind (at 187.7345 78.036961) (size 0.5) (drill 0.2) (layers "F.Cu" "In2.Cu") (net 296))
  (segment (start 188.33 75.55) (end 188.33 72.405) (width 0.16) (layer "In2.Cu") (net 296))
  (segment (start 192.225 66.275) (end 193.625 66.275) (width 0.16) (layer "In2.Cu") (net 296))
  (segment (start 188.33 75.795) (end 188.33 75.55) (width 0.1) (layer "In2.Cu") (net 296))
  (segment (start 189.320434 70.286516) (end 189.320436 70.286515) (width 0.16) (layer "In2.Cu") (net 296))
  (segment (start 193.375 64.925) (end 193.225 64.925) (width 0.16) (layer "In2.Cu") (net 296))
  (segment (start 193.2 62.761328) (end 193.3 62.761328) (width 0.16) (layer "In2.Cu") (net 296))
  (segment (start 189.778609 70.991216) (end 189.320435 70.533041) (width 0.16) (layer "In2.Cu") (net 296))
  (segment (start 192.385008 61.661328) (end 193.086328 60.960008) (width 0.16) (layer "In2.Cu") (net 296))
  (segment (start 188.1 77.671461) (end 188.1 76.025) (width 0.1) (layer "In2.Cu") (net 296))
  (segment (start 191.863672 62.571584) (end 191.863672 62.511328) (width 0.16) (layer "In2.Cu") (net 296))
  (segment (start 189.002236 70.851241) (end 189.460411 71.309415) (width 0.16) (layer "In2.Cu") (net 296))
  (segment (start 189.956833 69.650117) (end 189.956835 69.650116) (width 0.16) (layer "In2.Cu") (net 296))
  (segment (start 193 64.7) (end 193 62.961328) (width 0.16) (layer "In2.Cu") (net 296))
  (segment (start 190.593234 69.013717) (end 190.664907 68.942045) (width 0.16) (layer "In2.Cu") (net 296))
  (segment (start 193.625 66.725) (end 192.225 66.725) (width 0.16) (layer "In2.Cu") (net 296))
  (segment (start 190.450363 70.390172) (end 189.956834 69.896642) (width 0.16) (layer "In2.Cu") (net 296))
  (segment (start 189.14221 71.627615) (end 188.684036 71.16944) (width 0.16) (layer "In2.Cu") (net 296))
  (segment (start 188.648198 71.77) (end 188.824012 71.945814) (width 0.16) (layer "In2.Cu") (net 296))
  (segment (start 192.025003 68.075) (end 192.547838 68.075) (width 0.16) (layer "In2.Cu") (net 296))
  (segment (start 188.684037 70.922914) (end 188.75571 70.851242) (width 0.16) (layer "In2.Cu") (net 296))
  (segment (start 192.547838 67.625) (end 192.225 67.625) (width 0.16) (layer "In2.Cu") (net 296))
  (segment (start 190.911433 68.942044) (end 190.911434 68.942045) (width 0.16) (layer "In2.Cu") (net 296))
  (segment (start 193.625 65.825) (end 192.225 65.825) (width 0.16) (layer "In2.Cu") (net 296))
  (segment (start 189.956835 69.650116) (end 190.028508 69.578444) (width 0.16) (layer "In2.Cu") (net 296))
  (segment (start 189.002234 70.851242) (end 189.002236 70.851241) (width 0.16) (layer "In2.Cu") (net 296))
  (segment (start 191.440316 70.107327) (end 190.593233 69.260243) (width 0.16) (layer "In2.Cu") (net 296))
  (segment (start 188.21 71.89) (end 188.33 71.77) (width 0.16) (layer "In2.Cu") (net 296))
  (segment (start 189.638635 70.214842) (end 190.132165 70.708371) (width 0.16) (layer "In2.Cu") (net 296))
  (segment (start 189.320436 70.286515) (end 189.392109 70.214843) (width 0.16) (layer "In2.Cu") (net 296))
  (segment (start 191.563672 62.211328) (end 191.525 62.211328) (width 0.16) (layer "In2.Cu") (net 296))
  (segment (start 189.778609 70.991215) (end 189.778609 70.991216) (width 0.16) (layer "In2.Cu") (net 296))
  (segment (start 192.463672 62.537366) (end 192.463672 62.571584) (width 0.16) (layer "In2.Cu") (net 296))
  (segment (start 190.593232 69.013718) (end 190.593234 69.013717) (width 0.16) (layer "In2.Cu") (net 296))
  (segment (start 193.3 62.211328) (end 192.78971 62.211328) (width 0.16) (layer "In2.Cu") (net 296))
  (segment (start 188.33 72.405) (end 188.21 72.285) (width 0.16) (layer "In2.Cu") (net 296))
  (segment (start 188.684035 70.922915) (end 188.684037 70.922914) (width 0.16) (layer "In2.Cu") (net 296))
  (segment (start 189.14221 71.627614) (end 189.14221 71.627615) (width 0.16) (layer "In2.Cu") (net 296))
  (segment (start 191.157958 68.942045) (end 192.025003 68.075) (width 0.16) (layer "In2.Cu") (net 296))
  (segment (start 191.440316 70.107326) (end 191.440316 70.107327) (width 0.16) (layer "In2.Cu") (net 296))
  (segment (start 188.1 76.025) (end 188.33 75.795) (width 0.1) (layer "In2.Cu") (net 296))
  (segment (start 190.450363 70.390171) (end 190.450363 70.390172) (width 0.16) (layer "In2.Cu") (net 296))
  (segment (start 192.225 67.175) (end 193.625 67.175) (width 0.16) (layer "In2.Cu") (net 296))
  (segment (start 191.525 61.661328) (end 192.385008 61.661328) (width 0.16) (layer "In2.Cu") (net 296))
  (segment (start 190.911431 68.942045) (end 190.911433 68.942044) (width 0.16) (layer "In2.Cu") (net 296))
  (segment (start 189.638633 70.214843) (end 189.638635 70.214842) (width 0.16) (layer "In2.Cu") (net 296))
  (segment (start 187.7345 78.036961) (end 188.1 77.671461) (width 0.1) (layer "In2.Cu") (net 296))
  (segment (start 188.21 72.285) (end 188.21 71.89) (width 0.16) (layer "In2.Cu") (net 296))
  (segment (start 190.275032 69.578444) (end 190.275034 69.578443) (width 0.16) (layer "In2.Cu") (net 296))
  (segment (start 192.225 65.375) (end 193.375 65.375) (width 0.16) (layer "In2.Cu") (net 296))
  (segment (start 190.275034 69.578443) (end 191.122118 70.425526) (width 0.16) (layer "In2.Cu") (net 296))
  (arc (start 190.132165 70.708371) (mid 190.291264 70.774272) (end 190.450363 70.708371) (width 0.16) (layer "In2.Cu") (net 296))
  (arc (start 191.863672 62.511328) (mid 191.775804 62.299196) (end 191.563672 62.211328) (width 0.16) (layer "In2.Cu") (net 296))
  (arc (start 191.25 61.936328) (mid 191.330546 61.741874) (end 191.525 61.661328) (width 0.16) (layer "In2.Cu") (net 296))
  (arc (start 192.225 66.725) (mid 192.065901 66.659099) (end 192 66.5) (width 0.16) (layer "In2.Cu") (net 296))
  (arc (start 193.625 67.175) (mid 193.784099 67.109099) (end 193.85 66.95) (width 0.16) (layer "In2.Cu") (net 296))
  (arc (start 192 67.4) (mid 192.065901 67.240901) (end 192.225 67.175) (width 0.16) (layer "In2.Cu") (net 296))
  (arc (start 193.85 66.05) (mid 193.784099 65.890901) (end 193.625 65.825) (width 0.16) (layer "In2.Cu") (net 296))
  (arc (start 193.6 65.15) (mid 193.534099 64.990901) (end 193.375 64.925) (width 0.16) (layer "In2.Cu") (net 296))
  (arc (start 193 62.961328) (mid 193.058579 62.819907) (end 193.2 62.761328) (width 0.16) (layer "In2.Cu") (net 296))
  (arc (start 191.122118 70.425526) (mid 191.281217 70.491427) (end 191.440316 70.425526) (width 0.16) (layer "In2.Cu") (net 296))
  (arc (start 192.78971 62.211328) (mid 192.559166 62.306822) (end 192.463672 62.537366) (width 0.16) (layer "In2.Cu") (net 296))
  (arc (start 190.028508 69.578444) (mid 190.151771 69.527386) (end 190.275032 69.578444) (width 0.16) (layer "In2.Cu") (net 296))
  (arc (start 193.85 66.95) (mid 193.784099 66.790901) (end 193.625 66.725) (width 0.16) (layer "In2.Cu") (net 296))
  (arc (start 190.450363 70.708371) (mid 190.516264 70.549271) (end 190.450363 70.390171) (width 0.16) (layer "In2.Cu") (net 296))
  (arc (start 192.163672 62.871584) (mid 191.95154 62.783716) (end 191.863672 62.571584) (width 0.16) (layer "In2.Cu") (net 296))
  (arc (start 193.625 66.275) (mid 193.784099 66.209099) (end 193.85 66.05) (width 0.16) (layer "In2.Cu") (net 296))
  (arc (start 188.33 71.77) (mid 188.489099 71.704099) (end 188.648198 71.77) (width 0.16) (layer "In2.Cu") (net 296))
  (arc (start 192.547838 68.075) (mid 192.706937 68.009099) (end 192.772838 67.85) (width 0.16) (layer "In2.Cu") (net 296))
  (arc (start 193.575 62.486328) (mid 193.494454 62.291874) (end 193.3 62.211328) (width 0.16) (layer "In2.Cu") (net 296))
  (arc (start 190.593233 69.260243) (mid 190.542177 69.13698) (end 190.593232 69.013718) (width 0.16) (layer "In2.Cu") (net 296))
  (arc (start 188.824012 71.945814) (mid 188.983111 72.011715) (end 189.14221 71.945814) (width 0.16) (layer "In2.Cu") (net 296))
  (arc (start 192 66.5) (mid 192.065901 66.340901) (end 192.225 66.275) (width 0.16) (layer "In2.Cu") (net 296))
  (arc (start 192.463672 62.571584) (mid 192.375804 62.783716) (end 192.163672 62.871584) (width 0.16) (layer "In2.Cu") (net 296))
  (arc (start 193.3 62.761328) (mid 193.494454 62.680782) (end 193.575 62.486328) (width 0.16) (layer "In2.Cu") (net 296))
  (arc (start 189.14221 71.945814) (mid 189.208111 71.786714) (end 189.14221 71.627614) (width 0.16) (layer "In2.Cu") (net 296))
  (arc (start 188.684036 71.16944) (mid 188.63298 71.046177) (end 188.684035 70.922915) (width 0.16) (layer "In2.Cu") (net 296))
  (arc (start 190.664907 68.942045) (mid 190.78817 68.890987) (end 190.911431 68.942045) (width 0.16) (layer "In2.Cu") (net 296))
  (arc (start 188.75571 70.851242) (mid 188.878973 70.800184) (end 189.002234 70.851242) (width 0.16) (layer "In2.Cu") (net 296))
  (arc (start 193.375 65.375) (mid 193.534099 65.309099) (end 193.6 65.15) (width 0.16) (layer "In2.Cu") (net 296))
  (arc (start 189.392109 70.214843) (mid 189.515372 70.163785) (end 189.638633 70.214843) (width 0.16) (layer "In2.Cu") (net 296))
  (arc (start 193.225 64.925) (mid 193.065901 64.859099) (end 193 64.7) (width 0.16) (layer "In2.Cu") (net 296))
  (arc (start 189.320435 70.533041) (mid 189.269379 70.409778) (end 189.320434 70.286516) (width 0.16) (layer "In2.Cu") (net 296))
  (arc (start 190.911434 68.942045) (mid 191.034695 68.993103) (end 191.157958 68.942045) (width 0.16) (layer "In2.Cu") (net 296))
  (arc (start 189.956834 69.896642) (mid 189.905778 69.773379) (end 189.956833 69.650117) (width 0.16) (layer "In2.Cu") (net 296))
  (arc (start 191.440316 70.425526) (mid 191.506217 70.266426) (end 191.440316 70.107326) (width 0.16) (layer "In2.Cu") (net 296))
  (arc (start 192.772838 67.85) (mid 192.706937 67.690901) (end 192.547838 67.625) (width 0.16) (layer "In2.Cu") (net 296))
  (arc (start 192.225 65.825) (mid 192.065901 65.759099) (end 192 65.6) (width 0.16) (layer "In2.Cu") (net 296))
  (arc (start 192 65.6) (mid 192.065901 65.440901) (end 192.225 65.375) (width 0.16) (layer "In2.Cu") (net 296))
  (arc (start 191.525 62.211328) (mid 191.330546 62.130782) (end 191.25 61.936328) (width 0.16) (layer "In2.Cu") (net 296))
  (arc (start 189.460411 71.309415) (mid 189.61951 71.375316) (end 189.778609 71.309415) (width 0.16) (layer "In2.Cu") (net 296))
  (arc (start 192.225 67.625) (mid 192.065901 67.559099) (end 192 67.4) (width 0.16) (layer "In2.Cu") (net 296))
  (arc (start 189.778609 71.309415) (mid 189.84451 71.150315) (end 189.778609 70.991215) (width 0.16) (layer "In2.Cu") (net 296))
  (segment (start 192.136328 81.560008) (end 192.636328 81.060008) (width 0.127) (layer "F.Cu") (net 297))
  (segment (start 238.136328 59.660008) (end 238.136328 60.960008) (width 0.2) (layer "F.Cu") (net 297))
  (segment (start 192.636328 81.060008) (end 192.655836 81.060008) (width 0.127) (layer "F.Cu") (net 297))
  (via (at 192.655836 81.060008) (size 0.5) (drill 0.2) (layers "F.Cu" "B.Cu") (net 297))
  (via (at 238.136328 60.960008) (size 0.5) (drill 0.2) (layers "F.Cu" "B.Cu") (net 297))
  (segment (start 204.791389 78.746665) (end 204.791389 78.746664) (width 0.16) (layer "In9.Cu") (net 297))
  (segment (start 204.013571 79.135572) (end 204.013571 79.135573) (width 0.16) (layer "In9.Cu") (net 297))
  (segment (start 205.208972 76.441884) (end 205.922761 77.155673) (width 0.16) (layer "In9.Cu") (net 297))
  (segment (start 205.569207 77.579937) (end 204.820063 76.830793) (width 0.16) (layer "In9.Cu") (net 297))
  (segment (start 204.431154 77.219702) (end 205.180298 77.968846) (width 0.16) (layer "In9.Cu") (net 297))
  (segment (start 204.820062 76.441884) (end 204.820064 76.441883) (width 0.16) (layer "In9.Cu") (net 297))
  (segment (start 204.791389 78.357754) (end 204.791389 78.357755) (width 0.16) (layer "In9.Cu") (net 297))
  (segment (start 203.653336 77.99752) (end 204.40248 78.746664) (width 0.16) (layer "In9.Cu") (net 297))
  (segment (start 203.235753 79.91339) (end 203.235753 79.913391) (width 0.16) (layer "In9.Cu") (net 297))
  (segment (start 202.486608 78.775338) (end 202.48661 78.775337) (width 0.16) (layer "In9.Cu") (net 297))
  (segment (start 204.791389 78.357755) (end 204.042245 77.608611) (width 0.16) (layer "In9.Cu") (net 297))
  (segment (start 207.619574 74.780426) (end 215.9 66.5) (width 0.16) (layer "In9.Cu") (net 297))
  (segment (start 202.097702 79.553155) (end 202.0977 79.553156) (width 0.16) (layer "In9.Cu") (net 297))
  (segment (start 203.264426 77.99752) (end 203.264428 77.997519) (width 0.16) (layer "In9.Cu") (net 297))
  (segment (start 206.311669 77.155673) (end 206.31167 77.155673) (width 0.16) (layer "In9.Cu") (net 297))
  (segment (start 202.457935 80.691208) (end 202.457935 80.691209) (width 0.16) (layer "In9.Cu") (net 297))
  (segment (start 215.9 66.5) (end 235.3 66.5) (width 0.16) (layer "In9.Cu") (net 297))
  (segment (start 235.3 66.5) (end 238.136328 63.663672) (width 0.16) (layer "In9.Cu") (net 297))
  (segment (start 205.208974 76.441883) (end 205.208972 76.441884) (width 0.16) (layer "In9.Cu") (net 297))
  (segment (start 205.986792 75.664065) (end 205.98679 75.664066) (width 0.16) (layer "In9.Cu") (net 297))
  (segment (start 193.790008 81.060008) (end 192.655836 81.060008) (width 0.1) (layer "In9.Cu") (net 297))
  (segment (start 203.653338 77.997519) (end 203.653336 77.99752) (width 0.16) (layer "In9.Cu") (net 297))
  (segment (start 198.2 81.02) (end 201.38 81.02) (width 0.16) (layer "In9.Cu") (net 297))
  (segment (start 196.05 81.02) (end 198.2 81.02) (width 0.1) (layer "In9.Cu") (net 297))
  (segment (start 202.875518 78.775338) (end 203.624662 79.524482) (width 0.16) (layer "In9.Cu") (net 297))
  (segment (start 204.431156 77.219701) (end 204.431154 77.219702) (width 0.16) (layer "In9.Cu") (net 297))
  (segment (start 205.59788 75.664066) (end 205.597882 75.664065) (width 0.16) (layer "In9.Cu") (net 297))
  (segment (start 194.22 81.49) (end 193.790008 81.060008) (width 0.1) (layer "In9.Cu") (net 297))
  (segment (start 202.0977 79.553156) (end 202.846844 80.3023) (width 0.16) (layer "In9.Cu") (net 297))
  (segment (start 201.888908 80.9) (end 202.069026 81.080118) (width 0.16) (layer "In9.Cu") (net 297))
  (segment (start 206.555819 75.844184) (end 207.619574 74.780426) (width 0.16) (layer "In9.Cu") (net 297))
  (segment (start 201.70879 79.553156) (end 201.708792 79.553155) (width 0.16) (layer "In9.Cu") (net 297))
  (segment (start 202.457935 80.691209) (end 201.708791 79.942065) (width 0.16) (layer "In9.Cu") (net 297))
  (segment (start 206.31167 76.766764) (end 205.597881 76.052975) (width 0.16) (layer "In9.Cu") (net 297))
  (segment (start 206.31167 76.766763) (end 206.31167 76.766764) (width 0.16) (layer "In9.Cu") (net 297))
  (segment (start 203.235753 80.302301) (end 203.235753 80.3023) (width 0.16) (layer "In9.Cu") (net 297))
  (segment (start 201.38 81.02) (end 201.5 80.9) (width 0.16) (layer "In9.Cu") (net 297))
  (segment (start 196.05 81.02) (end 195.58 81.49) (width 0.1) (layer "In9.Cu") (net 297))
  (segment (start 203.235753 79.913391) (end 202.486609 79.164247) (width 0.16) (layer "In9.Cu") (net 297))
  (segment (start 205.98679 75.664066) (end 206.166909 75.844185) (width 0.16) (layer "In9.Cu") (net 297))
  (segment (start 238.136328 63.663672) (end 238.136328 60.960008) (width 0.16) (layer "In9.Cu") (net 297))
  (segment (start 204.013571 79.135573) (end 203.264427 78.386429) (width 0.16) (layer "In9.Cu") (net 297))
  (segment (start 206.555817 75.844185) (end 206.555819 75.844184) (width 0.16) (layer "In9.Cu") (net 297))
  (segment (start 205.569207 77.579936) (end 205.569207 77.579937) (width 0.16) (layer "In9.Cu") (net 297))
  (segment (start 202.87552 78.775337) (end 202.875518 78.775338) (width 0.16) (layer "In9.Cu") (net 297))
  (segment (start 202.457934 81.080118) (end 202.457935 81.080118) (width 0.16) (layer "In9.Cu") (net 297))
  (segment (start 205.569207 77.968847) (end 205.569207 77.968846) (width 0.16) (layer "In9.Cu") (net 297))
  (segment (start 204.042244 77.219702) (end 204.042246 77.219701) (width 0.16) (layer "In9.Cu") (net 297))
  (segment (start 195.58 81.49) (end 194.22 81.49) (width 0.1) (layer "In9.Cu") (net 297))
  (segment (start 204.013571 79.524483) (end 204.013571 79.524482) (width 0.16) (layer "In9.Cu") (net 297))
  (arc (start 201.708791 79.942065) (mid 201.628245 79.747611) (end 201.70879 79.553156) (width 0.16) (layer "In9.Cu") (net 297))
  (arc (start 205.180298 77.968846) (mid 205.374752 78.049392) (end 205.569207 77.968847) (width 0.16) (layer "In9.Cu") (net 297))
  (arc (start 202.069026 81.080118) (mid 202.26348 81.160663) (end 202.457934 81.080118) (width 0.16) (layer "In9.Cu") (net 297))
  (arc (start 202.486609 79.164247) (mid 202.406063 78.969793) (end 202.486608 78.775338) (width 0.16) (layer "In9.Cu") (net 297))
  (arc (start 205.922761 77.155673) (mid 206.117215 77.236218) (end 206.311669 77.155673) (width 0.16) (layer "In9.Cu") (net 297))
  (arc (start 204.042246 77.219701) (mid 204.2367 77.139156) (end 204.431156 77.219701) (width 0.16) (layer "In9.Cu") (net 297))
  (arc (start 206.31167 77.155673) (mid 206.392216 76.961218) (end 206.31167 76.766763) (width 0.16) (layer "In9.Cu") (net 297))
  (arc (start 205.597881 76.052975) (mid 205.517335 75.858521) (end 205.59788 75.664066) (width 0.16) (layer "In9.Cu") (net 297))
  (arc (start 201.708792 79.553155) (mid 201.903246 79.47261) (end 202.097702 79.553155) (width 0.16) (layer "In9.Cu") (net 297))
  (arc (start 204.791389 78.746664) (mid 204.871935 78.552209) (end 204.791389 78.357754) (width 0.16) (layer "In9.Cu") (net 297))
  (arc (start 204.820064 76.441883) (mid 205.014518 76.361338) (end 205.208974 76.441883) (width 0.16) (layer "In9.Cu") (net 297))
  (arc (start 205.569207 77.968846) (mid 205.649753 77.774391) (end 205.569207 77.579936) (width 0.16) (layer "In9.Cu") (net 297))
  (arc (start 206.166909 75.844185) (mid 206.361364 75.924729) (end 206.555817 75.844185) (width 0.16) (layer "In9.Cu") (net 297))
  (arc (start 202.846844 80.3023) (mid 203.041298 80.382846) (end 203.235753 80.302301) (width 0.16) (layer "In9.Cu") (net 297))
  (arc (start 201.5 80.9) (mid 201.694454 80.819455) (end 201.888908 80.9) (width 0.16) (layer "In9.Cu") (net 297))
  (arc (start 202.48661 78.775337) (mid 202.681064 78.694792) (end 202.87552 78.775337) (width 0.16) (layer "In9.Cu") (net 297))
  (arc (start 203.264428 77.997519) (mid 203.458882 77.916974) (end 203.653338 77.997519) (width 0.16) (layer "In9.Cu") (net 297))
  (arc (start 205.597882 75.664065) (mid 205.792336 75.58352) (end 205.986792 75.664065) (width 0.16) (layer "In9.Cu") (net 297))
  (arc (start 202.457935 81.080118) (mid 202.538481 80.885663) (end 202.457935 80.691208) (width 0.16) (layer "In9.Cu") (net 297))
  (arc (start 204.820063 76.830793) (mid 204.739517 76.636339) (end 204.820062 76.441884) (width 0.16) (layer "In9.Cu") (net 297))
  (arc (start 203.235753 80.3023) (mid 203.316299 80.107845) (end 203.235753 79.91339) (width 0.16) (layer "In9.Cu") (net 297))
  (arc (start 204.042245 77.608611) (mid 203.961699 77.414157) (end 204.042244 77.219702) (width 0.16) (layer "In9.Cu") (net 297))
  (arc (start 204.013571 79.524482) (mid 204.094117 79.330027) (end 204.013571 79.135572) (width 0.16) (layer "In9.Cu") (net 297))
  (arc (start 203.264427 78.386429) (mid 203.183881 78.191975) (end 203.264426 77.99752) (width 0.16) (layer "In9.Cu") (net 297))
  (arc (start 203.624662 79.524482) (mid 203.819116 79.605028) (end 204.013571 79.524483) (width 0.16) (layer "In9.Cu") (net 297))
  (arc (start 204.40248 78.746664) (mid 204.596934 78.82721) (end 204.791389 78.746665) (width 0.16) (layer "In9.Cu") (net 297))
  (segment (start 191.636328 86.060008) (end 191.655836 86.060008) (width 0.127) (layer "F.Cu") (net 298))
  (segment (start 191.136328 86.560008) (end 191.636328 86.060008) (width 0.127) (layer "F.Cu") (net 298))
  (segment (start 244.086328 59.660008) (end 244.086328 60.960008) (width 0.2) (layer "F.Cu") (net 298))
  (via (at 191.655836 86.060008) (size 0.5) (drill 0.2) (layers "F.Cu" "B.Cu") (net 298))
  (via (at 244.086328 60.960008) (size 0.5) (drill 0.2) (layers "F.Cu" "B.Cu") (net 298))
  (segment (start 206.27 86.705864) (end 206.27 87.394136) (width 0.16) (layer "In9.Cu") (net 298))
  (segment (start 195.9 86) (end 198.1 86) (width 0.1) (layer "In9.Cu") (net 298))
  (segment (start 206.87 87.394136) (end 206.87 86.705864) (width 0.16) (layer "In9.Cu") (net 298))
  (segment (start 192.105828 86.51) (end 195.39 86.51) (width 0.1) (layer "In9.Cu") (net 298))
  (segment (start 202.3 86) (end 203.35 87.05) (width 0.16) (layer "In9.Cu") (net 298))
  (segment (start 195.39 86.51) (end 195.9 86) (width 0.1) (layer "In9.Cu") (net 298))
  (segment (start 205.67 87.394136) (end 205.67 86.705864) (width 0.16) (layer "In9.Cu") (net 298))
  (segment (start 191.655836 86.060008) (end 192.105828 86.51) (width 0.1) (layer "In9.Cu") (net 298))
  (segment (start 207.47 86.705864) (end 207.47 87.394136) (width 0.16) (layer "In9.Cu") (net 298))
  (segment (start 237.7 76) (end 244.086328 69.613672) (width 0.16) (layer "In9.Cu") (net 298))
  (segment (start 204.47 87.394136) (end 204.47 87.35) (width 0.16) (layer "In9.Cu") (net 298))
  (segment (start 210.400893 87.05) (end 210.45 87.05) (width 0.16) (layer "In9.Cu") (net 298))
  (segment (start 210.45 87.05) (end 221.5 76) (width 0.16) (layer "In9.Cu") (net 298))
  (segment (start 208.37 87.05) (end 210.400893 87.05) (width 0.16) (layer "In9.Cu") (net 298))
  (segment (start 205.07 86.705864) (end 205.07 87.394136) (width 0.16) (layer "In9.Cu") (net 298))
  (segment (start 203.35 87.05) (end 203.57 87.05) (width 0.16) (layer "In9.Cu") (net 298))
  (segment locked (start 221.5 76) (end 237.7 76) (width 0.16) (layer "In9.Cu") (net 298))
  (segment (start 208.07 87.394136) (end 208.07 87.35) (width 0.16) (layer "In9.Cu") (net 298))
  (segment (start 204.47 87.35) (end 204.47 86.705864) (width 0.16) (layer "In9.Cu") (net 298))
  (segment (start 244.086328 69.613672) (end 244.086328 60.960008) (width 0.16) (layer "In9.Cu") (net 298))
  (segment (start 203.87 87.35) (end 203.87 87.394136) (width 0.16) (layer "In9.Cu") (net 298))
  (segment (start 198.1 86) (end 202.3 86) (width 0.16) (layer "In9.Cu") (net 298))
  (arc (start 204.17 87.694136) (mid 204.382132 87.606268) (end 204.47 87.394136) (width 0.16) (layer "In9.Cu") (net 298))
  (arc (start 204.77 86.405864) (mid 204.982132 86.493732) (end 205.07 86.705864) (width 0.16) (layer "In9.Cu") (net 298))
  (arc (start 203.87 87.394136) (mid 203.957868 87.606268) (end 204.17 87.694136) (width 0.16) (layer "In9.Cu") (net 298))
  (arc (start 204.47 86.705864) (mid 204.557868 86.493732) (end 204.77 86.405864) (width 0.16) (layer "In9.Cu") (net 298))
  (arc (start 208.07 87.35) (mid 208.157868 87.137868) (end 208.37 87.05) (width 0.16) (layer "In9.Cu") (net 298))
  (arc (start 205.07 87.394136) (mid 205.157868 87.606268) (end 205.37 87.694136) (width 0.16) (layer "In9.Cu") (net 298))
  (arc (start 207.77 87.694136) (mid 207.982132 87.606268) (end 208.07 87.394136) (width 0.16) (layer "In9.Cu") (net 298))
  (arc (start 205.97 86.405864) (mid 206.182132 86.493732) (end 206.27 86.705864) (width 0.16) (layer "In9.Cu") (net 298))
  (arc (start 205.67 86.705864) (mid 205.757868 86.493732) (end 205.97 86.405864) (width 0.16) (layer "In9.Cu") (net 298))
  (arc (start 206.57 87.694136) (mid 206.782132 87.606268) (end 206.87 87.394136) (width 0.16) (layer "In9.Cu") (net 298))
  (arc (start 207.47 87.394136) (mid 207.557868 87.606268) (end 207.77 87.694136) (width 0.16) (layer "In9.Cu") (net 298))
  (arc (start 206.87 86.705864) (mid 206.957868 86.493732) (end 207.17 86.405864) (width 0.16) (layer "In9.Cu") (net 298))
  (arc (start 203.57 87.05) (mid 203.782132 87.137868) (end 203.87 87.35) (width 0.16) (layer "In9.Cu") (net 298))
  (arc (start 207.17 86.405864) (mid 207.382132 86.493732) (end 207.47 86.705864) (width 0.16) (layer "In9.Cu") (net 298))
  (arc (start 206.27 87.394136) (mid 206.357868 87.606268) (end 206.57 87.694136) (width 0.16) (layer "In9.Cu") (net 298))
  (arc (start 205.37 87.694136) (mid 205.582132 87.606268) (end 205.67 87.394136) (width 0.16) (layer "In9.Cu") (net 298))
  (segment (start 116.208485 98.53) (end 118.204 98.53) (width 0.25) (layer "F.Cu") (net 299))
  (segment (start 116.411328 98.637157) (end 115.286328 98.637157) (width 0.5) (layer "F.Cu") (net 299))
  (segment (start 109.915528 92.580008) (end 110.63552 93.3) (width 0.2) (layer "F.Cu") (net 299))
  (segment (start 110.63552 93.3) (end 112.45 93.3) (width 0.2) (layer "F.Cu") (net 299))
  (segment (start 141.896328 90.635008) (end 142.586328 90.635008) (width 0.2) (layer "F.Cu") (net 300))
  (segment (start 142.1 83.7) (end 142.823 83.7) (width 0.127) (layer "F.Cu") (net 300))
  (via (at 142.586328 90.635008) (size 0.5) (drill 0.2) (layers "F.Cu" "B.Cu") (net 300))
  (via (at 142.7 89) (size 0.5) (drill 0.2) (layers "F.Cu" "B.Cu") (net 300))
  (segment (start 142.586328 90.635008) (end 142.586328 89.113672) (width 0.2) (layer "B.Cu") (net 300))
  (segment (start 142.586328 89.113672) (end 142.7 89) (width 0.2) (layer "B.Cu") (net 300))
  (segment (start 119.675 85.275) (end 119.65 85.3) (width 0.127) (layer "F.Cu") (net 301))
  (segment (start 117.353495 100.03) (end 117.286328 100.097167) (width 0.15) (layer "F.Cu") (net 301))
  (segment (start 121.916328 81.529208) (end 123.136328 80.309208) (width 0.2) (layer "F.Cu") (net 301))
  (segment (start 119.386328 85.360008) (end 121.014992 85.360008) (width 0.2) (layer "F.Cu") (net 301))
  (segment (start 118.204 100.03) (end 117.353495 100.03) (width 0.15) (layer "F.Cu") (net 301))
  (segment (start 121.916328 84.458672) (end 121.916328 81.529208) (width 0.2) (layer "F.Cu") (net 301))
  (segment (start 121.014992 85.360008) (end 121.916328 84.458672) (width 0.2) (layer "F.Cu") (net 301))
  (via (at 117.286328 97.872157) (size 0.5) (drill 0.2) (layers "F.Cu" "B.Cu") (net 301))
  (via (at 117.286328 100.097167) (size 0.5) (drill 0.2) (layers "F.Cu" "B.Cu") (net 301))
  (segment (start 117.286328 97.872157) (end 117.911328 98.497157) (width 0.15) (layer "B.Cu") (net 301))
  (segment (start 117.286328 100.097167) (end 117.911328 99.472167) (width 0.15) (layer "B.Cu") (net 301))
  (segment (start 117.911328 98.497157) (end 117.911328 99.472167) (width 0.15) (layer "B.Cu") (net 301))
  (segment (start 130.7 84.477) (end 130.7 85.2) (width 0.127) (layer "F.Cu") (net 302))
  (segment (start 129.55 85.2) (end 130.7 85.2) (width 0.2) (layer "F.Cu") (net 302))
  (segment (start 129.935528 79.560008) (end 129.136328 80.359208) (width 0.2) (layer "F.Cu") (net 302))
  (segment (start 132.051328 95.095008) (end 131.546328 94.590008) (width 0.2) (layer "F.Cu") (net 302))
  (segment (start 129.136328 80.359208) (end 129.136328 84.786328) (width 0.2) (layer "F.Cu") (net 302))
  (segment (start 129.136328 84.786328) (end 129.55 85.2) (width 0.2) (layer "F.Cu") (net 302))
  (via (at 130.586328 86.461328) (size 0.5) (drill 0.2) (layers "F.Cu" "B.Cu") (net 302))
  (via (at 131.546328 94.590008) (size 0.5) (drill 0.2) (layers "F.Cu" "B.Cu") (net 302))
  (segment (start 131.546328 90.720008) (end 130.586328 89.760008) (width 0.2) (layer "B.Cu") (net 302))
  (segment (start 130.586328 89.760008) (end 130.586328 86.461328) (width 0.2) (layer "B.Cu") (net 302))
  (segment (start 131.546328 94.590008) (end 131.546328 90.720008) (width 0.2) (layer "B.Cu") (net 302))
  (segment (start 121.004 99.53) (end 121.756463 99.53) (width 0.25) (layer "F.Cu") (net 303))
  (segment (start 122 99.286463) (end 121.756463 99.53) (width 0.15) (layer "F.Cu") (net 303))
  (segment (start 123.2 89.477) (end 123.2 90.2) (width 0.15) (layer "F.Cu") (net 303))
  (segment (start 122 99.1) (end 122 99.286463) (width 0.15) (layer "F.Cu") (net 303))
  (via (at 122 99.1) (size 0.5) (drill 0.2) (layers "F.Cu" "B.Cu") (net 303))
  (via (at 125.661328 97.372157) (size 0.5) (drill 0.2) (layers "F.Cu" "B.Cu") (net 303))
  (segment (start 124.925 99.1) (end 125.661328 98.363672) (width 0.2) (layer "B.Cu") (net 303))
  (segment (start 122 99.1) (end 124.925 99.1) (width 0.2) (layer "B.Cu") (net 303))
  (segment (start 125.661328 98.363672) (end 125.661328 97.372157) (width 0.2) (layer "B.Cu") (net 303))
  (segment (start 135 101.0742) (end 134.372136 101.0742) (width 0.2) (layer "F.Cu") (net 304))
  (segment (start 125.336328 106.310008) (end 125.066328 106.580008) (width 0.2) (layer "F.Cu") (net 304))
  (segment (start 125.336328 105.885008) (end 125.336328 106.310008) (width 0.2) (layer "F.Cu") (net 304))
  (segment (start 113.327 108.95) (end 114.05 108.95) (width 0.127) (layer "F.Cu") (net 304))
  (segment (start 134.372136 101.0742) (end 133.886328 101.560008) (width 0.2) (layer "F.Cu") (net 304))
  (via (at 115.275 108.55) (size 0.5) (drill 0.2) (layers "F.Cu" "B.Cu") (net 304))
  (via (at 125.066328 106.580008) (size 0.5) (drill 0.2) (layers "F.Cu" "B.Cu") (net 304))
  (via (at 133.886328 101.560008) (size 0.5) (drill 0.2) (layers "F.Cu" "B.Cu") (net 304))
  (via (at 115.266328 109.720008) (size 0.5) (drill 0.2) (layers "F.Cu" "B.Cu") (net 304))
  (segment (start 120.896328 106.580008) (end 125.066328 106.580008) (width 0.2) (layer "B.Cu") (net 304))
  (segment (start 117.496328 108.520008) (end 115.286328 108.520008) (width 0.2) (layer "B.Cu") (net 304))
  (segment (start 117.756328 109.720008) (end 120.896328 106.580008) (width 0.2) (layer "B.Cu") (net 304))
  (segment (start 123.73 105.3) (end 120.716336 105.3) (width 0.2) (layer "B.Cu") (net 304))
  (segment (start 115.266328 109.720008) (end 117.756328 109.720008) (width 0.2) (layer "B.Cu") (net 304))
  (segment (start 127 102.03) (end 123.73 105.3) (width 0.2) (layer "B.Cu") (net 304))
  (segment (start 133.416336 102.03) (end 127 102.03) (width 0.2) (layer "B.Cu") (net 304))
  (segment (start 115.286328 108.520008) (end 115.286328 108.538672) (width 0.2) (layer "B.Cu") (net 304))
  (segment (start 120.716336 105.3) (end 117.496328 108.520008) (width 0.2) (layer "B.Cu") (net 304))
  (segment (start 115.286328 108.538672) (end 115.275 108.55) (width 0.2) (layer "B.Cu") (net 304))
  (segment (start 133.886328 101.560008) (end 133.416336 102.03) (width 0.2) (layer "B.Cu") (net 304))
  (segment (start 118.364 100.69) (end 118.204 100.53) (width 0.2) (layer "F.Cu") (net 305))
  (segment (start 118.204 100.53) (end 117.704 100.53) (width 0.2) (layer "F.Cu") (net 305))
  (segment (start 117.611843 100.622157) (end 116.146328 100.622157) (width 0.2) (layer "F.Cu") (net 305))
  (segment (start 117.704 100.53) (end 117.611843 100.622157) (width 0.2) (layer "F.Cu") (net 305))
  (segment (start 161.066328 94.060008) (end 161.329179 93.797157) (width 0.15) (layer "F.Cu") (net 306))
  (segment (start 161.329179 93.797157) (end 161.863477 93.797157) (width 0.15) (layer "F.Cu") (net 306))
  (segment (start 151.571328 91.874306) (end 151.571328 92.874306) (width 0.2) (layer "F.Cu") (net 306))
  (segment (start 153.440627 94.274307) (end 152.681328 93.515008) (width 0.2) (layer "F.Cu") (net 306))
  (segment (start 152.040626 92.874306) (end 151.571328 92.874306) (width 0.2) (layer "F.Cu") (net 306))
  (segment (start 154.986329 94.274307) (end 153.440627 94.274307) (width 0.2) (layer "F.Cu") (net 306))
  (segment (start 161.863477 93.797157) (end 164.524179 93.797157) (width 0.15) (layer "F.Cu") (net 306))
  (segment (start 158.686328 92.620008) (end 158.686328 91.720008) (width 0.15) (layer "F.Cu") (net 306))
  (segment (start 152.681328 93.515008) (end 152.040626 92.874306) (width 0.2) (layer "F.Cu") (net 306))
  (segment (start 161.066328 94.530008) (end 161.066328 94.060008) (width 0.15) (layer "F.Cu") (net 306))
  (segment (start 154.967599 120.680073) (end 154.010656 121.637016) (width 0.2) (layer "F.Cu") (net 306))
  (segment (start 155.239415 120.680073) (end 154.967599 120.680073) (width 0.2) (layer "F.Cu") (net 306))
  (segment (start 153.699328 123.102008) (end 149.599328 123.102008) (width 0.2) (layer "F.Cu") (net 306))
  (segment (start 154.010656 122.79068) (end 153.699328 123.102008) (width 0.2) (layer "F.Cu") (net 306))
  (segment (start 154.010656 121.637016) (end 154.010656 122.79068) (width 0.2) (layer "F.Cu") (net 306))
  (segment (start 149.595328 123.103008) (end 148.495328 124.203008) (width 0.2) (layer "F.Cu") (net 306))
  (segment (start 148.495328 124.203008) (end 146.045328 124.203008) (width 0.2) (layer "F.Cu") (net 306))
  (segment (start 161.863477 98.297157) (end 162.447157 98.297157) (width 0.2) (layer "F.Cu") (net 306))
  (segment (start 194.62632 100.05) (end 194.136328 99.560008) (width 0.2) (layer "F.Cu") (net 306))
  (segment (start 161.863477 96.297157) (end 161.323465 96.297157) (width 0.15) (layer "F.Cu") (net 306))
  (segment (start 195.136328 96.560008) (end 195.636328 97.060008) (width 0.2) (layer "F.Cu") (net 306))
  (segment (start 163.397022 98.6) (end 163.486328 98.689306) (width 0.2) (layer "F.Cu") (net 306))
  (segment (start 192.136328 91.560008) (end 192.636328 92.060008) (width 0.2) (layer "F.Cu") (net 306))
  (segment (start 195.136328 92.560008) (end 195.636328 93.060008) (width 0.2) (layer "F.Cu") (net 306))
  (segment (start 154.1 121.7) (end 153.377 121.7) (width 0.12) (layer "F.Cu") (net 306))
  (segment (start 194.136328 101.560008) (end 194.636328 102.060008) (width 0.2) (layer "F.Cu") (net 306))
  (segment (start 146.786328 94.610008) (end 146.786328 93.910008) (width 0.15) (layer "F.Cu") (net 306))
  (segment (start 160.686328 91.875708) (end 160.694181 91.867855) (width 0.15) (layer "F.Cu") (net 306))
  (segment (start 195.136328 100.560008) (end 195.636328 101.060008) (width 0.2) (layer "F.Cu") (net 306))
  (segment (start 162.447157 98.297157) (end 162.75 98.6) (width 0.2) (layer "F.Cu") (net 306))
  (segment (start 194.136328 91.560008) (end 194.636328 92.060008) (width 0.2) (layer "F.Cu") (net 306))
  (segment (start 160.686328 92.620008) (end 160.686328 91.875708) (width 0.15) (layer "F.Cu") (net 306))
  (segment (start 194.136328 95.560008) (end 194.636328 96.060008) (width 0.2) (layer "F.Cu") (net 306))
  (segment (start 163.486328 98.689306) (end 164.586328 98.689306) (width 0.2) (layer "F.Cu") (net 306))
  (segment (start 194.65 100.05) (end 194.62632 100.05) (width 0.1) (layer "F.Cu") (net 306))
  (segment (start 161.323465 96.297157) (end 161.066328 96.04002) (width 0.15) (layer "F.Cu") (net 306))
  (segment (start 162.75 98.6) (end 163.397022 98.6) (width 0.2) (layer "F.Cu") (net 306))
  (via (at 158.686328 91.720008) (size 0.5) (drill 0.2) (layers "F.Cu" "B.Cu") (net 306))
  (via (at 154.740087 119.178065) (size 0.5) (drill 0.2) (layers "F.Cu" "B.Cu") (net 306))
  (via (at 154.240087 119.678065) (size 0.5) (drill 0.2) (layers "F.Cu" "B.Cu") (net 306))
  (via (at 155.240087 119.678065) (size 0.5) (drill 0.2) (layers "F.Cu" "B.Cu") (net 306))
  (via (at 155.240087 120.678065) (size 0.5) (drill 0.2) (layers "F.Cu" "B.Cu") (net 306))
  (via (at 155.740087 119.178065) (size 0.5) (drill 0.2) (layers "F.Cu" "B.Cu") (net 306))
  (via (at 154.740087 120.178065) (size 0.5) (drill 0.2) (layers "F.Cu" "B.Cu") (net 306))
  (via (at 155.740087 120.178065) (size 0.5) (drill 0.2) (layers "F.Cu" "B.Cu") (net 306))
  (via (at 153.739415 120.180073) (size 0.5) (drill 0.2) (layers "F.Cu" "B.Cu") (net 306))
  (via (at 160.694181 91.867855) (size 0.5) (drill 0.2) (layers "F.Cu" "B.Cu") (net 306))
  (via (at 162.75 98.6) (size 0.5) (drill 0.2) (layers "F.Cu" "B.Cu") (net 306))
  (via (at 194.636328 92.060008) (size 0.5) (drill 0.2) (layers "F.Cu" "B.Cu") (net 306))
  (via (at 160.418567 98.044798) (size 0.5) (drill 0.2) (layers "F.Cu" "B.Cu") (net 306))
  (via (at 195.6 105.2) (size 0.5) (drill 0.2) (layers "F.Cu" "B.Cu") (net 306))
  (via (at 161.066328 96.04002) (size 0.5) (drill 0.2) (layers "F.Cu" "B.Cu") (net 306))
  (via (at 194.636328 102.060008) (size 0.5) (drill 0.2) (layers "F.Cu" "B.Cu") (net 306))
  (via (at 194.636328 96.060008) (size 0.5) (drill 0.2) (layers "F.Cu" "B.Cu") (net 306))
  (via (at 160.4 98.575) (size 0.5) (drill 0.2) (layers "F.Cu" "B.Cu") (net 306))
  (via (at 197.4 105.2) (size 0.5) (drill 0.2) (layers "F.Cu" "B.Cu") (net 306))
  (via (at 195.636328 97.060008) (size 0.5) (drill 0.2) (layers "F.Cu" "B.Cu") (net 306))
  (via (at 194.65 100.05) (size 0.5) (drill 0.2) (layers "F.Cu" "B.Cu") (net 306))
  (via (at 152.681328 93.515008) (size 0.5) (drill 0.2) (layers "F.Cu" "B.Cu") (net 306))
  (via (at 195.636328 93.060008) (size 0.5) (drill 0.2) (layers "F.Cu" "B.Cu") (net 306))
  (via (at 161.066328 94.530008) (size 0.5) (drill 0.2) (layers "F.Cu" "B.Cu") (net 306))
  (via (at 198.5 104.9) (size 0.5) (drill 0.2) (layers "F.Cu" "B.Cu") (net 306))
  (via (at 198 105.2) (size 0.5) (drill 0.2) (layers "F.Cu" "B.Cu") (net 306))
  (via (at 195.636328 101.060008) (size 0.5) (drill 0.2) (layers "F.Cu" "B.Cu") (net 306))
  (via (at 146.786328 93.910008) (size 0.5) (drill 0.2) (layers "F.Cu" "B.Cu") (net 306))
  (via (at 196.2 105.2) (size 0.5) (drill 0.2) (layers "F.Cu" "B.Cu") (net 306))
  (via (at 196.8 105.2) (size 0.5) (drill 0.2) (layers "F.Cu" "B.Cu") (net 306))
  (via (at 192.636328 92.060008) (size 0.5) (drill 0.2) (layers "F.Cu" "B.Cu") (net 306))
  (via (at 195 105.2) (size 0.5) (drill 0.2) (layers "F.Cu" "B.Cu") (net 306))
  (segment (start 159.586328 92.535008) (end 160.686328 92.535008) (width 0.2) (layer "B.Cu") (net 306))
  (segment (start 158.686328 91.720008) (end 158.686328 92.335008) (width 0.2) (layer "B.Cu") (net 306))
  (segment (start 158.686328 92.335008) (end 158.486328 92.535008) (width 0.2) (layer "B.Cu") (net 306))
  (segment (start 157.486328 92.535008) (end 158.486328 92.535008) (width 0.2) (layer "B.Cu") (net 306))
  (segment (start 160.418567 98.044798) (end 160.4 98.063365) (width 0.4) (layer "B.Cu") (net 306))
  (segment (start 192.636328 92.101328) (end 193.21 92.675) (width 0.2) (layer "B.Cu") (net 306))
  (segment (start 160.418567 98.044798) (end 160.418567 98.181433) (width 0.4) (layer "B.Cu") (net 306))
  (segment (start 192.636328 92.060008) (end 192.636328 92.101328) (width 0.1) (layer "B.Cu") (net 306))
  (segment (start 194.45 95.6) (end 194.636328 95.786328) (width 0.2) (layer "B.Cu") (net 306))
  (segment (start 154.721935 120.678065) (end 154.721935 120.196217) (width 0.4) (layer "B.Cu") (net 306))
  (segment (start 194.525 101.6) (end 194.636328 101.711328) (width 0.2) (layer "B.Cu") (net 306))
  (segment (start 154.721935 120.196217) (end 154.740087 120.178065) (width 0.4) (layer "B.Cu") (net 306))
  (segment (start 208.288 97.891) (end 196.46732 97.891) (width 0.2) (layer "B.Cu") (net 306))
  (segment (start 195.88 96.55) (end 195.875 96.55) (width 0.2) (layer "B.Cu") (net 306))
  (segment (start 160.686328 92.535008) (end 160.686328 91.875708) (width 0.2) (layer "B.Cu") (net 306))
  (segment (start 194.52 99.5) (end 194.55 99.5) (width 0.2) (layer "B.Cu") (net 306))
  (segment (start 160.4 98.063365) (end 160.4 98.575) (width 0.4) (layer "B.Cu") (net 306))
  (segment (start 194.52 101.645) (end 194.52 101.6) (width 0.2) (layer "B.Cu") (net 306))
  (segment (start 153.85 121.55) (end 154.721935 120.678065) (width 0.4) (layer "B.Cu") (net 306))
  (segment (start 195.636328 101.563672) (end 195.636328 101.060008) (width 0.2) (layer "B.Cu") (net 306))
  (segment (start 153.85 123.55) (end 153.85 121.55) (width 0.4) (layer "B.Cu") (net 306))
  (segment (start 195.636328 96.788672) (end 195.636328 97.060008) (width 0.2) (layer "B.Cu") (net 306))
  (segment (start 194.55 99.5) (end 194.65 99.6) (width 0.2) (layer "B.Cu") (net 306))
  (segment (start 160.418567 98.181433) (end 160.325 98.275) (width 0.4) (layer "B.Cu") (net 306))
  (segment (start 194.52 101.6) (end 194.525 101.6) (width 0.2) (layer "B.Cu") (net 306))
  (segment (start 194.67 91.5) (end 194.67 92.026336) (width 0.2) (layer "B.Cu") (net 306))
  (segment (start 160.686328 91.875708) (end 160.694181 91.867855) (width 0.2) (layer "B.Cu") (net 306))
  (segment (start 195.875 96.55) (end 195.636328 96.788672) (width 0.2) (layer "B.Cu") (net 306))
  (segment (start 194.61 102.775) (end 194.61 102.086336) (width 0.2) (layer "B.Cu") (net 306))
  (segment (start 193.21 92.675) (end 194.021336 92.675) (width 0.2) (layer "B.Cu") (net 306))
  (segment (start 194.636328 101.711328) (end 194.636328 102.060008) (width 0.2) (layer "B.Cu") (net 306))
  (segment (start 195.139992 102.060008) (end 195.636328 101.563672) (width 0.2) (layer "B.Cu") (net 306))
  (segment (start 194.61 102.086336) (end 194.636328 102.060008) (width 0.2) (layer "B.Cu") (net 306))
  (segment (start 154.721935 120.678065) (end 155.240087 120.678065) (width 0.4) (layer "B.Cu") (net 306))
  (segment (start 216.087 90.092) (end 208.288 97.891) (width 0.2) (layer "B.Cu") (net 306))
  (segment (start 195.636328 100.738672) (end 195.636328 101.060008) (width 0.2) (layer "B.Cu") (net 306))
  (segment (start 194.42 95.6) (end 194.45 95.6) (width 0.2) (layer "B.Cu") (net 306))
  (segment (start 160.325 98.275) (end 159.6 98.275) (width 0.4) (layer "B.Cu") (net 306))
  (segment (start 195.78 100.595) (end 195.636328 100.738672) (width 0.2) (layer "B.Cu") (net 306))
  (segment (start 195.846336 92.85) (end 195.636328 93.060008) (width 0.2) (layer "B.Cu") (net 306))
  (segment (start 195.78 100.525) (end 195.78 100.595) (width 0.2) (layer "B.Cu") (net 306))
  (segment (start 194.021336 92.675) (end 194.636328 92.060008) (width 0.2) (layer "B.Cu") (net 306))
  (segment (start 194.67 92.026336) (end 194.636328 92.060008) (width 0.2) (layer "B.Cu") (net 306))
  (segment (start 194.65 99.6) (end 194.65 100.05) (width 0.2) (layer "B.Cu") (net 306))
  (segment (start 196.46732 97.891) (end 195.636328 97.060008) (width 0.2) (layer "B.Cu") (net 306))
  (segment (start 194.636328 102.060008) (end 195.139992 102.060008) (width 0.2) (layer "B.Cu") (net 306))
  (segment (start 194.636328 95.786328) (end 194.636328 96.060008) (width 0.2) (layer "B.Cu") (net 306))
  (segment (start 196.14 92.85) (end 195.846336 92.85) (width 0.2) (layer "B.Cu") (net 306))
  (segment (start 122.267843 103.232157) (end 122.7 102.8) (width 0.2) (layer "F.Cu") (net 307))
  (segment (start 122.7 102) (end 122.352529 101.652529) (width 0.2) (layer "F.Cu") (net 307))
  (segment (start 122.352529 101.652529) (end 121.877529 101.652529) (width 0.2) (layer "F.Cu") (net 307))
  (segment (start 122.7 102.8) (end 122.7 102) (width 0.2) (layer "F.Cu") (net 307))
  (segment (start 136.301328 94.247815) (end 136.024143 94.525) (width 0.2) (layer "F.Cu") (net 307))
  (segment (start 131.6 98.423) (end 131.6 97.7) (width 0.127) (layer "F.Cu") (net 307))
  (segment (start 121.877529 101.652529) (end 121.7 101.475) (width 0.2) (layer "F.Cu") (net 307))
  (segment (start 121.536328 103.232157) (end 122.267843 103.232157) (width 0.2) (layer "F.Cu") (net 307))
  (segment (start 124.326328 106.835008) (end 124.525008 106.835008) (width 0.2) (layer "F.Cu") (net 307))
  (segment (start 136.301328 93.286328) (end 136.301328 94.247815) (width 0.2) (layer "F.Cu") (net 307))
  (via (at 153.299328 117.402008) (size 0.5) (drill 0.2) (layers "F.Cu" "B.Cu") (free) (net 307))
  (via (at 153.899328 117.402008) (size 0.5) (drill 0.2) (layers "F.Cu" "B.Cu") (free) (net 307))
  (via (at 154.499328 117.402008) (size 0.5) (drill 0.2) (layers "F.Cu" "B.Cu") (free) (net 307))
  (via (at 155.099328 117.402008) (size 0.5) (drill 0.2) (layers "F.Cu" "B.Cu") (free) (net 307))
  (via blind (at 125.562 107.1) (size 0.5) (drill 0.2) (layers "F.Cu" "In2.Cu") (net 307))
  (via (at 134.43 96.59) (size 0.5) (drill 0.2) (layers "F.Cu" "B.Cu") (net 307))
  (via (at 153.4 125) (size 0.5) (drill 0.2) (layers "F.Cu" "B.Cu") (free) (net 307))
  (via blind (at 133.5 97.5) (size 0.5) (drill 0.2) (layers "F.Cu" "In2.Cu") (net 307))
  (via blind (at 125.1 107.4) (size 0.5) (drill 0.2) (layers "F.Cu" "In2.Cu") (net 307))
  (via (at 152.8 125) (size 0.5) (drill 0.2) (layers "F.Cu" "B.Cu") (free) (net 307))
  (via (at 121.7 101.475) (size 0.5) (drill 0.2) (layers "F.Cu" "B.Cu") (net 307))
  (via (at 138.536328 91.660008) (size 0.5) (drill 0.2) (layers "F.Cu" "B.Cu") (net 307))
  (via (at 153.1 124.5) (size 0.5) (drill 0.2) (layers "F.Cu" "B.Cu") (free) (net 307))
  (via blind (at 133.5 96.85) (size 0.5) (drill 0.2) (layers "F.Cu" "In2.Cu") (net 307))
  (via blind (at 132.95 98.5) (size 0.5) (drill 0.2) (layers "F.Cu" "In2.Cu") (net 307))
  (via (at 153.7 124.5) (size 0.5) (drill 0.2) (layers "F.Cu" "B.Cu") (free) (net 307))
  (via (at 131.375 110.625) (size 0.5) (drill 0.2) (layers "F.Cu" "B.Cu") (net 307))
  (via (at 121.9 116.8) (size 0.5) (drill 0.2) (layers "F.Cu" "B.Cu") (net 307))
  (via blind (at 125.538964 107.676964) (size 0.5) (drill 0.2) (layers "F.Cu" "In2.Cu") (net 307))
  (via (at 131.375 106.75) (size 0.5) (drill 0.2) (layers "F.Cu" "B.Cu") (net 307))
  (via blind (at 132.95 97.15) (size 0.5) (drill 0.2) (layers "F.Cu" "In2.Cu") (net 307))
  (via blind (at 132.95 97.8) (size 0.5) (drill 0.2) (layers "F.Cu" "In2.Cu") (net 307))
  (via blind (at 133.5 98.2) (size 0.5) (drill 0.2) (layers "F.Cu" "In2.Cu") (net 307))
  (via blind (at 125.1 108) (size 0.5) (drill 0.2) (layers "F.Cu" "In2.Cu") (net 307))
  (via (at 137.98583 89.9) (size 0.5) (drill 0.2) (layers "F.Cu" "B.Cu") (net 307))
  (segment (start 121.9 116.8) (end 125.2 116.8) (width 0.4) (layer "In2.Cu") (net 307))
  (segment (start 125.5 116.5) (end 125.5 108.4) (width 0.4) (layer "In2.Cu") (net 307))
  (segment (start 125.5 108.4) (end 125.1 108) (width 0.4) (layer "In2.Cu") (net 307))
  (segment (start 125.2 116.8) (end 125.5 116.5) (width 0.4) (layer "In2.Cu") (net 307))
  (segment (start 155.602683 126.302683) (end 154.1 124.8) (width 1) (layer "In7.Cu") (net 307))
  (segment (start 173.9 132.9) (end 159 132.9) (width 1) (layer "In7.Cu") (net 307))
  (segment (start 213.661485 123.8) (end 198.3 123.8) (width 1) (layer "In7.Cu") (net 307))
  (segment (start 159 132.9) (end 158.255 133.645) (width 1) (layer "In7.Cu") (net 307))
  (segment (start 179.25 127.55) (end 173.9 132.9) (width 1) (layer "In7.Cu") (net 307))
  (segment (start 156.645 133.645) (end 155.602683 132.602683) (width 1) (layer "In7.Cu") (net 307))
  (segment (start 216.914328 120.547157) (end 213.661485 123.8) (width 1) (layer "In7.Cu") (net 307))
  (segment (start 155.602683 132.602683) (end 155.602683 126.302683) (width 1) (layer "In7.Cu") (net 307))
  (segment (start 194.55 127.55) (end 179.25 127.55) (width 1) (layer "In7.Cu") (net 307))
  (segment (start 158.255 133.645) (end 156.645 133.645) (width 1) (layer "In7.Cu") (net 307))
  (segment (start 198.3 123.8) (end 194.55 127.55) (width 1) (layer "In7.Cu") (net 307))
  (segment (start 154.1 124.8) (end 153 124.8) (width 1) (layer "In7.Cu") (net 307))
  (segment (start 131.95 109.3) (end 132.575 109.3) (width 0.127) (layer "B.Cu") (net 307))
  (segment (start 139.235 82) (end 138.985 82.25) (width 0.4) (layer "B.Cu") (net 307))
  (segment (start 134.625 97.905) (end 134.625 97.37) (width 0.127) (layer "B.Cu") (net 307))
  (segment (start 133.85 105.675) (end 134.39 105.675) (width 0.127) (layer "B.Cu") (net 307))
  (segment (start 140.536328 91.885008) (end 138.761328 91.885008) (width 0.2) (layer "B.Cu") (net 307))
  (segment (start 131.425 106.7) (end 131.375 106.75) (width 0.127) (layer "B.Cu") (net 307))
  (segment (start 140 81.7) (end 139.7 82) (width 0.4) (layer "B.Cu") (net 307))
  (segment (start 142.536328 91.885008) (end 141.536328 91.885008) (width 0.2) (layer "B.Cu") (net 307))
  (segment (start 137.98583 89.9) (end 137.98583 89.48583) (width 0.4) (layer "B.Cu") (net 307))
  (segment (start 120.122 100.232) (end 119.503 100.232) (width 0.127) (layer "B.Cu") (net 307))
  (segment (start 138.985 82.315) (end 138.985 82.25) (width 0.4) (layer "B.Cu") (net 307))
  (segment (start 134.625 97.37) (end 134.625 96.785) (width 0.127) (layer "B.Cu") (net 307))
  (segment (start 119.175 99.489) (end 119.175 98) (width 0.127) (layer "B.Cu") (net 307))
  (segment (start 119.185 99.499) (end 119.175 99.489) (width 0.127) (layer "B.Cu") (net 307))
  (segment (start 119.503 100.232) (end 119.185 99.914) (width 0.127) (layer "B.Cu") (net 307))
  (segment (start 137 88.5) (end 137 84.3) (width 0.4) (layer "B.Cu") (net 307))
  (segment (start 132.225 110.625) (end 132.575 110.275) (width 0.127) (layer "B.Cu") (net 307))
  (segment (start 132.775 106.75) (end 133.85 105.675) (width 0.127) (layer "B.Cu") (net 307))
  (segment (start 121.7 101.475) (end 121.365 101.475) (width 0.127) (layer "B.Cu") (net 307))
  (segment (start 134.95 98.23) (end 134.625 97.905) (width 0.127) (layer "B.Cu") (net 307))
  (segment (start 139.7 82) (end 139.235 82) (width 0.4) (layer "B.Cu") (net 307))
  (segment (start 131.375 106.75) (end 132.775 106.75) (width 0.127) (layer "B.Cu") (net 307))
  (segment (start 140 80.9) (end 140 81.7) (width 0.4) (layer "B.Cu") (net 307))
  (segment (start 121.9 118.9) (end 121.9 116.8) (width 0.4) (layer "B.Cu") (net 307))
  (segment (start 141.536328 91.885008) (end 140.536328 91.885008) (width 0.2) (layer "B.Cu") (net 307))
  (segment (start 137 84.3) (end 138.985 82.315) (width 0.4) (layer "B.Cu") (net 307))
  (segment (start 131.425 106.035) (end 131.425 106.7) (width 0.127) (layer "B.Cu") (net 307))
  (segment (start 131.075 109.82) (end 131.43 109.82) (width 0.127) (layer "B.Cu") (net 307))
  (segment (start 138.761328 91.885008) (end 138.536328 91.660008) (width 0.2) (layer "B.Cu") (net 307))
  (segment (start 131.135 110.625) (end 130.56 111.2) (width 0.127) (layer "B.Cu") (net 307))
  (segment (start 121.365 101.475) (end 120.122 100.232) (width 0.127) (layer "B.Cu") (net 307))
  (segment (start 131.375 110.625) (end 131.135 110.625) (width 0.127) (layer "B.Cu") (net 307))
  (segment (start 134.625 96.785) (end 134.43 96.59) (width 0.127) (layer "B.Cu") (net 307))
  (segment (start 119.185 99.914) (end 119.185 99.499) (width 0.127) (layer "B.Cu") (net 307))
  (segment (start 131.43 109.82) (end 131.95 109.3) (width 0.127) (layer "B.Cu") (net 307))
  (segment (start 137.98583 89.48583) (end 137 88.5) (width 0.4) (layer "B.Cu") (net 307))
  (segment (start 132.575 110.275) (end 132.575 109.3) (width 0.127) (layer "B.Cu") (net 307))
  (segment (start 131.425 106.035) (end 131.36 106.1) (width 0.127) (layer "B.Cu") (net 307))
  (segment (start 131.375 110.625) (end 132.225 110.625) (width 0.127) (layer "B.Cu") (net 307))
  (segment (start 131.36 106.1) (end 130.125 106.1) (width 0.127) (layer "B.Cu") (net 307))
  (segment (start 134.95 98.79) (end 134.95 98.23) (width 0.127) (layer "B.Cu") (net 307))
  (segment (start 109.036328 111.721328) (end 109.036328 110.760008) (width 0.4) (layer "F.Cu") (net 308))
  (segment (start 247.7 62.45) (end 251.5 62.45) (width 0.4) (layer "F.Cu") (net 308))
  (segment (start 251.5 62.45) (end 252.586328 63.536328) (width 0.4) (layer "F.Cu") (net 308))
  (segment (start 246.636328 59.660008) (end 246.636328 61.386328) (width 0.4) (layer "F.Cu") (net 308))
  (segment (start 246.636328 61.386328) (end 247.7 62.45) (width 0.4) (layer "F.Cu") (net 308))
  (segment (start 252.586328 63.536328) (end 252.586328 63.560008) (width 0.4) (layer "F.Cu") (net 308))
  (segment (start 109.39 112.075) (end 109.036328 111.721328) (width 0.4) (layer "F.Cu") (net 308))
  (via (at 247.736328 55.860008) (size 0.5) (drill 0.2) (layers "F.Cu" "B.Cu") (net 308))
  (via (at 247.736328 57.360008) (size 0.5) (drill 0.2) (layers "F.Cu" "B.Cu") (net 308))
  (via (at 247.736328 58.860008) (size 0.5) (drill 0.2) (layers "F.Cu" "B.Cu") (net 308))
  (via (at 247.736328 60.360008) (size 0.5) (drill 0.2) (layers "F.Cu" "B.Cu") (net 308))
  (via (at 248.236328 56.610008) (size 0.5) (drill 0.2) (layers "F.Cu" "B.Cu") (net 308))
  (via (at 248.236328 58.110008) (size 0.5) (drill 0.2) (layers "F.Cu" "B.Cu") (net 308))
  (via (at 248.236328 59.610008) (size 0.5) (drill 0.2) (layers "F.Cu" "B.Cu") (net 308))
  (via (at 247.736328 54.360008) (size 0.5) (drill 0.2) (layers "F.Cu" "B.Cu") (net 308))
  (via (at 108.57 110.42) (size 0.5) (drill 0.2) (layers "F.Cu" "B.Cu") (net 308))
  (via (at 107.92 112.22) (size 0.5) (drill 0.2) (layers "F.Cu" "B.Cu") (net 308))
  (via (at 248.236328 55.110008) (size 0.5) (drill 0.2) (layers "F.Cu" "B.Cu") (net 308))
  (via (at 109.036328 110.760008) (size 0.5) (drill 0.2) (layers "F.Cu" "B.Cu") (net 308))
  (via (at 107.93 111.65) (size 0.5) (drill 0.2) (layers "F.Cu" "B.Cu") (net 308))
  (segment (start 188.636328 86.060008) (end 188.655836 86.060008) (width 0.127) (layer "F.Cu") (net 309))
  (segment (start 188.136328 86.560008) (end 188.636328 86.060008) (width 0.2) (layer "F.Cu") (net 309))
  (via (at 188.655836 86.060008) (size 0.5) (drill 0.2) (layers "F.Cu" "B.Cu") (net 309))
  (segment (start 189.96 84.89) (end 188.789992 86.060008) (width 0.4) (layer "B.Cu") (net 309))
  (segment (start 188.789992 86.060008) (end 188.655836 86.060008) (width 0.4) (layer "B.Cu") (net 309))
  (segment (start 185.63 85.060008) (end 185.649508 85.060008) (width 0.127) (layer "F.Cu") (net 310))
  (segment (start 185.13 85.560008) (end 185.63 85.060008) (width 0.2) (layer "F.Cu") (net 310))
  (via (at 185.649508 85.060008) (size 0.5) (drill 0.2) (layers "F.Cu" "B.Cu") (net 310))
  (segment (start 185.92 83.32) (end 185.92 84.789516) (width 0.4) (layer "B.Cu") (net 310))
  (segment (start 185.92 84.789516) (end 185.649508 85.060008) (width 0.4) (layer "B.Cu") (net 310))
  (segment (start 185.136328 100.560008) (end 184.636328 100.060008) (width 0.1) (layer "F.Cu") (net 311))
  (segment (start 180.406328 104.790008) (end 180.406328 106.6) (width 0.1) (layer "F.Cu") (net 311))
  (segment (start 181.636328 101.245507) (end 181.636328 103.560008) (width 0.1) (layer "F.Cu") (net 311))
  (segment (start 182.636328 100.874509) (end 182.450829 101.060008) (width 0.1) (layer "F.Cu") (net 311))
  (segment (start 184.636328 100.060008) (end 182.821827 100.060008) (width 0.1) (layer "F.Cu") (net 311))
  (segment (start 181.821827 101.060008) (end 181.636328 101.245507) (width 0.1) (layer "F.Cu") (net 311))
  (segment (start 182.450829 101.060008) (end 181.821827 101.060008) (width 0.1) (layer "F.Cu") (net 311))
  (segment (start 182.636328 100.245507) (end 182.636328 100.874509) (width 0.1) (layer "F.Cu") (net 311))
  (segment (start 181.636328 103.560008) (end 180.406328 104.790008) (width 0.1) (layer "F.Cu") (net 311))
  (segment (start 182.821827 100.060008) (end 182.636328 100.245507) (width 0.1) (layer "F.Cu") (net 311))
  (segment (start 186.635673 78.031673) (end 186.635673 78.060663) (width 0.127) (layer "F.Cu") (net 312))
  (segment (start 186.635673 78.060663) (end 186.136328 78.560008) (width 0.127) (layer "F.Cu") (net 312))
  (via (at 186.635673 78.031673) (size 0.5) (drill 0.2) (layers "F.Cu" "B.Cu") (net 312))
  (segment (start 186.425 76.735) (end 185.91 77.25) (width 0.2) (layer "B.Cu") (net 312))
  (segment (start 185.91 78.275) (end 186.392346 78.275) (width 0.2) (layer "B.Cu") (net 312))
  (segment (start 185.91 77.25) (end 185.91 78.275) (width 0.2) (layer "B.Cu") (net 312))
  (segment (start 186.425 75.975) (end 186.425 76.735) (width 0.2) (layer "B.Cu") (net 312))
  (segment (start 187.75 76.575) (end 187.15 75.975) (width 0.2) (layer "B.Cu") (net 312))
  (segment (start 186.392346 78.275) (end 186.635673 78.031673) (width 0.2) (layer "B.Cu") (net 312))
  (segment (start 187.15 75.975) (end 186.425 75.975) (width 0.2) (layer "B.Cu") (net 312))
  (segment (start 191.634581 83.230873) (end 191.519127 83.230873) (width 0.127) (layer "F.Cu") (net 314))
  (segment (start 240.111327 60.685009) (end 239.836328 60.960008) (width 0.1) (layer "F.Cu") (net 314))
  (segment (start 191.189992 83.560008) (end 191.136328 83.560008) (width 0.127) (layer "F.Cu") (net 314))
  (segment (start 240.111328 60.550008) (end 240.111327 60.685009) (width 0.1) (layer "F.Cu") (net 314))
  (segment (start 239.836328 59.660008) (end 239.836328 60.275008) (width 0.1) (layer "F.Cu") (net 314))
  (segment (start 191.519127 83.230873) (end 191.189992 83.560008) (width 0.127) (layer "F.Cu") (net 314))
  (segment (start 239.836328 60.275008) (end 240.111328 60.550008) (width 0.1) (layer "F.Cu") (net 314))
  (via (at 239.836328 60.960008) (size 0.5) (drill 0.2) (layers "F.Cu" "B.Cu") (net 314))
  (via (at 191.634581 83.230873) (size 0.5) (drill 0.2) (layers "F.Cu" "B.Cu") (net 314))
  (segment (start 206.423175 79.541286) (end 207.458714 80.576824) (width 0.143) (layer "In9.Cu") (net 314))
  (segment (start 191.909127 83.230873) (end 192.014105 83.125895) (width 0.1) (layer "In9.Cu") (net 314))
  (segment (start 192.014105 83.125895) (end 192.014105 82.764975) (width 0.1) (layer "In9.Cu") (net 314))
  (segment (start 205.151089 80.813372) (end 206.186628 81.848911) (width 0.143) (layer "In9.Cu") (net 314))
  (segment (start 192.299072 82.480008) (end 192.829806 82.480008) (width 0.1) (layer "In9.Cu") (net 314))
  (segment (start 204.443273 81.521188) (end 205.478811 82.556726) (width 0.143) (layer "In9.Cu") (net 314))
  (segment (start 204.926394 82.56858) (end 205.196676 82.838862) (width 0.143) (layer "In9.Cu") (net 314))
  (segment (start 198.2 82.6495) (end 204.13766 82.6495) (width 0.143) (layer "In9.Cu") (net 314))
  (segment (start 204.13766 82.6495) (end 204.21858 82.56858) (width 0.143) (layer "In9.Cu") (net 314))
  (segment (start 207.68341 79.103753) (end 207.683408 79.103754) (width 0.143) (layer "In9.Cu") (net 314))
  (segment (start 206.14104 79.823421) (end 207.176579 80.85896) (width 0.143) (layer "In9.Cu") (net 314))
  (segment (start 207.683408 79.103754) (end 217.43766 69.3495) (width 0.143) (layer "In9.Cu") (net 314))
  (segment (start 205.478812 82.838862) (end 205.478811 82.838862) (width 0.143) (layer "In9.Cu") (net 314))
  (segment (start 192.829806 82.480008) (end 192.994814 82.315) (width 0.1) (layer "In9.Cu") (net 314))
  (segment (start 207.458715 80.85896) (end 207.458714 80.85896) (width 0.143) (layer "In9.Cu") (net 314))
  (segment (start 191.634581 83.230873) (end 191.909127 83.230873) (width 0.1) (layer "In9.Cu") (net 314))
  (segment (start 192.014105 82.764975) (end 192.299072 82.480008) (width 0.1) (layer "In9.Cu") (net 314))
  (segment (start 198.1845 82.665) (end 198.2 82.6495) (width 0.1) (layer "In9.Cu") (net 314))
  (segment (start 239.836328 60.960008) (end 240.110827 61.234507) (width 0.143) (layer "In9.Cu") (net 314))
  (segment (start 240.110827 65.276333) (end 236.03766 69.3495) (width 0.143) (layer "In9.Cu") (net 314))
  (segment (start 196.53592 82.665) (end 198.1845 82.665) (width 0.1) (layer "In9.Cu") (net 314))
  (segment (start 205.433224 80.531237) (end 206.468763 81.566775) (width 0.143) (layer "In9.Cu") (net 314))
  (segment (start 206.468764 81.848911) (end 206.468763 81.848911) (width 0.143) (layer "In9.Cu") (net 314))
  (segment (start 240.110827 61.234507) (end 240.110827 65.276333) (width 0.143) (layer "In9.Cu") (net 314))
  (segment locked (start 236.03766 69.3495) (end 217.43766 69.3495) (width 0.143) (layer "In9.Cu") (net 314))
  (segment (start 192.994814 82.315) (end 196.18592 82.315) (width 0.1) (layer "In9.Cu") (net 314))
  (segment (start 207.130991 78.83347) (end 207.401274 79.103753) (width 0.143) (layer "In9.Cu") (net 314))
  (segment (start 196.18592 82.315) (end 196.53592 82.665) (width 0.1) (layer "In9.Cu") (net 314))
  (arc (start 205.433226 79.823421) (mid 205.787133 79.676828) (end 206.14104 79.823421) (width 0.143) (layer "In9.Cu") (net 314))
  (arc (start 207.458714 80.85896) (mid 207.517146 80.717892) (end 207.458714 80.576824) (width 0.143) (layer "In9.Cu") (net 314))
  (arc (start 206.186628 81.848911) (mid 206.327696 81.907343) (end 206.468764 81.848911) (width 0.143) (layer "In9.Cu") (net 314))
  (arc (start 206.423177 78.83347) (mid 206.777084 78.686877) (end 207.130991 78.83347) (width 0.143) (layer "In9.Cu") (net 314))
  (arc (start 205.196676 82.838862) (mid 205.337744 82.897294) (end 205.478812 82.838862) (width 0.143) (layer "In9.Cu") (net 314))
  (arc (start 206.423175 79.541286) (mid 206.276582 79.187379) (end 206.423177 78.83347) (width 0.143) (layer "In9.Cu") (net 314))
  (arc (start 207.176579 80.85896) (mid 207.317647 80.917392) (end 207.458715 80.85896) (width 0.143) (layer "In9.Cu") (net 314))
  (arc (start 204.21858 82.56858) (mid 204.572487 82.421987) (end 204.926394 82.56858) (width 0.143) (layer "In9.Cu") (net 314))
  (arc (start 204.443275 80.813372) (mid 204.797182 80.666779) (end 205.151089 80.813372) (width 0.143) (layer "In9.Cu") (net 314))
  (arc (start 207.401274 79.103753) (mid 207.542342 79.162185) (end 207.68341 79.103753) (width 0.143) (layer "In9.Cu") (net 314))
  (arc (start 205.433224 80.531237) (mid 205.286631 80.17733) (end 205.433226 79.823421) (width 0.143) (layer "In9.Cu") (net 314))
  (arc (start 204.443273 81.521188) (mid 204.29668 81.167281) (end 204.443275 80.813372) (width 0.143) (layer "In9.Cu") (net 314))
  (arc (start 205.478811 82.838862) (mid 205.537243 82.697794) (end 205.478811 82.556726) (width 0.143) (layer "In9.Cu") (net 314))
  (arc (start 206.468763 81.848911) (mid 206.527195 81.707843) (end 206.468763 81.566775) (width 0.143) (layer "In9.Cu") (net 314))
  (segment (start 192.634919 83.23036) (end 192.51964 83.23036) (width 0.127) (layer "F.Cu") (net 315))
  (segment (start 192.189992 83.560008) (end 192.136328 83.560008) (width 0.127) (layer "F.Cu") (net 315))
  (segment (start 240.686328 60.275008) (end 240.411328 60.550008) (width 0.1) (layer "F.Cu") (net 315))
  (segment (start 240.411328 60.550008) (end 240.411329 60.685009) (width 0.1) (layer "F.Cu") (net 315))
  (segment (start 240.686328 59.660008) (end 240.686328 60.275008) (width 0.1) (layer "F.Cu") (net 315))
  (segment (start 192.51964 83.23036) (end 192.189992 83.560008) (width 0.127) (layer "F.Cu") (net 315))
  (segment (start 240.411329 60.685009) (end 240.686328 60.960008) (width 0.1) (layer "F.Cu") (net 315))
  (via (at 240.686328 60.960008) (size 0.5) (drill 0.2) (layers "F.Cu" "B.Cu") (net 315))
  (via (at 192.634919 83.23036) (size 0.5) (drill 0.2) (layers "F.Cu" "B.Cu") (net 315))
  (segment (start 206.636016 79.046309) (end 206.636015 79.046311) (width 0.143) (layer "In9.Cu") (net 315))
  (segment (start 192.284105 83.154105) (end 192.284105 82.876815) (width 0.1) (layer "In9.Cu") (net 315))
  (segment (start 240.686328 60.960008) (end 240.411829 61.234507) (width 0.143) (layer "In9.Cu") (net 315))
  (segment (start 206.44597 80.554032) (end 206.44597 80.554029) (width 0.143) (layer "In9.Cu") (net 315))
  (segment (start 192.941635 82.749989) (end 193.106624 82.585) (width 0.1) (layer "In9.Cu") (net 315))
  (segment (start 196.07408 82.585) (end 196.42408 82.935) (width 0.1) (layer "In9.Cu") (net 315))
  (segment (start 204.26234 82.9505) (end 204.431419 82.781419) (width 0.143) (layer "In9.Cu") (net 315))
  (segment (start 193.106624 82.585) (end 196.07408 82.585) (width 0.1) (layer "In9.Cu") (net 315))
  (segment (start 204.938249 81.026213) (end 205.456019 81.543983) (width 0.143) (layer "In9.Cu") (net 315))
  (segment (start 205.173881 81.826117) (end 205.173884 81.826117) (width 0.143) (layer "In9.Cu") (net 315))
  (segment (start 198.6095 83.1505) (end 198.6095 83.1945) (width 0.143) (layer "In9.Cu") (net 315))
  (segment (start 204.656114 81.026211) (end 204.656113 81.026213) (width 0.143) (layer "In9.Cu") (net 315))
  (segment locked (start 236.16234 69.6505) (end 217.56234 69.6505) (width 0.143) (layer "In9.Cu") (net 315))
  (segment (start 200.2095 83.1505) (end 200.2095 83.1945) (width 0.143) (layer "In9.Cu") (net 315))
  (segment (start 196.42408 82.935) (end 198.1845 82.935) (width 0.1) (layer "In9.Cu") (net 315))
  (segment (start 206.636016 79.328445) (end 207.671554 80.363985) (width 0.143) (layer "In9.Cu") (net 315))
  (segment (start 205.456019 81.54398) (end 205.973789 82.06175) (width 0.143) (layer "In9.Cu") (net 315))
  (segment (start 205.646065 80.03626) (end 205.646064 80.036262) (width 0.143) (layer "In9.Cu") (net 315))
  (segment (start 198.1845 82.935) (end 198.2 82.9505) (width 0.1) (layer "In9.Cu") (net 315))
  (segment (start 198.2 82.9505) (end 198.4095 82.9505) (width 0.143) (layer "In9.Cu") (net 315))
  (segment (start 240.411829 61.234507) (end 240.411829 65.401011) (width 0.143) (layer "In9.Cu") (net 315))
  (segment (start 192.284105 82.876815) (end 192.410931 82.749989) (width 0.1) (layer "In9.Cu") (net 315))
  (segment (start 201.4095 83.1945) (end 201.4095 83.1505) (width 0.143) (layer "In9.Cu") (net 315))
  (segment (start 199.0095 83.1945) (end 199.0095 83.1505) (width 0.143) (layer "In9.Cu") (net 315))
  (segment (start 205.646065 80.318396) (end 206.681603 81.353936) (width 0.143) (layer "In9.Cu") (net 315))
  (segment (start 205.456019 81.543983) (end 205.456019 81.54398) (width 0.143) (layer "In9.Cu") (net 315))
  (segment (start 192.36036 83.23036) (end 192.284105 83.154105) (width 0.1) (layer "In9.Cu") (net 315))
  (segment (start 207.896248 79.316594) (end 217.56234 69.6505) (width 0.143) (layer "In9.Cu") (net 315))
  (segment (start 192.634919 83.23036) (end 192.36036 83.23036) (width 0.1) (layer "In9.Cu") (net 315))
  (segment (start 201.6095 82.9505) (end 201.6595 82.9505) (width 0.143) (layer "In9.Cu") (net 315))
  (segment (start 206.44597 80.554029) (end 206.96374 81.071799) (width 0.143) (layer "In9.Cu") (net 315))
  (segment (start 205.9282 80.036262) (end 206.44597 80.554032) (width 0.143) (layer "In9.Cu") (net 315))
  (segment (start 205.173884 81.826117) (end 204.656114 81.308347) (width 0.143) (layer "In9.Cu") (net 315))
  (segment (start 204.713555 82.781419) (end 204.983837 83.051701) (width 0.143) (layer "In9.Cu") (net 315))
  (segment (start 192.410931 82.749989) (end 192.941635 82.749989) (width 0.1) (layer "In9.Cu") (net 315))
  (segment (start 201.0095 83.1505) (end 201.0095 83.1945) (width 0.143) (layer "In9.Cu") (net 315))
  (segment (start 206.918151 79.046311) (end 207.188434 79.316594) (width 0.143) (layer "In9.Cu") (net 315))
  (segment (start 200.6095 83.1945) (end 200.6095 83.1505) (width 0.143) (layer "In9.Cu") (net 315))
  (segment (start 199.8095 83.1945) (end 199.8095 83.1505) (width 0.143) (layer "In9.Cu") (net 315))
  (segment (start 199.4095 83.1505) (end 199.4095 83.1945) (width 0.143) (layer "In9.Cu") (net 315))
  (segment (start 201.6595 82.9505) (end 204.26234 82.9505) (width 0.143) (layer "In9.Cu") (net 315))
  (segment (start 205.691651 82.343887) (end 205.173881 81.826117) (width 0.143) (layer "In9.Cu") (net 315))
  (segment (start 240.411829 65.401011) (end 236.16234 69.6505) (width 0.143) (layer "In9.Cu") (net 315))
  (arc (start 200.6095 83.1505) (mid 200.668079 83.009079) (end 200.8095 82.9505) (width 0.143) (layer "In9.Cu") (net 315))
  (arc (start 198.6095 83.1945) (mid 198.668079 83.335921) (end 198.8095 83.3945) (width 0.143) (layer "In9.Cu") (net 315))
  (arc (start 205.646064 80.036262) (mid 205.787132 79.97783) (end 205.9282 80.036262) (width 0.143) (layer "In9.Cu") (net 315))
  (arc (start 206.681603 82.06175) (mid 206.828196 81.707843) (end 206.681603 81.353936) (width 0.143) (layer "In9.Cu") (net 315))
  (arc (start 199.4095 83.1945) (mid 199.468079 83.335921) (end 199.6095 83.3945) (width 0.143) (layer "In9.Cu") (net 315))
  (arc (start 206.636015 79.046311) (mid 206.777083 78.987879) (end 206.918151 79.046311) (width 0.143) (layer "In9.Cu") (net 315))
  (arc (start 199.6095 83.3945) (mid 199.750921 83.335921) (end 199.8095 83.1945) (width 0.143) (layer "In9.Cu") (net 315))
  (arc (start 199.2095 82.9505) (mid 199.350921 83.009079) (end 199.4095 83.1505) (width 0.143) (layer "In9.Cu") (net 315))
  (arc (start 198.8095 83.3945) (mid 198.950921 83.335921) (end 199.0095 83.1945) (width 0.143) (layer "In9.Cu") (net 315))
  (arc (start 200.4095 83.3945) (mid 200.550921 83.335921) (end 200.6095 83.1945) (width 0.143) (layer "In9.Cu") (net 315))
  (arc (start 204.431419 82.781419) (mid 204.572487 82.722987) (end 204.713555 82.781419) (width 0.143) (layer "In9.Cu") (net 315))
  (arc (start 204.656114 81.308347) (mid 204.597682 81.167279) (end 204.656114 81.026211) (width 0.143) (layer "In9.Cu") (net 315))
  (arc (start 204.983837 83.051701) (mid 205.337744 83.198294) (end 205.691651 83.051701) (width 0.143) (layer "In9.Cu") (net 315))
  (arc (start 206.636016 79.328445) (mid 206.577584 79.187377) (end 206.636016 79.046309) (width 0.143) (layer "In9.Cu") (net 315))
  (arc (start 198.4095 82.9505) (mid 198.550921 83.009079) (end 198.6095 83.1505) (width 0.143) (layer "In9.Cu") (net 315))
  (arc (start 200.8095 82.9505) (mid 200.950921 83.009079) (end 201.0095 83.1505) (width 0.143) (layer "In9.Cu") (net 315))
  (arc (start 205.691651 83.051701) (mid 205.838244 82.697794) (end 205.691651 82.343887) (width 0.143) (layer "In9.Cu") (net 315))
  (arc (start 199.0095 83.1505) (mid 199.068079 83.009079) (end 199.2095 82.9505) (width 0.143) (layer "In9.Cu") (net 315))
  (arc (start 206.96374 81.071799) (mid 207.317647 81.218392) (end 207.671554 81.071799) (width 0.143) (layer "In9.Cu") (net 315))
  (arc (start 199.8095 83.1505) (mid 199.868079 83.009079) (end 200.0095 82.9505) (width 0.143) (layer "In9.Cu") (net 315))
  (arc (start 201.0095 83.1945) (mid 201.068079 83.335921) (end 201.2095 83.3945) (width 0.143) (layer "In9.Cu") (net 315))
  (arc (start 201.4095 83.1505) (mid 201.468079 83.009079) (end 201.6095 82.9505) (width 0.143) (layer "In9.Cu") (net 315))
  (arc (start 200.2095 83.1945) (mid 200.268079 83.335921) (end 200.4095 83.3945) (width 0.143) (layer "In9.Cu") (net 315))
  (arc (start 205.646065 80.318396) (mid 205.587633 80.177328) (end 205.646065 80.03626) (width 0.143) (layer "In9.Cu") (net 315))
  (arc (start 207.671554 81.071799) (mid 207.818147 80.717892) (end 207.671554 80.363985) (width 0.143) (layer "In9.Cu") (net 315))
  (arc (start 207.188434 79.316594) (mid 207.542341 79.463187) (end 207.896248 79.316594) (width 0.143) (layer "In9.Cu") (net 315))
  (arc (start 205.973789 82.06175) (mid 206.327696 82.208343) (end 206.681603 82.06175) (width 0.143) (layer "In9.Cu") (net 315))
  (arc (start 201.2095 83.3945) (mid 201.350921 83.335921) (end 201.4095 83.1945) (width 0.143) (layer "In9.Cu") (net 315))
  (arc (start 204.656113 81.026213) (mid 204.797181 80.967781) (end 204.938249 81.026213) (width 0.143) (layer "In9.Cu") (net 315))
  (arc (start 200.0095 82.9505) (mid 200.150921 83.009079) (end 200.2095 83.1505) (width 0.143) (layer "In9.Cu") (net 315))
  (segment (start 241.536328 55.060008) (end 241.536328 55.675008) (width 0.1) (layer "F.Cu") (net 316))
  (segment (start 241.536328 55.675008) (end 241.261328 55.950008) (width 0.1) (layer "F.Cu") (net 316))
  (segment (start 241.261328 55.950008) (end 241.261329 56.460011) (width 0.1) (layer "F.Cu") (net 316))
  (segment (start 241.261329 56.460011) (end 241.436328 56.63501) (width 0.1) (layer "F.Cu") (net 316))
  (segment (start 191.649733 84.046603) (end 191.136328 84.560008) (width 0.127) (layer "F.Cu") (net 316))
  (segment (start 191.649733 83.920267) (end 191.649733 84.046603) (width 0.127) (layer "F.Cu") (net 316))
  (via (at 191.649733 83.920267) (size 0.5) (drill 0.2) (layers "F.Cu" "B.Cu") (net 316))
  (via (at 241.436328 56.63501) (size 0.5) (drill 0.2) (layers "F.Cu" "B.Cu") (net 316))
  (segment (start 241.261829 59.378989) (end 241.261829 56.809509) (width 0.143) (layer "In9.Cu") (net 316))
  (segment (start 209.332839 79.837161) (end 209.332839 79.83967) (width 0.143) (layer "In9.Cu") (net 316))
  (segment locked (start 236.66234 71.1505) (end 219.06234 71.1505) (width 0.143) (layer "In9.Cu") (net 316))
  (segment (start 191.649733 83.920267) (end 191.970267 83.920267) (width 0.1) (layer "In9.Cu") (net 316))
  (segment (start 211.251538 79.638448) (end 211.251538 79.637049) (width 0.143) (layer "In9.Cu") (net 316))
  (segment (start 241.5705 66.24234) (end 236.66234 71.1505) (width 0.143) (layer "In9.Cu") (net 316))
  (segment (start 211.072406 79.140426) (end 211.147407 79.065429) (width 0.143) (layer "In9.Cu") (net 316))
  (segment (start 196.78235 84.1505) (end 198.2 84.1505) (width 0.1) (layer "In9.Cu") (net 316))
  (segment (start 241.5705 59.68766) (end 241.261829 59.378989) (width 0.143) (layer "In9.Cu") (net 316))
  (segment (start 191.970267 83.920267) (end 192.018491 83.968491) (width 0.1) (layer "In9.Cu") (net 316))
  (segment (start 209.332839 79.83967) (end 209.48142 79.98825) (width 0.143) (layer "In9.Cu") (net 316))
  (segment (start 192.256446 84.725) (end 194.24592 84.725) (width 0.1) (layer "In9.Cu") (net 316))
  (segment (start 195.36592 83.605) (end 196.23685 83.605) (width 0.1) (layer "In9.Cu") (net 316))
  (segment (start 196.23685 83.605) (end 196.78235 84.1505) (width 0.1) (layer "In9.Cu") (net 316))
  (segment (start 211.251538 80.381617) (end 211.251538 80.381618) (width 0.143) (layer "In9.Cu") (net 316))
  (segment (start 209.650331 79.521069) (end 209.650331 79.52358) (width 0.143) (layer "In9.Cu") (net 316))
  (segment (start 211.147412 79.065429) (end 219.06234 71.1505) (width 0.143) (layer "In9.Cu") (net 316))
  (segment (start 211.251538 79.637049) (end 211.072406 79.457917) (width 0.143) (layer "In9.Cu") (net 316))
  (segment (start 192.018491 83.968491) (end 192.018491 84.487045) (width 0.1) (layer "In9.Cu") (net 316))
  (segment (start 206.06234 84.1505) (end 198.2 84.1505) (width 0.143) (layer "In9.Cu") (net 316))
  (segment (start 194.24592 84.725) (end 195.36592 83.605) (width 0.1) (layer "In9.Cu") (net 316))
  (segment (start 211.072406 79.140427) (end 211.072406 79.140426) (width 0.143) (layer "In9.Cu") (net 316))
  (segment (start 241.5705 66.24234) (end 241.5705 59.68766) (width 0.143) (layer "In9.Cu") (net 316))
  (segment (start 209.650331 79.52358) (end 210.508369 80.381618) (width 0.143) (layer "In9.Cu") (net 316))
  (segment (start 241.261829 56.809509) (end 241.436328 56.63501) (width 0.143) (layer "In9.Cu") (net 316))
  (segment (start 211.147407 79.065429) (end 211.147412 79.065429) (width 0.143) (layer "In9.Cu") (net 316))
  (segment (start 192.018491 84.487045) (end 192.256446 84.725) (width 0.1) (layer "In9.Cu") (net 316))
  (segment (start 209.481419 80.731419) (end 206.06234 84.1505) (width 0.143) (layer "In9.Cu") (net 316))
  (segment (start 209.650331 79.521069) (end 209.650332 79.519668) (width 0.143) (layer "In9.Cu") (net 316))
  (arc (start 209.650332 79.519668) (mid 209.491585 79.453914) (end 209.33284 79.51967) (width 0.143) (layer "In9.Cu") (net 316))
  (arc (start 209.48142 79.98825) (mid 209.635335 80.359835) (end 209.481419 80.731419) (width 0.143) (layer "In9.Cu") (net 316))
  (arc (start 211.072406 79.457917) (mid 211.006652 79.299172) (end 211.072406 79.140427) (width 0.143) (layer "In9.Cu") (net 316))
  (arc (start 211.251538 80.381618) (mid 211.405454 80.010033) (end 211.251538 79.638448) (width 0.143) (layer "In9.Cu") (net 316))
  (arc (start 210.508369 80.381618) (mid 210.879954 80.535533) (end 211.251538 80.381617) (width 0.143) (layer "In9.Cu") (net 316))
  (arc (start 209.33284 79.51967) (mid 209.267085 79.678415) (end 209.332839 79.837161) (width 0.143) (layer "In9.Cu") (net 316))
  (segment (start 192.635001 83.994999) (end 192.136328 84.493672) (width 0.127) (layer "F.Cu") (net 317))
  (segment (start 240.961328 55.950008) (end 240.961327 56.460011) (width 0.1) (layer "F.Cu") (net 317))
  (segment (start 240.961327 56.460011) (end 240.786328 56.63501) (width 0.1) (layer "F.Cu") (net 317))
  (segment (start 240.686328 55.060008) (end 240.686328 55.675008) (width 0.1) (layer "F.Cu") (net 317))
  (segment (start 240.686328 55.675008) (end 240.961328 55.950008) (width 0.1) (layer "F.Cu") (net 317))
  (segment (start 192.635001 83.891759) (end 192.635001 83.994999) (width 0.127) (layer "F.Cu") (net 317))
  (segment (start 192.136328 84.493672) (end 192.136328 84.560008) (width 0.127) (layer "F.Cu") (net 317))
  (via (at 240.786328 56.63501) (size 0.5) (drill 0.2) (layers "F.Cu" "B.Cu") (net 317))
  (via (at 192.635001 83.891759) (size 0.5) (drill 0.2) (layers "F.Cu" "B.Cu") (net 317))
  (segment (start 202.8755 83.6245) (end 202.8755 83.588834) (width 0.143) (layer "In9.Cu") (net 317))
  (segment (start 209.863171 79.306829) (end 209.863171 79.310742) (width 0.143) (layer "In9.Cu") (net 317))
  (segment (start 209.12 80.052511) (end 209.12 80.05) (width 0.143) (layer "In9.Cu") (net 317))
  (segment (start 210.934573 78.85259) (end 218.93766 70.8495) (width 0.143) (layer "In9.Cu") (net 317))
  (segment (start 202.4255 83.588834) (end 202.4255 83.6245) (width 0.143) (layer "In9.Cu") (net 317))
  (segment (start 210.859566 78.927588) (end 210.934568 78.85259) (width 0.143) (layer "In9.Cu") (net 317))
  (segment (start 209.268579 80.20109) (end 209.12 80.052511) (width 0.143) (layer "In9.Cu") (net 317))
  (segment (start 195.25408 83.335) (end 196.34869 83.335) (width 0.1) (layer "In9.Cu") (net 317))
  (segment (start 241.2695 66.11766) (end 236.53766 70.8495) (width 0.143) (layer "In9.Cu") (net 317))
  (segment locked (start 236.53766 70.8495) (end 218.93766 70.8495) (width 0.143) (layer "In9.Cu") (net 317))
  (segment (start 211.038699 80.168778) (end 211.038699 80.168779) (width 0.143) (layer "In9.Cu") (net 317))
  (segment (start 240.960827 56.809509) (end 240.786328 56.63501) (width 0.143) (layer "In9.Cu") (net 317))
  (segment (start 241.2695 59.81234) (end 240.960827 59.503667) (width 0.143) (layer "In9.Cu") (net 317))
  (segment (start 203.3255 83.588834) (end 203.3255 83.645101) (width 0.143) (layer "In9.Cu") (net 317))
  (segment (start 192.635001 83.891759) (end 192.383241 83.891759) (width 0.1) (layer "In9.Cu") (net 317))
  (segment (start 209.268581 80.201089) (end 209.268579 80.20109) (width 0.143) (layer "In9.Cu") (net 317))
  (segment (start 210.859567 79.672155) (end 210.859567 79.670757) (width 0.143) (layer "In9.Cu") (net 317))
  (segment (start 198.2 83.8495) (end 201.7505 83.8495) (width 0.143) (layer "In9.Cu") (net 317))
  (segment (start 196.34869 83.335) (end 196.86319 83.8495) (width 0.1) (layer "In9.Cu") (net 317))
  (segment (start 192.368286 84.455) (end 194.13408 84.455) (width 0.1) (layer "In9.Cu") (net 317))
  (segment (start 203.529899 83.8495) (end 205.93766 83.8495) (width 0.143) (layer "In9.Cu") (net 317))
  (segment (start 192.288491 84.375205) (end 192.368286 84.455) (width 0.1) (layer "In9.Cu") (net 317))
  (segment (start 209.863171 79.310742) (end 210.721208 80.168779) (width 0.143) (layer "In9.Cu") (net 317))
  (segment (start 201.9755 83.6245) (end 201.9755 83.588834) (width 0.143) (layer "In9.Cu") (net 317))
  (segment (start 210.934568 78.85259) (end 210.934573 78.85259) (width 0.143) (layer "In9.Cu") (net 317))
  (segment (start 192.383241 83.891759) (end 192.288491 83.986509) (width 0.1) (layer "In9.Cu") (net 317))
  (segment (start 194.13408 84.455) (end 195.25408 83.335) (width 0.1) (layer "In9.Cu") (net 317))
  (segment (start 205.93766 83.8495) (end 209.26858 80.51858) (width 0.143) (layer "In9.Cu") (net 317))
  (segment (start 240.960827 59.503667) (end 240.960827 56.809509) (width 0.143) (layer "In9.Cu") (net 317))
  (segment (start 192.288491 83.986509) (end 192.288491 84.375205) (width 0.1) (layer "In9.Cu") (net 317))
  (segment (start 196.86319 83.8495) (end 198.2 83.8495) (width 0.1) (layer "In9.Cu") (net 317))
  (segment (start 211.038699 79.851287) (end 210.859567 79.672155) (width 0.143) (layer "In9.Cu") (net 317))
  (segment (start 241.2695 66.11766) (end 241.2695 59.81234) (width 0.143) (layer "In9.Cu") (net 317))
  (arc (start 202.4255 83.6245) (mid 202.491401 83.783599) (end 202.6505 83.8495) (width 0.143) (layer "In9.Cu") (net 317))
  (arc (start 203.1005 83.363834) (mid 203.259599 83.429735) (end 203.3255 83.588834) (width 0.143) (layer "In9.Cu") (net 317))
  (arc (start 202.6505 83.8495) (mid 202.809599 83.783599) (end 202.8755 83.6245) (width 0.143) (layer "In9.Cu") (net 317))
  (arc (start 209.26858 80.51858) (mid 209.334335 80.359835) (end 209.268581 80.201089) (width 0.143) (layer "In9.Cu") (net 317))
  (arc (start 202.8755 83.588834) (mid 202.941401 83.429735) (end 203.1005 83.363834) (width 0.143) (layer "In9.Cu") (net 317))
  (arc (start 201.7505 83.8495) (mid 201.909599 83.783599) (end 201.9755 83.6245) (width 0.143) (layer "In9.Cu") (net 317))
  (arc (start 209.12 80.05) (mid 208.966085 79.678415) (end 209.120001 79.306831) (width 0.143) (layer "In9.Cu") (net 317))
  (arc (start 211.038699 80.168779) (mid 211.104454 80.010033) (end 211.038699 79.851287) (width 0.143) (layer "In9.Cu") (net 317))
  (arc (start 209.120001 79.306831) (mid 209.491585 79.152914) (end 209.863171 79.306829) (width 0.143) (layer "In9.Cu") (net 317))
  (arc (start 202.2005 83.363834) (mid 202.359599 83.429735) (end 202.4255 83.588834) (width 0.143) (layer "In9.Cu") (net 317))
  (arc (start 210.721208 80.168779) (mid 210.879954 80.234533) (end 211.038699 80.168778) (width 0.143) (layer "In9.Cu") (net 317))
  (arc (start 203.3255 83.645101) (mid 203.385367 83.789633) (end 203.529899 83.8495) (width 0.143) (layer "In9.Cu") (net 317))
  (arc (start 201.9755 83.588834) (mid 202.041401 83.429735) (end 202.2005 83.363834) (width 0.143) (layer "In9.Cu") (net 317))
  (arc (start 210.859567 79.670757) (mid 210.705651 79.299173) (end 210.859566 78.927588) (width 0.143) (layer "In9.Cu") (net 317))
  (segment (start 230.747828 60.536508) (end 230.486328 60.275008) (width 0.127) (layer "F.Cu") (net 318))
  (segment (start 230.486328 60.275008) (end 230.486328 59.660008) (width 0.127) (layer "F.Cu") (net 318))
  (segment (start 230.486328 60.960008) (end 230.747828 60.698508) (width 0.127) (layer "F.Cu") (net 318))
  (segment (start 194.136328 82.560008) (end 194.636328 82.060008) (width 0.127) (layer "F.Cu") (net 318))
  (segment (start 230.747828 60.698508) (end 230.747828 60.536508) (width 0.127) (layer "F.Cu") (net 318))
  (segment (start 194.636328 82.060008) (end 194.655836 82.060008) (width 0.127) (layer "F.Cu") (net 318))
  (via blind (at 230.486328 60.960008) (size 0.5) (drill 0.2) (layers "F.Cu" "In5.Cu") (net 318))
  (via blind (at 194.655836 82.060008) (size 0.5) (drill 0.2) (layers "F.Cu" "In5.Cu") (net 318))
  (segment (start 195.392994 81.195) (end 198.14 81.195) (width 0.09) (layer "In5.Cu") (net 318))
  (segment (start 198.14 81.195) (end 198.355 81.195) (width 0.127) (layer "In5.Cu") (net 318))
  (segment (start 210.35 81.15) (end 210.35 80.1565) (width 0.127) (layer "In5.Cu") (net 318))
  (segment (start 208.387 80.1565) (end 208.387 81.0435) (width 0.127) (layer "In5.Cu") (net 318))
  (segment (start 202.387 80.9) (end 202.387 81.0435) (width 0.127) (layer "In5.Cu") (net 318))
  (segment (start 212.351499 80.4565) (end 213.34056 80.4565) (width 0.127) (layer "In5.Cu") (net 318))
  (segment (start 230.767828 63.029232) (end 230.767828 61.241508) (width 0.127) (layer "In5.Cu") (net 318))
  (segment (start 200.702891 81.194169) (end 201.44056 80.4565) (width 0.127) (layer "In5.Cu") (net 318))
  (segment (start 198.955831 81.194169) (end 200.702891 81.194169) (width 0.127) (layer "In5.Cu") (net 318))
  (segment (start 210.7935 79.713) (end 210.9435 79.713) (width 0.127) (layer "In5.Cu") (net 318))
  (segment (start 204.0435 81.2) (end 204.1935 81.2) (width 0.127) (layer "In5.Cu") (net 318))
  (segment (start 207.35 81.0435) (end 207.35 80.1565) (width 0.127) (layer "In5.Cu") (net 318))
  (segment (start 205.5435 81.2) (end 205.6935 81.2) (width 0.127) (layer "In5.Cu") (net 318))
  (segment (start 230.767828 61.241508) (end 230.486328 60.960008) (width 0.127) (layer "In5.Cu") (net 318))
  (segment (start 207.7935 79.713) (end 207.9435 79.713) (width 0.127) (layer "In5.Cu") (net 318))
  (segment (start 211.387 80.1565) (end 211.387 81.2) (width 0.127) (layer "In5.Cu") (net 318))
  (segment (start 195.010836 81.959164) (end 195.010836 81.577158) (width 0.09) (layer "In5.Cu") (net 318))
  (segment (start 194.909992 82.060008) (end 195.010836 81.959164) (width 0.09) (layer "In5.Cu") (net 318))
  (segment (start 194.655836 82.060008) (end 194.909992 82.060008) (width 0.09) (layer "In5.Cu") (net 318))
  (segment (start 206.887 80.1565) (end 206.887 81.0435) (width 0.127) (layer "In5.Cu") (net 318))
  (segment (start 203.2935 79.713) (end 203.4435 79.713) (width 0.127) (layer "In5.Cu") (net 318))
  (segment (start 205.387 80.1565) (end 205.387 81.0435) (width 0.127) (layer "In5.Cu") (net 318))
  (segment (start 211.5435 81.3565) (end 211.6935 81.3565) (width 0.127) (layer "In5.Cu") (net 318))
  (segment (start 204.7935 79.713) (end 204.9435 79.713) (width 0.127) (layer "In5.Cu") (net 318))
  (segment (start 213.34056 80.4565) (end 230.767828 63.029232) (width 0.127) (layer "In5.Cu") (net 318))
  (segment (start 202.85 81.0435) (end 202.85 80.1565) (width 0.127) (layer "In5.Cu") (net 318))
  (segment (start 208.5435 81.2) (end 208.6935 81.2) (width 0.127) (layer "In5.Cu") (net 318))
  (segment (start 203.887 80.1565) (end 203.887 81.0435) (width 0.127) (layer "In5.Cu") (net 318))
  (segment (start 209.2935 79.713) (end 209.4435 79.713) (width 0.127) (layer "In5.Cu") (net 318))
  (segment (start 198.355 81.195) (end 198.355831 81.194169) (width 0.127) (layer "In5.Cu") (net 318))
  (segment (start 210.0435 81.3065) (end 210.1935 81.3065) (width 0.127) (layer "In5.Cu") (net 318))
  (segment (start 198.505831 81.044169) (end 198.505831 81.03734) (width 0.127) (layer "In5.Cu") (net 318))
  (segment (start 206.2935 79.713) (end 206.4435 79.713) (width 0.127) (layer "In5.Cu") (net 318))
  (segment (start 204.35 81.0435) (end 204.35 80.1565) (width 0.127) (layer "In5.Cu") (net 318))
  (segment (start 202.5435 81.2) (end 202.6935 81.2) (width 0.127) (layer "In5.Cu") (net 318))
  (segment (start 209.887 80.1565) (end 209.887 81.15) (width 0.127) (layer "In5.Cu") (net 318))
  (segment (start 205.85 81.0435) (end 205.85 80.1565) (width 0.127) (layer "In5.Cu") (net 318))
  (segment (start 207.0435 81.2) (end 207.1935 81.2) (width 0.127) (layer "In5.Cu") (net 318))
  (segment (start 208.85 81.0435) (end 208.85 80.1565) (width 0.127) (layer "In5.Cu") (net 318))
  (segment (start 195.010836 81.577158) (end 195.392994 81.195) (width 0.09) (layer "In5.Cu") (net 318))
  (segment (start 198.805831 81.03734) (end 198.805831 81.044169) (width 0.127) (layer "In5.Cu") (net 318))
  (segment (start 201.44056 80.4565) (end 201.9435 80.4565) (width 0.127) (layer "In5.Cu") (net 318))
  (segment (start 211.85 81.2) (end 211.85 80.957999) (width 0.127) (layer "In5.Cu") (net 318))
  (arc (start 207.1935 81.2) (mid 207.304162 81.154162) (end 207.35 81.0435) (width 0.127) (layer "In5.Cu") (net 318))
  (arc (start 198.355831 81.194169) (mid 198.461897 81.150235) (end 198.505831 81.044169) (width 0.127) (layer "In5.Cu") (net 318))
  (arc (start 203.4435 79.713) (mid 203.757102 79.842898) (end 203.887 80.1565) (width 0.127) (layer "In5.Cu") (net 318))
  (arc (start 205.387 81.0435) (mid 205.432838 81.154162) (end 205.5435 81.2) (width 0.127) (layer "In5.Cu") (net 318))
  (arc (start 203.887 81.0435) (mid 203.932838 81.154162) (end 204.0435 81.2) (width 0.127) (layer "In5.Cu") (net 318))
  (arc (start 208.85 80.1565) (mid 208.979898 79.842898) (end 209.2935 79.713) (width 0.127) (layer "In5.Cu") (net 318))
  (arc (start 209.4435 79.713) (mid 209.757102 79.842898) (end 209.887 80.1565) (width 0.127) (layer "In5.Cu") (net 318))
  (arc (start 204.9435 79.713) (mid 205.257102 79.842898) (end 205.387 80.1565) (width 0.127) (layer "In5.Cu") (net 318))
  (arc (start 211.6935 81.3565) (mid 211.804162 81.310662) (end 211.85 81.2) (width 0.127) (layer "In5.Cu") (net 318))
  (arc (start 206.887 81.0435) (mid 206.932838 81.154162) (end 207.0435 81.2) (width 0.127) (layer "In5.Cu") (net 318))
  (arc (start 210.9435 79.713) (mid 211.257102 79.842898) (end 211.387 80.1565) (width 0.127) (layer "In5.Cu") (net 318))
  (arc (start 204.35 80.1565) (mid 204.479898 79.842898) (end 204.7935 79.713) (width 0.127) (layer "In5.Cu") (net 318))
  (arc (start 211.387 81.2) (mid 211.432838 81.310662) (end 211.5435 81.3565) (width 0.127) (layer "In5.Cu") (net 318))
  (arc (start 207.35 80.1565) (mid 207.479898 79.842898) (end 207.7935 79.713) (width 0.127) (layer "In5.Cu") (net 318))
  (arc (start 201.9435 80.4565) (mid 202.257102 80.586398) (end 202.387 80.9) (width 0.127) (layer "In5.Cu") (net 318))
  (arc (start 209.887 81.15) (mid 209.932838 81.260662) (end 210.0435 81.3065) (width 0.127) (layer "In5.Cu") (net 318))
  (arc (start 202.85 80.1565) (mid 202.979898 79.842898) (end 203.2935 79.713) (width 0.127) (layer "In5.Cu") (net 318))
  (arc (start 211.85 80.957999) (mid 211.996886 80.603386) (end 212.351499 80.4565) (width 0.127) (layer "In5.Cu") (net 318))
  (arc (start 207.9435 79.713) (mid 208.257102 79.842898) (end 208.387 80.1565) (width 0.127) (layer "In5.Cu") (net 318))
  (arc (start 202.6935 81.2) (mid 202.804162 81.154162) (end 202.85 81.0435) (width 0.127) (layer "In5.Cu") (net 318))
  (arc (start 206.4435 79.713) (mid 206.757102 79.842898) (end 206.887 80.1565) (width 0.127) (layer "In5.Cu") (net 318))
  (arc (start 198.805831 81.044169) (mid 198.849765 81.150235) (end 198.955831 81.194169) (width 0.127) (layer "In5.Cu") (net 318))
  (arc (start 198.505831 81.03734) (mid 198.549765 80.931274) (end 198.655831 80.88734) (width 0.127) (layer "In5.Cu") (net 318))
  (arc (start 210.35 80.1565) (mid 210.479898 79.842898) (end 210.7935 79.713) (width 0.127) (layer "In5.Cu") (net 318))
  (arc (start 208.387 81.0435) (mid 208.432838 81.154162) (end 208.5435 81.2) (width 0.127) (layer "In5.Cu") (net 318))
  (arc (start 210.1935 81.3065) (mid 210.304162 81.260662) (end 210.35 81.15) (width 0.127) (layer "In5.Cu") (net 318))
  (arc (start 205.85 80.1565) (mid 205.979898 79.842898) (end 206.2935 79.713) (width 0.127) (layer "In5.Cu") (net 318))
  (arc (start 208.6935 81.2) (mid 208.804162 81.154162) (end 208.85 81.0435) (width 0.127) (layer "In5.Cu") (net 318))
  (arc (start 198.655831 80.88734) (mid 198.761897 80.931274) (end 198.805831 81.03734) (width 0.127) (layer "In5.Cu") (net 318))
  (arc (start 202.387 81.0435) (mid 202.432838 81.154162) (end 202.5435 81.2) (width 0.127) (layer "In5.Cu") (net 318))
  (arc (start 204.1935 81.2) (mid 204.304162 81.154162) (end 204.35 81.0435) (width 0.127) (layer "In5.Cu") (net 318))
  (arc (start 205.6935 81.2) (mid 205.804162 81.154162) (end 205.85 81.0435) (width 0.127) (layer "In5.Cu") (net 318))
  (segment (start 194.636328 85.060008) (end 194.655836 85.060008) (width 0.127) (layer "F.Cu") (net 319))
  (segment (start 231.924828 55.936508) (end 232.186328 55.675008) (width 0.127) (layer "F.Cu") (net 319))
  (segment (start 194.136328 85.560008) (end 194.636328 85.060008) (width 0.127) (layer "F.Cu") (net 319))
  (segment (start 232.186328 55.675008) (end 232.186328 55.060008) (width 0.127) (layer "F.Cu") (net 319))
  (segment (start 232.086328 56.63501) (end 231.924828 56.47351) (width 0.127) (layer "F.Cu") (net 319))
  (segment (start 231.924828 56.47351) (end 231.924828 55.936508) (width 0.127) (layer "F.Cu") (net 319))
  (via blind (at 232.086328 56.63501) (size 0.5) (drill 0.2) (layers "F.Cu" "In5.Cu") (net 319))
  (via blind (at 194.655836 85.060008) (size 0.5) (drill 0.2) (layers "F.Cu" "In5.Cu") (net 319))
  (segment (start 195.319938 84.925) (end 195.099946 84.705008) (width 0.09) (layer "In5.Cu") (net 319))
  (segment (start 194.731664 84.705008) (end 194.655836 84.780836) (width 0.09) (layer "In5.Cu") (net 319))
  (segment (start 196.874359 84.904687) (end 196.750756 84.781085) (width 0.09) (layer "In5.Cu") (net 319))
  (segment (start 232.3535 63.87944) (end 213.53794 82.695) (width 0.127) (layer "In5.Cu") (net 319))
  (segment (start 196.57398 84.781086) (end 196.573977 84.781084) (width 0.09) (layer "In5.Cu") (net 319))
  (segment (start 200.11 84.295) (end 200.11 82.56) (width 0.127) (layer "In5.Cu") (net 319))
  (segment (start 196.92753 84.604308) (end 196.927531 84.604306) (width 0.09) (layer "In5.Cu") (net 319))
  (segment (start 201.143934 83.140169) (end 201.676607 83.672842) (width 0.127) (layer "In5.Cu") (net 319))
  (segment (start 196.97753 84.37753) (end 196.92753 84.42753) (width 0.09) (layer "In5.Cu") (net 319))
  (segment (start 201.677035 84.589) (end 201.566964 84.699071) (width 0.127) (layer "In5.Cu") (net 319))
  (segment (start 200.605 84.79) (end 201.347629 84.79) (width 0.127) (layer "In5.Cu") (net 319))
  (segment (start 201.767404 83.892045) (end 201.767404 84.15821) (width 0.127) (layer "In5.Cu") (net 319))
  (segment (start 232.3535 59.81056) (end 232.3535 63.87944) (width 0.127) (layer "In5.Cu") (net 319))
  (segment (start 198.205 82.695) (end 198.13 82.695) (width 0.127) (layer "In5.Cu") (net 319))
  (segment (start 197.331084 84.023977) (end 197.331082 84.023976) (width 0.09) (layer "In5.Cu") (net 319))
  (segment (start 197.331082 84.200752) (end 197.437148 84.306819) (width 0.09) (layer "In5.Cu") (net 319))
  (segment (start 198.41 84.3) (end 198.41 82.9) (width 0.127) (layer "In5.Cu") (net 319))
  (segment (start 194.655836 84.780836) (end 194.655836 85.060008) (width 0.09) (layer "In5.Cu") (net 319))
  (segment (start 213.53794 82.695) (end 201.305 82.695) (width 0.127) (layer "In5.Cu") (net 319))
  (segment (start 196.573979 84.781084) (end 196.57398 84.781086) (width 0.09) (layer "In5.Cu") (net 319))
  (segment (start 196.573977 84.781084) (end 196.430062 84.925) (width 0.09) (layer "In5.Cu") (net 319))
  (segment (start 196.927531 84.604306) (end 197.051135 84.727911) (width 0.09) (layer "In5.Cu") (net 319))
  (segment (start 197.690062 82.695) (end 197.375 83.010062) (width 0.09) (layer "In5.Cu") (net 319))
  (segment (start 197.260371 84.483596) (end 197.154306 84.37753) (width 0.09) (layer "In5.Cu") (net 319))
  (segment (start 201.143934 83.135994) (end 201.143934 83.140169) (width 0.127) (layer "In5.Cu") (net 319))
  (segment (start 201.767832 84.369797) (end 201.767832 84.158638) (width 0.127) (layer "In5.Cu") (net 319))
  (segment (start 201.347629 84.79) (end 201.347761 84.789868) (width 0.127) (layer "In5.Cu") (net 319))
  (segment (start 201.767832 84.158638) (end 201.767404 84.15821) (width 0.127) (layer "In5.Cu") (net 319))
  (segment (start 232.086328 56.63501) (end 231.904828 56.81651) (width 0.127) (layer "In5.Cu") (net 319))
  (segment (start 197.437148 84.483596) (end 197.437148 84.483597) (width 0.09) (layer "In5.Cu") (net 319))
  (segment (start 199.4 82.56) (end 199.4 84.3) (width 0.127) (layer "In5.Cu") (net 319))
  (segment (start 231.904828 56.81651) (end 231.904828 59.361888) (width 0.127) (layer "In5.Cu") (net 319))
  (segment (start 195.099946 84.705008) (end 194.731664 84.705008) (width 0.09) (layer "In5.Cu") (net 319))
  (segment (start 197.375 83.980062) (end 197.331084 84.023977) (width 0.09) (layer "In5.Cu") (net 319))
  (segment (start 196.430062 84.925) (end 195.319938 84.925) (width 0.09) (layer "In5.Cu") (net 319))
  (segment (start 198.13 82.695) (end 197.690062 82.695) (width 0.09) (layer "In5.Cu") (net 319))
  (segment (start 201.1 82.9) (end 201.1 83.029928) (width 0.127) (layer "In5.Cu") (net 319))
  (segment (start 197.437148 84.306819) (end 197.437148 84.306818) (width 0.09) (layer "In5.Cu") (net 319))
  (segment (start 197.375 83.010062) (end 197.375 83.980062) (width 0.09) (layer "In5.Cu") (net 319))
  (segment (start 199.905 82.355) (end 199.605 82.355) (width 0.127) (layer "In5.Cu") (net 319))
  (segment (start 231.904828 59.361888) (end 232.3535 59.81056) (width 0.127) (layer "In5.Cu") (net 319))
  (arc (start 197.437148 84.306818) (mid 197.47376 84.395207) (end 197.437148 84.483596) (width 0.09) (layer "In5.Cu") (net 319))
  (arc (start 196.750756 84.781085) (mid 196.662368 84.744473) (end 196.573979 84.781084) (width 0.09) (layer "In5.Cu") (net 319))
  (arc (start 200.605 84.79) (mid 200.254982 84.645018) (end 200.11 84.295) (width 0.127) (layer "In5.Cu") (net 319))
  (arc (start 201.305 82.695) (mid 201.160043 82.755043) (end 201.1 82.9) (width 0.127) (layer "In5.Cu") (net 319))
  (arc (start 199.605 82.355) (mid 199.460043 82.415043) (end 199.4 82.56) (width 0.127) (layer "In5.Cu") (net 319))
  (arc (start 200.11 82.56) (mid 200.049957 82.415043) (end 199.905 82.355) (width 0.127) (layer "In5.Cu") (net 319))
  (arc (start 197.154306 84.37753) (mid 197.065918 84.340918) (end 196.97753 84.37753) (width 0.09) (layer "In5.Cu") (net 319))
  (arc (start 201.676607 83.672842) (mid 201.743807 83.773413) (end 201.767404 83.892045) (width 0.127) (layer "In5.Cu") (net 319))
  (arc (start 201.566964 84.699071) (mid 201.466393 84.766271) (end 201.347761 84.789868) (width 0.127) (layer "In5.Cu") (net 319))
  (arc (start 197.051135 84.904687) (mid 196.962747 84.941299) (end 196.874359 84.904687) (width 0.09) (layer "In5.Cu") (net 319))
  (arc (start 196.92753 84.42753) (mid 196.890919 84.51592) (end 196.92753 84.604308) (width 0.09) (layer "In5.Cu") (net 319))
  (arc (start 198.905 84.795) (mid 198.554982 84.650018) (end 198.41 84.3) (width 0.127) (layer "In5.Cu") (net 319))
  (arc (start 198.41 82.9) (mid 198.349957 82.755043) (end 198.205 82.695) (width 0.127) (layer "In5.Cu") (net 319))
  (arc (start 197.051135 84.727911) (mid 197.087747 84.816299) (end 197.051135 84.904687) (width 0.09) (layer "In5.Cu") (net 319))
  (arc (start 201.1 83.029928) (mid 201.111418 83.087331) (end 201.143934 83.135994) (width 0.127) (layer "In5.Cu") (net 319))
  (arc (start 197.331082 84.023976) (mid 197.29447 84.112364) (end 197.331082 84.200752) (width 0.09) (layer "In5.Cu") (net 319))
  (arc (start 201.767832 84.369797) (mid 201.744235 84.488429) (end 201.677035 84.589) (width 0.127) (layer "In5.Cu") (net 319))
  (arc (start 197.437148 84.483597) (mid 197.348759 84.520208) (end 197.260371 84.483596) (width 0.09) (layer "In5.Cu") (net 319))
  (arc (start 199.4 84.3) (mid 199.255018 84.650018) (end 198.905 84.795) (width 0.127) (layer "In5.Cu") (net 319))
  (segment (start 195.136328 82.560008) (end 195.636328 82.060008) (width 0.127) (layer "F.Cu") (net 320))
  (segment (start 231.336328 60.960008) (end 231.074828 60.698508) (width 0.127) (layer "F.Cu") (net 320))
  (segment (start 231.074828 60.536508) (end 231.336328 60.275008) (width 0.127) (layer "F.Cu") (net 320))
  (segment (start 195.636328 82.060008) (end 195.655836 82.060008) (width 0.127) (layer "F.Cu") (net 320))
  (segment (start 231.336328 60.275008) (end 231.336328 59.660008) (width 0.127) (layer "F.Cu") (net 320))
  (segment (start 231.074828 60.698508) (end 231.074828 60.536508) (width 0.127) (layer "F.Cu") (net 320))
  (via blind (at 231.336328 60.960008) (size 0.5) (drill 0.2) (layers "F.Cu" "In5.Cu") (net 320))
  (via blind (at 195.655836 82.060008) (size 0.5) (drill 0.2) (layers "F.Cu" "In5.Cu") (net 320))
  (segment (start 204.637 81.0435) (end 204.637 80.1565) (width 0.127) (layer "In5.Cu") (net 320))
  (segment (start 209.137 81.0435) (end 209.137 80.1565) (width 0.127) (layer "In5.Cu") (net 320))
  (segment (start 195.300836 82.000836) (end 195.360008 82.060008) (width 0.09) (layer "In5.Cu") (net 320))
  (segment (start 231.054828 61.241508) (end 231.336328 60.960008) (width 0.127) (layer "In5.Cu") (net 320))
  (segment (start 210.7935 80) (end 210.9435 80) (width 0.127) (layer "In5.Cu") (net 320))
  (segment (start 198.14 81.485) (end 195.513118 81.485) (width 0.09) (layer "In5.Cu") (net 320))
  (segment (start 208.5435 81.487) (end 208.6935 81.487) (width 0.127) (layer "In5.Cu") (net 320))
  (segment (start 205.1 80.1565) (end 205.1 81.0435) (width 0.127) (layer "In5.Cu") (net 320))
  (segment (start 206.137 81.0435) (end 206.137 80.1565) (width 0.127) (layer "In5.Cu") (net 320))
  (segment (start 204.0435 81.487) (end 204.1935 81.487) (width 0.127) (layer "In5.Cu") (net 320))
  (segment (start 210.0435 81.5935) (end 210.1935 81.5935) (width 0.127) (layer "In5.Cu") (net 320))
  (segment (start 202.1 80.9) (end 202.1 81.0435) (width 0.127) (layer "In5.Cu") (net 320))
  (segment (start 198.14 81.485) (end 200.81794 81.485) (width 0.127) (layer "In5.Cu") (net 320))
  (segment (start 212.137 81.2) (end 212.137 80.989763) (width 0.127) (layer "In5.Cu") (net 320))
  (segment (start 195.300836 81.697282) (end 195.300836 82.000836) (width 0.09) (layer "In5.Cu") (net 320))
  (segment (start 206.2935 80) (end 206.4435 80) (width 0.127) (layer "In5.Cu") (net 320))
  (segment (start 203.2935 80) (end 203.4435 80) (width 0.127) (layer "In5.Cu") (net 320))
  (segment (start 205.5435 81.487) (end 205.6935 81.487) (width 0.127) (layer "In5.Cu") (net 320))
  (segment (start 209.6 80.1565) (end 209.6 81.15) (width 0.127) (layer "In5.Cu") (net 320))
  (segment (start 206.6 80.1565) (end 206.6 81.0435) (width 0.127) (layer "In5.Cu") (net 320))
  (segment (start 207.0435 81.487) (end 207.1935 81.487) (width 0.127) (layer "In5.Cu") (net 320))
  (segment (start 208.1 80.1565) (end 208.1 81.0435) (width 0.127) (layer "In5.Cu") (net 320))
  (segment (start 211.5435 81.6435) (end 211.6935 81.6435) (width 0.127) (layer "In5.Cu") (net 320))
  (segment (start 204.7935 80) (end 204.9435 80) (width 0.127) (layer "In5.Cu") (net 320))
  (segment (start 231.054828 63.148112) (end 231.054828 61.241508) (width 0.127) (layer "In5.Cu") (net 320))
  (segment (start 203.137 81.0435) (end 203.137 80.1565) (width 0.127) (layer "In5.Cu") (net 320))
  (segment (start 201.55944 80.7435) (end 201.9435 80.7435) (width 0.127) (layer "In5.Cu") (net 320))
  (segment (start 213.45944 80.7435) (end 231.054828 63.148112) (width 0.127) (layer "In5.Cu") (net 320))
  (segment (start 212.383263 80.7435) (end 213.45944 80.7435) (width 0.127) (layer "In5.Cu") (net 320))
  (segment (start 209.2935 80) (end 209.4435 80) (width 0.127) (layer "In5.Cu") (net 320))
  (segment (start 195.513118 81.485) (end 195.300836 81.697282) (width 0.09) (layer "In5.Cu") (net 320))
  (segment (start 211.1 80.1565) (end 211.1 81.2) (width 0.127) (layer "In5.Cu") (net 320))
  (segment (start 207.637 81.0435) (end 207.637 80.1565) (width 0.127) (layer "In5.Cu") (net 320))
  (segment (start 207.7935 80) (end 207.9435 80) (width 0.127) (layer "In5.Cu") (net 320))
  (segment (start 202.5435 81.487) (end 202.6935 81.487) (width 0.127) (layer "In5.Cu") (net 320))
  (segment (start 203.6 80.1565) (end 203.6 81.0435) (width 0.127) (layer "In5.Cu") (net 320))
  (segment (start 195.360008 82.060008) (end 195.655836 82.060008) (width 0.09) (layer "In5.Cu") (net 320))
  (segment (start 210.637 81.15) (end 210.637 80.1565) (width 0.127) (layer "In5.Cu") (net 320))
  (segment (start 200.81794 81.485) (end 201.55944 80.7435) (width 0.127) (layer "In5.Cu") (net 320))
  (arc (start 210.9435 80) (mid 211.054162 80.045838) (end 211.1 80.1565) (width 0.127) (layer "In5.Cu") (net 320))
  (arc (start 208.6935 81.487) (mid 209.007102 81.357102) (end 209.137 81.0435) (width 0.127) (layer "In5.Cu") (net 320))
  (arc (start 207.1935 81.487) (mid 207.507102 81.357102) (end 207.637 81.0435) (width 0.127) (layer "In5.Cu") (net 320))
  (arc (start 204.637 80.1565) (mid 204.682838 80.045838) (end 204.7935 80) (width 0.127) (layer "In5.Cu") (net 320))
  (arc (start 203.137 80.1565) (mid 203.182838 80.045838) (end 203.2935 80) (width 0.127) (layer "In5.Cu") (net 320))
  (arc (start 210.1935 81.5935) (mid 210.507102 81.463602) (end 210.637 81.15) (width 0.127) (layer "In5.Cu") (net 320))
  (arc (start 207.637 80.1565) (mid 207.682838 80.045838) (end 207.7935 80) (width 0.127) (layer "In5.Cu") (net 320))
  (arc (start 203.6 81.0435) (mid 203.729898 81.357102) (end 204.0435 81.487) (width 0.127) (layer "In5.Cu") (net 320))
  (arc (start 204.1935 81.487) (mid 204.507102 81.357102) (end 204.637 81.0435) (width 0.127) (layer "In5.Cu") (net 320))
  (arc (start 206.4435 80) (mid 206.554162 80.045838) (end 206.6 80.1565) (width 0.127) (layer "In5.Cu") (net 320))
  (arc (start 209.6 81.15) (mid 209.729898 81.463602) (end 210.0435 81.5935) (width 0.127) (layer "In5.Cu") (net 320))
  (arc (start 202.1 81.0435) (mid 202.229898 81.357102) (end 202.5435 81.487) (width 0.127) (layer "In5.Cu") (net 320))
  (arc (start 211.6935 81.6435) (mid 212.007102 81.513602) (end 212.137 81.2) (width 0.127) (layer "In5.Cu") (net 320))
  (arc (start 206.6 81.0435) (mid 206.729898 81.357102) (end 207.0435 81.487) (width 0.127) (layer "In5.Cu") (net 320))
  (arc (start 206.137 80.1565) (mid 206.182838 80.045838) (end 206.2935 80) (width 0.127) (layer "In5.Cu") (net 320))
  (arc (start 205.6935 81.487) (mid 206.007102 81.357102) (end 206.137 81.0435) (width 0.127) (layer "In5.Cu") (net 320))
  (arc (start 207.9435 80) (mid 208.054162 80.045838) (end 208.1 80.1565) (width 0.127) (layer "In5.Cu") (net 320))
  (arc (start 204.9435 80) (mid 205.054162 80.045838) (end 205.1 80.1565) (width 0.127) (layer "In5.Cu") (net 320))
  (arc (start 210.637 80.1565) (mid 210.682838 80.045838) (end 210.7935 80) (width 0.127) (layer "In5.Cu") (net 320))
  (arc (start 202.6935 81.487) (mid 203.007102 81.357102) (end 203.137 81.0435) (width 0.127) (layer "In5.Cu") (net 320))
  (arc (start 203.4435 80) (mid 203.554162 80.045838) (end 203.6 80.1565) (width 0.127) (layer "In5.Cu") (net 320))
  (arc (start 208.1 81.0435) (mid 208.229898 81.357102) (end 208.5435 81.487) (width 0.127) (layer "In5.Cu") (net 320))
  (arc (start 212.137 80.989763) (mid 212.209129 80.815629) (end 212.383263 80.7435) (width 0.127) (layer "In5.Cu") (net 320))
  (arc (start 201.9435 80.7435) (mid 202.054162 80.789338) (end 202.1 80.9) (width 0.127) (layer "In5.Cu") (net 320))
  (arc (start 209.137 80.1565) (mid 209.182838 80.045838) (end 209.2935 80) (width 0.127) (layer "In5.Cu") (net 320))
  (arc (start 209.4435 80) (mid 209.554162 80.045838) (end 209.6 80.1565) (width 0.127) (layer "In5.Cu") (net 320))
  (arc (start 205.1 81.0435) (mid 205.229898 81.357102) (end 205.5435 81.487) (width 0.127) (layer "In5.Cu") (net 320))
  (arc (start 211.1 81.2) (mid 211.229898 81.513602) (end 211.5435 81.6435) (width 0.127) (layer "In5.Cu") (net 320))
  (segment (start 194.636328 84.060008) (end 194.655836 84.060008) (width 0.127) (layer "F.Cu") (net 321))
  (segment (start 194.136328 84.560008) (end 194.636328 84.060008) (width 0.127) (layer "F.Cu") (net 321))
  (segment (start 231.436328 56.63501) (end 231.597828 56.47351) (width 0.127) (layer "F.Cu") (net 321))
  (segment (start 231.336328 55.675008) (end 231.336328 55.060008) (width 0.127) (layer "F.Cu") (net 321))
  (segment (start 231.597828 55.936508) (end 231.336328 55.675008) (width 0.127) (layer "F.Cu") (net 321))
  (segment (start 231.597828 56.47351) (end 231.597828 55.936508) (width 0.127) (layer "F.Cu") (net 321))
  (via blind (at 231.436328 56.63501) (size 0.5) (drill 0.2) (layers "F.Cu" "In5.Cu") (net 321))
  (via blind (at 194.655836 84.060008) (size 0.5) (drill 0.2) (layers "F.Cu" "In5.Cu") (net 321))
  (segment (start 231.436328 56.63501) (end 231.617828 56.81651) (width 0.127) (layer "In5.Cu") (net 321))
  (segment (start 194.655836 84.330836) (end 194.655836 84.060008) (width 0.09) (layer "In5.Cu") (net 321))
  (segment (start 197.569938 82.405) (end 197.085 82.889938) (width 0.09) (layer "In5.Cu") (net 321))
  (segment (start 198.7 84.3) (end 198.7 82.9) (width 0.127) (layer "In5.Cu") (net 321))
  (segment (start 195.22007 84.415008) (end 194.740008 84.415008) (width 0.09) (layer "In5.Cu") (net 321))
  (segment (start 201.436898 84.423257) (end 201.404221 84.455934) (width 0.127) (layer "In5.Cu") (net 321))
  (segment (start 232.0665 63.76056) (end 213.42206 82.405) (width 0.127) (layer "In5.Cu") (net 321))
  (segment (start 197.085 82.889938) (end 197.085 83.859938) (width 0.09) (layer "In5.Cu") (net 321))
  (segment (start 197.085 83.859938) (end 196.309938 84.635) (width 0.09) (layer "In5.Cu") (net 321))
  (segment (start 195.440062 84.635) (end 195.22007 84.415008) (width 0.09) (layer "In5.Cu") (net 321))
  (segment (start 194.740008 84.415008) (end 194.655836 84.330836) (width 0.09) (layer "In5.Cu") (net 321))
  (segment (start 231.617828 56.81651) (end 231.617828 59.480768) (width 0.127) (layer "In5.Cu") (net 321))
  (segment (start 200.81 82.9) (end 200.81 83.079534) (width 0.127) (layer "In5.Cu") (net 321))
  (segment (start 201.480832 84.317191) (end 201.480832 84.158638) (width 0.127) (layer "In5.Cu") (net 321))
  (segment (start 198.205 82.405) (end 198.13 82.405) (width 0.127) (layer "In5.Cu") (net 321))
  (segment (start 201.480404 83.944651) (end 201.480404 84.15821) (width 0.127) (layer "In5.Cu") (net 321))
  (segment (start 201.480832 84.158638) (end 201.480404 84.15821) (width 0.127) (layer "In5.Cu") (net 321))
  (segment (start 200.605 84.5) (end 201.298023 84.5) (width 0.127) (layer "In5.Cu") (net 321))
  (segment (start 232.0665 59.92944) (end 232.0665 63.76056) (width 0.127) (layer "In5.Cu") (net 321))
  (segment (start 199.905 82.065) (end 199.605 82.065) (width 0.127) (layer "In5.Cu") (net 321))
  (segment (start 200.4 84.295) (end 200.4 82.56) (width 0.127) (layer "In5.Cu") (net 321))
  (segment (start 198.13 82.405) (end 197.569938 82.405) (width 0.09) (layer "In5.Cu") (net 321))
  (segment (start 199.11 82.56) (end 199.11 84.3) (width 0.127) (layer "In5.Cu") (net 321))
  (segment (start 231.617828 59.480768) (end 232.0665 59.92944) (width 0.127) (layer "In5.Cu") (net 321))
  (segment (start 201.298023 84.5) (end 201.298155 84.499868) (width 0.127) (layer "In5.Cu") (net 321))
  (segment (start 200.900797 83.302912) (end 201.43647 83.838585) (width 0.127) (layer "In5.Cu") (net 321))
  (segment (start 200.900797 83.298737) (end 200.900797 83.302912) (width 0.127) (layer "In5.Cu") (net 321))
  (segment (start 213.42206 82.405) (end 201.305 82.405) (width 0.127) (layer "In5.Cu") (net 321))
  (segment (start 196.309938 84.635) (end 195.440062 84.635) (width 0.09) (layer "In5.Cu") (net 321))
  (arc (start 198.905 84.505) (mid 198.760043 84.444957) (end 198.7 84.3) (width 0.127) (layer "In5.Cu") (net 321))
  (arc (start 200.4 82.56) (mid 200.255018 82.209982) (end 199.905 82.065) (width 0.127) (layer "In5.Cu") (net 321))
  (arc (start 199.11 84.3) (mid 199.049957 84.444957) (end 198.905 84.505) (width 0.127) (layer "In5.Cu") (net 321))
  (arc (start 201.480832 84.317191) (mid 201.469414 84.374594) (end 201.436898 84.423257) (width 0.127) (layer "In5.Cu") (net 321))
  (arc (start 201.305 82.405) (mid 200.954982 82.549982) (end 200.81 82.9) (width 0.127) (layer "In5.Cu") (net 321))
  (arc (start 201.404221 84.455934) (mid 201.355558 84.48845) (end 201.298155 84.499868) (width 0.127) (layer "In5.Cu") (net 321))
  (arc (start 200.81 83.079534) (mid 200.833597 83.198166) (end 200.900797 83.298737) (width 0.127) (layer "In5.Cu") (net 321))
  (arc (start 199.605 82.065) (mid 199.254982 82.209982) (end 199.11 82.56) (width 0.127) (layer "In5.Cu") (net 321))
  (arc (start 200.605 84.5) (mid 200.460043 84.439957) (end 200.4 84.295) (width 0.127) (layer "In5.Cu") (net 321))
  (arc (start 201.480404 83.944651) (mid 201.468986 83.887248) (end 201.43647 83.838585) (width 0.127) (layer "In5.Cu") (net 321))
  (arc (start 198.7 82.9) (mid 198.555018 82.549982) (end 198.205 82.405) (width 0.127) (layer "In5.Cu") (net 321))
  (segment (start 196.71 81.07) (end 196.219992 81.560008) (width 0.127) (layer "F.Cu") (net 322))
  (segment (start 196.219992 81.560008) (end 196.136328 81.560008) (width 0.127) (layer "F.Cu") (net 322))
  (segment (start 221.411327 60.685009) (end 221.136328 60.960008) (width 0.1) (layer "F.Cu") (net 322))
  (segment (start 221.136328 59.660008) (end 221.136328 60.275008) (width 0.1) (layer "F.Cu") (net 322))
  (segment (start 196.81 81.07) (end 196.71 81.07) (width 0.127) (layer "F.Cu") (net 322))
  (segment (start 221.411328 60.550008) (end 221.411327 60.685009) (width 0.1) (layer "F.Cu") (net 322))
  (segment (start 221.136328 60.275008) (end 221.411328 60.550008) (width 0.1) (layer "F.Cu") (net 322))
  (via blind (at 196.81 81.07) (size 0.5) (drill 0.2) (layers "F.Cu" "In2.Cu") (net 322))
  (via blind (at 221.136328 60.960008) (size 0.5) (drill 0.2) (layers "F.Cu" "In2.Cu") (net 322))
  (segment (start 209.568282 78.359953) (end 209.568283 78.359952) (width 0.143) (layer "In2.Cu") (net 322))
  (segment (start 198.2 80.22064) (end 198.185207 80.235433) (width 0.1) (layer "In2.Cu") (net 322))
  (segment (start 208.297922 77.477793) (end 209.180081 78.359952) (width 0.143) (layer "In2.Cu") (net 322))
  (segment (start 197.421 80.44808) (end 197.421 81.18908) (width 0.1) (layer "In2.Cu") (net 322))
  (segment (start 206.281959 78.679162) (end 206.281959 78.679161) (width 0.143) (layer "In2.Cu") (net 322))
  (segment (start 197.421 81.18908) (end 197.13008 81.48) (width 0.1) (layer "In2.Cu") (net 322))
  (segment (start 198.2 80.22064) (end 201.27936 80.22064) (width 0.143) (layer "In2.Cu") (net 322))
  (segment (start 203.30436 79.99564) (end 203.30436 79.963513) (width 0.143) (layer "In2.Cu") (net 322))
  (segment (start 197.13008 81.48) (end 196.45592 81.48) (width 0.1) (layer "In2.Cu") (net 322))
  (segment (start 209.398785 76.988373) (end 221.410827 64.976333) (width 0.143) (layer "In2.Cu") (net 322))
  (segment (start 202.40436 79.99564) (end 202.40436 79.963513) (width 0.143) (layer "In2.Cu") (net 322))
  (segment (start 203.97936 80.22064) (end 206.16652 80.22064) (width 0.143) (layer "In2.Cu") (net 322))
  (segment (start 196.432292 80.685628) (end 196.707628 80.685628) (width 0.1) (layer "In2.Cu") (net 322))
  (segment (start 206.393581 79.604664) (end 206.281958 79.493041) (width 0.143) (layer "In2.Cu") (net 322))
  (segment (start 202.85436 79.963513) (end 202.85436 79.99564) (width 0.143) (layer "In2.Cu") (net 322))
  (segment (start 209.398786 76.988373) (end 209.398785 76.988373) (width 0.143) (layer "In2.Cu") (net 322))
  (segment (start 201.95436 79.963513) (end 201.95436 79.99564) (width 0.143) (layer "In2.Cu") (net 322))
  (segment (start 196.45592 81.48) (end 196.222 81.24608) (width 0.1) (layer "In2.Cu") (net 322))
  (segment (start 207.484041 77.477079) (end 207.484042 77.477078) (width 0.143) (layer "In2.Cu") (net 322))
  (segment (start 207.095839 78.679161) (end 207.095839 78.679876) (width 0.143) (layer "In2.Cu") (net 322))
  (segment (start 206.393581 79.605379) (end 206.393581 79.604664) (width 0.143) (layer "In2.Cu") (net 322))
  (segment (start 208.3662 79.17312) (end 207.48404 78.29096) (width 0.143) (layer "In2.Cu") (net 322))
  (segment (start 221.410827 61.234507) (end 221.136328 60.960008) (width 0.143) (layer "In2.Cu") (net 322))
  (segment (start 206.16652 80.22064) (end 206.393581 79.993581) (width 0.143) (layer "In2.Cu") (net 322))
  (segment (start 201.50436 79.99564) (end 201.50436 79.963513) (width 0.143) (layer "In2.Cu") (net 322))
  (segment (start 196.707628 80.685628) (end 196.81 80.788) (width 0.1) (layer "In2.Cu") (net 322))
  (segment (start 208.297922 77.477078) (end 208.297922 77.477793) (width 0.143) (layer "In2.Cu") (net 322))
  (segment (start 221.410827 64.976333) (end 221.410827 61.234507) (width 0.143) (layer "In2.Cu") (net 322))
  (segment (start 208.3662 79.173833) (end 208.3662 79.17312) (width 0.143) (layer "In2.Cu") (net 322))
  (segment (start 196.222 80.89592) (end 196.432292 80.685628) (width 0.1) (layer "In2.Cu") (net 322))
  (segment (start 198.185207 80.235433) (end 197.633647 80.235433) (width 0.1) (layer "In2.Cu") (net 322))
  (segment (start 207.095839 78.679876) (end 207.977998 79.562035) (width 0.143) (layer "In2.Cu") (net 322))
  (segment (start 197.633647 80.235433) (end 197.421 80.44808) (width 0.1) (layer "In2.Cu") (net 322))
  (segment (start 203.75436 79.963513) (end 203.75436 79.99564) (width 0.143) (layer "In2.Cu") (net 322))
  (segment (start 209.568283 77.97175) (end 209.398785 77.802252) (width 0.143) (layer "In2.Cu") (net 322))
  (segment (start 208.366199 79.562036) (end 208.3662 79.562035) (width 0.143) (layer "In2.Cu") (net 322))
  (segment (start 196.81 80.788) (end 196.81 81.07) (width 0.1) (layer "In2.Cu") (net 322))
  (segment (start 196.222 81.24608) (end 196.222 80.89592) (width 0.1) (layer "In2.Cu") (net 322))
  (arc (start 201.50436 79.963513) (mid 201.570261 79.804414) (end 201.72936 79.738513) (width 0.143) (layer "In2.Cu") (net 322))
  (arc (start 209.568283 78.359952) (mid 209.648682 78.165851) (end 209.568283 77.97175) (width 0.143) (layer "In2.Cu") (net 322))
  (arc (start 207.977998 79.562035) (mid 208.172098 79.642435) (end 208.366199 79.562036) (width 0.143) (layer "In2.Cu") (net 322))
  (arc (start 202.17936 80.22064) (mid 202.338459 80.154739) (end 202.40436 79.99564) (width 0.143) (layer "In2.Cu") (net 322))
  (arc (start 203.30436 79.963513) (mid 203.370261 79.804414) (end 203.52936 79.738513) (width 0.143) (layer "In2.Cu") (net 322))
  (arc (start 206.281959 78.679161) (mid 206.688899 78.510601) (end 207.095839 78.679161) (width 0.143) (layer "In2.Cu") (net 322))
  (arc (start 206.393581 79.993581) (mid 206.47398 79.79948) (end 206.393581 79.605379) (width 0.143) (layer "In2.Cu") (net 322))
  (arc (start 203.52936 79.738513) (mid 203.688459 79.804414) (end 203.75436 79.963513) (width 0.143) (layer "In2.Cu") (net 322))
  (arc (start 201.27936 80.22064) (mid 201.438459 80.154739) (end 201.50436 79.99564) (width 0.143) (layer "In2.Cu") (net 322))
  (arc (start 203.75436 79.99564) (mid 203.820261 80.154739) (end 203.97936 80.22064) (width 0.143) (layer "In2.Cu") (net 322))
  (arc (start 207.48404 78.29096) (mid 207.315481 77.88402) (end 207.484041 77.477079) (width 0.143) (layer "In2.Cu") (net 322))
  (arc (start 206.281958 79.493041) (mid 206.1134 79.0861) (end 206.281959 78.679162) (width 0.143) (layer "In2.Cu") (net 322))
  (arc (start 207.484042 77.477078) (mid 207.890982 77.308518) (end 208.297922 77.477078) (width 0.143) (layer "In2.Cu") (net 322))
  (arc (start 209.180081 78.359952) (mid 209.374181 78.440352) (end 209.568282 78.359953) (width 0.143) (layer "In2.Cu") (net 322))
  (arc (start 208.3662 79.562035) (mid 208.446599 79.367934) (end 208.3662 79.173833) (width 0.143) (layer "In2.Cu") (net 322))
  (arc (start 201.95436 79.99564) (mid 202.020261 80.154739) (end 202.17936 80.22064) (width 0.143) (layer "In2.Cu") (net 322))
  (arc (start 202.62936 79.738513) (mid 202.788459 79.804414) (end 202.85436 79.963513) (width 0.143) (layer "In2.Cu") (net 322))
  (arc (start 202.85436 79.99564) (mid 202.920261 80.154739) (end 203.07936 80.22064) (width 0.143) (layer "In2.Cu") (net 322))
  (arc (start 203.07936 80.22064) (mid 203.238459 80.154739) (end 203.30436 79.99564) (width 0.143) (layer "In2.Cu") (net 322))
  (arc (start 201.72936 79.738513) (mid 201.888459 79.804414) (end 201.95436 79.963513) (width 0.143) (layer "In2.Cu") (net 322))
  (arc (start 202.40436 79.963513) (mid 202.470261 79.804414) (end 202.62936 79.738513) (width 0.143) (layer "In2.Cu") (net 322))
  (arc (start 209.398785 77.802252) (mid 209.230226 77.395312) (end 209.398786 76.988373) (width 0.143) (layer "In2.Cu") (net 322))
  (segment (start 222.561329 56.460011) (end 222.736328 56.63501) (width 0.1) (layer "F.Cu") (net 323))
  (segment (start 196.155836 84.560008) (end 196.655836 84.060008) (width 0.127) (layer "F.Cu") (net 323))
  (segment (start 222.836328 55.060008) (end 222.836328 55.675008) (width 0.1) (layer "F.Cu") (net 323))
  (segment (start 196.136328 84.560008) (end 196.155836 84.560008) (width 0.127) (layer "F.Cu") (net 323))
  (segment (start 222.561328 55.950008) (end 222.561329 56.460011) (width 0.1) (layer "F.Cu") (net 323))
  (segment (start 222.836328 55.675008) (end 222.561328 55.950008) (width 0.1) (layer "F.Cu") (net 323))
  (via blind (at 222.736328 56.63501) (size 0.5) (drill 0.2) (layers "F.Cu" "In2.Cu") (net 323))
  (via blind (at 196.655836 84.060008) (size 0.5) (drill 0.2) (layers "F.Cu" "In2.Cu") (net 323))
  (segment (start 211.256419 78.356419) (end 208.083109 81.529731) (width 0.143) (layer "In2.Cu") (net 323))
  (segment (start 196.655836 84.060008) (end 196.655836 83.744164) (width 0.1) (layer "In2.Cu") (net 323))
  (segment (start 197.255912 83.695008) (end 197.485 83.46592) (width 0.1) (layer "In2.Cu") (net 323))
  (segment (start 200.370269 81.878296) (end 200.318833 81.878296) (width 0.143) (layer "In2.Cu") (net 323))
  (segment (start 198.966083 82.046757) (end 198.198282 82.046757) (width 0.143) (layer "In2.Cu") (net 323))
  (segment (start 196.655836 83.744164) (end 196.704992 83.695008) (width 0.1) (layer "In2.Cu") (net 323))
  (segment (start 199.483109 81.529731) (end 198.966083 82.046757) (width 0.143) (layer "In2.Cu") (net 323))
  (segment (start 202.144551 81.704013) (end 202.144551 81.704014) (width 0.143) (layer "In2.Cu") (net 323))
  (segment (start 211.534159 76.830329) (end 212.600257 77.896427) (width 0.143) (layer "In2.Cu") (net 323))
  (segment (start 197.914163 82.046757) (end 198.198282 82.046757) (width 0.1) (layer "In2.Cu") (net 323))
  (segment (start 222.736328 56.63501) (end 222.561829 56.809509) (width 0.143) (layer "In2.Cu") (net 323))
  (segment (start 197.485 83.46592) (end 197.485 82.47592) (width 0.1) (layer "In2.Cu") (net 323))
  (segment (start 212.600257 78.639597) (end 212.600258 78.639597) (width 0.143) (layer "In2.Cu") (net 323))
  (segment (start 222.9905 60.01766) (end 222.9905 66.62234) (width 0.143) (layer "In2.Cu") (net 323))
  (segment (start 208.083109 81.529731) (end 202.318833 81.529731) (width 0.143) (layer "In2.Cu") (net 323))
  (segment (start 211.857088 78.639597) (end 211.57391 78.356419) (width 0.143) (layer "In2.Cu") (net 323))
  (segment (start 201.170269 81.878296) (end 201.118833 81.878296) (width 0.143) (layer "In2.Cu") (net 323))
  (segment (start 200.944551 81.704014) (end 200.944551 81.704013) (width 0.143) (layer "In2.Cu") (net 323))
  (segment (start 199.970269 81.529731) (end 199.483109 81.529731) (width 0.143) (layer "In2.Cu") (net 323))
  (segment (start 211.57391 78.356419) (end 211.573911 78.356419) (width 0.143) (layer "In2.Cu") (net 323))
  (segment (start 211.851652 76.512839) (end 211.850331 76.512839) (width 0.143) (layer "In2.Cu") (net 323))
  (segment (start 222.561829 59.588989) (end 222.9905 60.01766) (width 0.143) (layer "In2.Cu") (net 323))
  (segment (start 201.970269 81.878296) (end 201.918833 81.878296) (width 0.143) (layer "In2.Cu") (net 323))
  (segment (start 211.532839 76.512839) (end 211.532841 76.512838) (width 0.143) (layer "In2.Cu") (net 323))
  (segment (start 222.9905 66.62234) (end 212.847412 76.765429) (width 0.143) (layer "In2.Cu") (net 323))
  (segment (start 200.770269 81.529731) (end 200.718833 81.529731) (width 0.143) (layer "In2.Cu") (net 323))
  (segment (start 197.485 82.47592) (end 197.914163 82.046757) (width 0.1) (layer "In2.Cu") (net 323))
  (segment (start 201.570269 81.529731) (end 201.518833 81.529731) (width 0.143) (layer "In2.Cu") (net 323))
  (segment (start 222.561829 56.809509) (end 222.561829 59.588989) (width 0.143) (layer "In2.Cu") (net 323))
  (segment (start 196.704992 83.695008) (end 197.255912 83.695008) (width 0.1) (layer "In2.Cu") (net 323))
  (segment (start 211.53284 76.830329) (end 211.534159 76.830329) (width 0.143) (layer "In2.Cu") (net 323))
  (segment (start 200.144551 81.704014) (end 200.144551 81.704013) (width 0.143) (layer "In2.Cu") (net 323))
  (segment (start 201.344551 81.704013) (end 201.344551 81.704014) (width 0.143) (layer "In2.Cu") (net 323))
  (segment (start 212.104242 76.765429) (end 211.851652 76.512839) (width 0.143) (layer "In2.Cu") (net 323))
  (segment (start 201.744551 81.704014) (end 201.744551 81.704013) (width 0.143) (layer "In2.Cu") (net 323))
  (segment (start 200.544551 81.704013) (end 200.544551 81.704014) (width 0.143) (layer "In2.Cu") (net 323))
  (arc (start 201.744551 81.704013) (mid 201.693505 81.580777) (end 201.570269 81.529731) (width 0.143) (layer "In2.Cu") (net 323))
  (arc (start 202.318833 81.529731) (mid 202.195597 81.580777) (end 202.144551 81.704013) (width 0.143) (layer "In2.Cu") (net 323))
  (arc (start 200.318833 81.878296) (mid 200.195597 81.82725) (end 200.144551 81.704014) (width 0.143) (layer "In2.Cu") (net 323))
  (arc (start 200.144551 81.704013) (mid 200.093505 81.580777) (end 199.970269 81.529731) (width 0.143) (layer "In2.Cu") (net 323))
  (arc (start 212.847412 76.765429) (mid 212.475826 76.919346) (end 212.104242 76.765429) (width 0.143) (layer "In2.Cu") (net 323))
  (arc (start 212.600258 78.639597) (mid 212.228673 78.793513) (end 211.857088 78.639597) (width 0.143) (layer "In2.Cu") (net 323))
  (arc (start 212.600257 77.896427) (mid 212.754173 78.268012) (end 212.600257 78.639597) (width 0.143) (layer "In2.Cu") (net 323))
  (arc (start 211.850331 76.512839) (mid 211.691586 76.447083) (end 211.532839 76.512839) (width 0.143) (layer "In2.Cu") (net 323))
  (arc (start 201.918833 81.878296) (mid 201.795597 81.82725) (end 201.744551 81.704014) (width 0.143) (layer "In2.Cu") (net 323))
  (arc (start 211.573911 78.356419) (mid 211.415165 78.290664) (end 211.256419 78.356419) (width 0.143) (layer "In2.Cu") (net 323))
  (arc (start 201.344551 81.704014) (mid 201.293505 81.82725) (end 201.170269 81.878296) (width 0.143) (layer "In2.Cu") (net 323))
  (arc (start 200.944551 81.704013) (mid 200.893505 81.580777) (end 200.770269 81.529731) (width 0.143) (layer "In2.Cu") (net 323))
  (arc (start 202.144551 81.704014) (mid 202.093505 81.82725) (end 201.970269 81.878296) (width 0.143) (layer "In2.Cu") (net 323))
  (arc (start 201.518833 81.529731) (mid 201.395597 81.580777) (end 201.344551 81.704013) (width 0.143) (layer "In2.Cu") (net 323))
  (arc (start 201.118833 81.878296) (mid 200.995597 81.82725) (end 200.944551 81.704014) (width 0.143) (layer "In2.Cu") (net 323))
  (arc (start 200.544551 81.704014) (mid 200.493505 81.82725) (end 200.370269 81.878296) (width 0.143) (layer "In2.Cu") (net 323))
  (arc (start 200.718833 81.529731) (mid 200.595597 81.580777) (end 200.544551 81.704013) (width 0.143) (layer "In2.Cu") (net 323))
  (arc (start 211.532841 76.512838) (mid 211.467086 76.671583) (end 211.53284 76.830329) (width 0.143) (layer "In2.Cu") (net 323))
  (segment (start 196.734 80.06) (end 196.233992 80.560008) (width 0.127) (layer "F.Cu") (net 324))
  (segment (start 196.8 80.06) (end 196.734 80.06) (width 0.127) (layer "F.Cu") (net 324))
  (segment (start 221.986328 59.660008) (end 221.986328 60.275008) (width 0.1) (layer "F.Cu") (net 324))
  (segment (start 196.233992 80.560008) (end 196.136328 80.560008) (width 0.127) (layer "F.Cu") (net 324))
  (segment (start 221.986328 60.275008) (end 221.711328 60.550008) (width 0.1) (layer "F.Cu") (net 324))
  (segment (start 221.711329 60.685009) (end 221.986328 60.960008) (width 0.1) (layer "F.Cu") (net 324))
  (segment (start 221.711328 60.550008) (end 221.711329 60.685009) (width 0.1) (layer "F.Cu") (net 324))
  (via blind (at 221.986328 60.960008) (size 0.5) (drill 0.2) (layers "F.Cu" "In2.Cu") (net 324))
  (via blind (at 196.8 80.06) (size 0.5) (drill 0.2) (layers "F.Cu" "In2.Cu") (net 324))
  (segment (start 209.611628 77.201212) (end 221.711829 65.101011) (width 0.143) (layer "In2.Cu") (net 324))
  (segment (start 195.952 81.35792) (end 195.952 80.78408) (width 0.1) (layer "In2.Cu") (net 324))
  (segment (start 209.574922 77.241094) (end 209.611625 77.204391) (width 0.143) (layer "In2.Cu") (net 324))
  (segment (start 198.2 80.52164) (end 198.183793 80.505433) (width 0.1) (layer "In2.Cu") (net 324))
  (segment (start 207.765159 79.774159) (end 206.883 78.892) (width 0.143) (layer "In2.Cu") (net 324))
  (segment (start 221.711829 61.234507) (end 221.986328 60.960008) (width 0.143) (layer "In2.Cu") (net 324))
  (segment (start 197.24192 81.75) (end 196.34408 81.75) (width 0.1) (layer "In2.Cu") (net 324))
  (segment (start 196.34408 81.75) (end 195.952 81.35792) (width 0.1) (layer "In2.Cu") (net 324))
  (segment (start 207.696881 77.689917) (end 207.69688 77.689918) (width 0.143) (layer "In2.Cu") (net 324))
  (segment (start 207.765159 79.774874) (end 207.765159 79.774159) (width 0.143) (layer "In2.Cu") (net 324))
  (segment (start 197.691 81.30092) (end 197.24192 81.75) (width 0.1) (layer "In2.Cu") (net 324))
  (segment (start 209.611625 77.201212) (end 209.611628 77.201212) (width 0.143) (layer "In2.Cu") (net 324))
  (segment (start 206.494798 78.892) (end 206.494798 78.892001) (width 0.143) (layer "In2.Cu") (net 324))
  (segment (start 209.781121 78.572792) (end 209.781122 78.572791) (width 0.143) (layer "In2.Cu") (net 324))
  (segment (start 196.320452 80.415628) (end 196.716372 80.415628) (width 0.1) (layer "In2.Cu") (net 324))
  (segment (start 208.579039 79.774874) (end 208.579038 79.774875) (width 0.143) (layer "In2.Cu") (net 324))
  (segment (start 207.696881 78.078836) (end 208.579039 78.960994) (width 0.143) (layer "In2.Cu") (net 324))
  (segment (start 198.183793 80.505433) (end 197.745487 80.505433) (width 0.1) (layer "In2.Cu") (net 324))
  (segment (start 196.716372 80.415628) (end 196.8 80.332) (width 0.1) (layer "In2.Cu") (net 324))
  (segment (start 209.611625 77.204391) (end 209.611625 77.201212) (width 0.143) (layer "In2.Cu") (net 324))
  (segment (start 195.952 80.78408) (end 196.320452 80.415628) (width 0.1) (layer "In2.Cu") (net 324))
  (segment (start 206.60642 79.391825) (end 206.494797 79.280202) (width 0.143) (layer "In2.Cu") (net 324))
  (segment (start 209.781122 77.758911) (end 209.611624 77.589413) (width 0.143) (layer "In2.Cu") (net 324))
  (segment (start 197.745487 80.505433) (end 197.691 80.55992) (width 0.1) (layer "In2.Cu") (net 324))
  (segment (start 207.696881 78.078119) (end 207.696881 78.078836) (width 0.143) (layer "In2.Cu") (net 324))
  (segment (start 206.60642 79.39254) (end 206.60642 79.391825) (width 0.143) (layer "In2.Cu") (net 324))
  (segment (start 208.085083 77.689917) (end 208.085083 77.690632) (width 0.143) (layer "In2.Cu") (net 324))
  (segment (start 206.60642 80.20642) (end 206.2912 80.52164) (width 0.143) (layer "In2.Cu") (net 324))
  (segment (start 208.085083 77.690632) (end 208.967242 78.572791) (width 0.143) (layer "In2.Cu") (net 324))
  (segment (start 197.691 80.55992) (end 197.691 81.30092) (width 0.1) (layer "In2.Cu") (net 324))
  (segment (start 206.2912 80.52164) (end 198.2 80.52164) (width 0.143) (layer "In2.Cu") (net 324))
  (segment (start 196.8 80.332) (end 196.8 80.06) (width 0.1) (layer "In2.Cu") (net 324))
  (segment (start 221.711829 65.101011) (end 221.711829 61.234507) (width 0.143) (layer "In2.Cu") (net 324))
  (arc (start 206.494798 78.892001) (mid 206.414398 79.086101) (end 206.494797 79.280202) (width 0.143) (layer "In2.Cu") (net 324))
  (arc (start 206.883 78.892) (mid 206.688899 78.811601) (end 206.494798 78.892) (width 0.143) (layer "In2.Cu") (net 324))
  (arc (start 208.967242 78.572791) (mid 209.374181 78.741351) (end 209.781121 78.572792) (width 0.143) (layer "In2.Cu") (net 324))
  (arc (start 208.579038 79.774875) (mid 208.172098 79.943434) (end 207.765159 79.774874) (width 0.143) (layer "In2.Cu") (net 324))
  (arc (start 208.085083 77.689917) (mid 207.890982 77.609518) (end 207.696881 77.689917) (width 0.143) (layer "In2.Cu") (net 324))
  (arc (start 209.611624 77.589413) (mid 209.532532 77.422216) (end 209.574922 77.241094) (width 0.143) (layer "In2.Cu") (net 324))
  (arc (start 209.781122 78.572791) (mid 209.949682 78.165851) (end 209.781122 77.758911) (width 0.143) (layer "In2.Cu") (net 324))
  (arc (start 207.69688 77.689918) (mid 207.616481 77.884019) (end 207.696881 78.078119) (width 0.143) (layer "In2.Cu") (net 324))
  (arc (start 208.579039 78.960994) (mid 208.747599 79.367934) (end 208.579039 79.774874) (width 0.143) (layer "In2.Cu") (net 324))
  (arc (start 206.60642 79.39254) (mid 206.77498 79.79948) (end 206.60642 80.20642) (width 0.143) (layer "In2.Cu") (net 324))
  (segment (start 196.155836 83.560008) (end 196.655836 83.060008) (width 0.127) (layer "F.Cu") (net 325))
  (segment (start 221.986328 55.675008) (end 222.261328 55.950008) (width 0.1) (layer "F.Cu") (net 325))
  (segment (start 196.136328 83.560008) (end 196.155836 83.560008) (width 0.127) (layer "F.Cu") (net 325))
  (segment (start 221.986328 55.060008) (end 221.986328 55.675008) (width 0.1) (layer "F.Cu") (net 325))
  (segment (start 222.261328 55.950008) (end 222.261327 56.460011) (width 0.1) (layer "F.Cu") (net 325))
  (segment (start 222.261327 56.460011) (end 222.086328 56.63501) (width 0.1) (layer "F.Cu") (net 325))
  (via blind (at 222.086328 56.63501) (size 0.5) (drill 0.2) (layers "F.Cu" "In2.Cu") (net 325))
  (via blind (at 196.655836 83.060008) (size 0.5) (drill 0.2) (layers "F.Cu" "In2.Cu") (net 325))
  (segment (start 198.841403 81.745757) (end 199.358429 81.228731) (width 0.143) (layer "In2.Cu") (net 325))
  (segment (start 212.634573 76.55259) (end 213.426868 75.760292) (width 0.143) (layer "In2.Cu") (net 325))
  (segment (start 207.958429 81.228731) (end 211.04358 78.14358) (width 0.143) (layer "In2.Cu") (net 325))
  (segment (start 196.725008 83.425008) (end 197.144072 83.425008) (width 0.1) (layer "In2.Cu") (net 325))
  (segment (start 197.144072 83.425008) (end 197.215 83.35408) (width 0.1) (layer "In2.Cu") (net 325))
  (segment (start 212.634572 76.552592) (end 212.634573 76.55259) (width 0.143) (layer "In2.Cu") (net 325))
  (segment (start 222.6895 66.49766) (end 222.6895 60.14234) (width 0.143) (layer "In2.Cu") (net 325))
  (segment (start 196.655836 83.355836) (end 196.725008 83.425008) (width 0.1) (layer "In2.Cu") (net 325))
  (segment (start 213.426868 75.760292) (end 222.6895 66.49766) (width 0.143) (layer "In2.Cu") (net 325))
  (segment (start 222.260827 59.713667) (end 222.260827 56.809509) (width 0.143) (layer "In2.Cu") (net 325))
  (segment (start 212.387418 78.426759) (end 212.387418 78.426758) (width 0.143) (layer "In2.Cu") (net 325))
  (segment (start 198.198282 81.745757) (end 198.841403 81.745757) (width 0.143) (layer "In2.Cu") (net 325))
  (segment (start 212.06317 76.3) (end 212.06449 76.3) (width 0.143) (layer "In2.Cu") (net 325))
  (segment (start 211.319999 77.04317) (end 211.321322 77.04317) (width 0.143) (layer "In2.Cu") (net 325))
  (segment (start 211.320002 76.299999) (end 211.32 76.3) (width 0.143) (layer "In2.Cu") (net 325))
  (segment (start 211.786749 78.14358) (end 212.069927 78.426758) (width 0.143) (layer "In2.Cu") (net 325))
  (segment (start 212.387418 78.109266) (end 211.321322 77.04317) (width 0.143) (layer "In2.Cu") (net 325))
  (segment (start 211.78675 78.14358) (end 211.786749 78.14358) (width 0.143) (layer "In2.Cu") (net 325))
  (segment (start 197.215 82.36408) (end 197.833323 81.745757) (width 0.1) (layer "In2.Cu") (net 325))
  (segment (start 222.260827 56.809509) (end 222.086328 56.63501) (width 0.143) (layer "In2.Cu") (net 325))
  (segment (start 197.215 83.35408) (end 197.215 82.36408) (width 0.1) (layer "In2.Cu") (net 325))
  (segment (start 196.655836 83.060008) (end 196.655836 83.355836) (width 0.1) (layer "In2.Cu") (net 325))
  (segment (start 199.358429 81.228731) (end 207.958429 81.228731) (width 0.143) (layer "In2.Cu") (net 325))
  (segment (start 222.6895 60.14234) (end 222.260827 59.713667) (width 0.143) (layer "In2.Cu") (net 325))
  (segment (start 197.833323 81.745757) (end 198.198282 81.745757) (width 0.1) (layer "In2.Cu") (net 325))
  (segment (start 212.06449 76.3) (end 212.317081 76.552591) (width 0.143) (layer "In2.Cu") (net 325))
  (arc (start 212.317081 76.552591) (mid 212.475826 76.618346) (end 212.634572 76.552592) (width 0.143) (layer "In2.Cu") (net 325))
  (arc (start 211.04358 78.14358) (mid 211.415165 77.989664) (end 211.78675 78.14358) (width 0.143) (layer "In2.Cu") (net 325))
  (arc (start 212.069927 78.426758) (mid 212.228672 78.492513) (end 212.387418 78.426759) (width 0.143) (layer "In2.Cu") (net 325))
  (arc (start 211.32 76.3) (mid 211.691586 76.146083) (end 212.06317 76.3) (width 0.143) (layer "In2.Cu") (net 325))
  (arc (start 212.387418 78.426758) (mid 212.453173 78.268012) (end 212.387418 78.109266) (width 0.143) (layer "In2.Cu") (net 325))
  (arc (start 211.319999 77.04317) (mid 211.166086 76.671583) (end 211.320002 76.299999) (width 0.143) (layer "In2.Cu") (net 325))
  (segment (start 192.6 76.96) (end 192.6 77.03) (width 0.127) (layer "F.Cu") (net 326))
  (segment (start 192.136328 77.493672) (end 192.136328 77.560008) (width 0.127) (layer "F.Cu") (net 326))
  (segment (start 212.047828 60.698508) (end 212.047828 60.536508) (width 0.127) (layer "F.Cu") (net 326))
  (segment (start 211.786328 60.960008) (end 212.047828 60.698508) (width 0.127) (layer "F.Cu") (net 326))
  (segment (start 212.047828 60.536508) (end 211.786328 60.275008) (width 0.127) (layer "F.Cu") (net 326))
  (segment (start 211.786328 60.275008) (end 211.786328 59.660008) (width 0.127) (layer "F.Cu") (net 326))
  (segment (start 192.6 77.03) (end 192.136328 77.493672) (width 0.127) (layer "F.Cu") (net 326))
  (via blind (at 192.6 76.96) (size 0.5) (drill 0.2) (layers "F.Cu" "In5.Cu") (net 326))
  (via blind (at 211.786328 60.960008) (size 0.5) (drill 0.2) (layers "F.Cu" "In5.Cu") (net 326))
  (segment (start 195.478099 66.963393) (end 195.478098 66.963394) (width 0.127) (layer "In5.Cu") (net 326))
  (segment (start 193.498196 69.64121) (end 194.196108 70.339123) (width 0.127) (layer "In5.Cu") (net 326))
  (segment (start 198.02455 65.847475) (end 198.0565 65.847475) (width 0.127) (layer "In5.Cu") (net 326))
  (segment (start 194.196108 70.63116) (end 194.196108 70.631159) (width 0.127) (layer "In5.Cu") (net 326))
  (segment (start 196.569519 67.064864) (end 196.569518 67.064864) (width 0.127) (layer "In5.Cu") (net 326))
  (segment (start 212.067828 61.241508) (end 211.786328 60.960008) (width 0.127) (layer "In5.Cu") (net 326))
  (segment (start 195.478098 67.661308) (end 196.176012 68.359221) (width 0.127) (layer "In5.Cu") (net 326))
  (segment (start 194.488147 68.651259) (end 195.186061 69.349172) (width 0.127) (layer "In5.Cu") (net 326))
  (segment (start 193.802604 70.52969) (end 193.904073 70.631159) (width 0.127) (layer "In5.Cu") (net 326))
  (segment (start 194.488148 67.953344) (end 194.488147 67.953345) (width 0.127) (layer "In5.Cu") (net 326))
  (segment (start 196.176014 66.963393) (end 196.277484 67.064863) (width 0.127) (layer "In5.Cu") (net 326))
  (segment (start 196.569518 67.064864) (end 196.985135 66.649245) (width 0.127) (layer "In5.Cu") (net 326))
  (segment (start 196.176012 68.651256) (end 196.176012 68.651257) (width 0.127) (layer "In5.Cu") (net 326))
  (segment (start 192.63 76.96) (end 192.87 76.72) (width 0.09) (layer "In5.Cu") (net 326))
  (segment (start 192.87 76.72) (end 192.87 75.58) (width 0.09) (layer "In5.Cu") (net 326))
  (segment (start 195.186061 69.641207) (end 195.186061 69.641208) (width 0.127) (layer "In5.Cu") (net 326))
  (segment (start 196.176014 66.963394) (end 196.176014 66.963393) (width 0.127) (layer "In5.Cu") (net 326))
  (segment (start 212.067828 62.199232) (end 212.067828 61.241508) (width 0.127) (layer "In5.Cu") (net 326))
  (segment (start 195.186063 67.953345) (end 195.186063 67.953344) (width 0.127) (layer "In5.Cu") (net 326))
  (segment (start 192.87 70.76438) (end 193.10469 70.52969) (width 0.127) (layer "In5.Cu") (net 326))
  (segment (start 198.67455 66.5565) (end 207.71056 66.5565) (width 0.127) (layer "In5.Cu") (net 326))
  (segment (start 197.572025 66.390975) (end 197.572025 66.3) (width 0.127) (layer "In5.Cu") (net 326))
  (segment (start 197.20904 66.5565) (end 197.4065 66.5565) (width 0.127) (layer "In5.Cu") (net 326))
  (segment (start 207.71056 66.5565) (end 212.067828 62.199232) (width 0.127) (layer "In5.Cu") (net 326))
  (segment (start 193.498197 68.943295) (end 193.498196 68.943296) (width 0.127) (layer "In5.Cu") (net 326))
  (segment (start 192.6 76.96) (end 192.63 76.96) (width 0.09) (layer "In5.Cu") (net 326))
  (segment (start 192.87 75.58) (end 192.87 70.76438) (width 0.127) (layer "In5.Cu") (net 326))
  (segment (start 194.196112 68.943295) (end 194.894026 69.641208) (width 0.127) (layer "In5.Cu") (net 326))
  (segment (start 198.509025 66.3) (end 198.509025 66.390975) (width 0.127) (layer "In5.Cu") (net 326))
  (segment (start 194.196112 68.943296) (end 194.196112 68.943295) (width 0.127) (layer "In5.Cu") (net 326))
  (segment (start 195.186063 67.953344) (end 195.883977 68.651257) (width 0.127) (layer "In5.Cu") (net 326))
  (arc (start 196.985135 66.649245) (mid 197.087863 66.580604) (end 197.20904 66.5565) (width 0.127) (layer "In5.Cu") (net 326))
  (arc (start 196.176012 68.651257) (mid 196.236495 68.505239) (end 196.176012 68.359221) (width 0.127) (layer "In5.Cu") (net 326))
  (arc (start 198.509025 66.390975) (mid 198.557506 66.508019) (end 198.67455 66.5565) (width 0.127) (layer "In5.Cu") (net 326))
  (arc (start 196.277484 67.064863) (mid 196.423501 67.125346) (end 196.569519 67.064864) (width 0.127) (layer "In5.Cu") (net 326))
  (arc (start 193.498196 68.943296) (mid 193.847155 68.798752) (end 194.196112 68.943296) (width 0.127) (layer "In5.Cu") (net 326))
  (arc (start 198.0565 65.847475) (mid 198.376483 65.980017) (end 198.509025 66.3) (width 0.127) (layer "In5.Cu") (net 326))
  (arc (start 193.10469 70.52969) (mid 193.453647 70.385147) (end 193.802604 70.52969) (width 0.127) (layer "In5.Cu") (net 326))
  (arc (start 197.572025 66.3) (mid 197.704567 65.980017) (end 198.02455 65.847475) (width 0.127) (layer "In5.Cu") (net 326))
  (arc (start 197.4065 66.5565) (mid 197.523544 66.508019) (end 197.572025 66.390975) (width 0.127) (layer "In5.Cu") (net 326))
  (arc (start 193.498196 69.64121) (mid 193.353654 69.292252) (end 193.498197 68.943295) (width 0.127) (layer "In5.Cu") (net 326))
  (arc (start 195.186061 69.641208) (mid 195.246544 69.49519) (end 195.186061 69.349172) (width 0.127) (layer "In5.Cu") (net 326))
  (arc (start 194.488147 68.651259) (mid 194.343605 68.302301) (end 194.488148 67.953344) (width 0.127) (layer "In5.Cu") (net 326))
  (arc (start 194.894026 69.641208) (mid 195.040044 69.70169) (end 195.186061 69.641207) (width 0.127) (layer "In5.Cu") (net 326))
  (arc (start 195.478098 66.963394) (mid 195.827057 66.81885) (end 196.176014 66.963394) (width 0.127) (layer "In5.Cu") (net 326))
  (arc (start 195.478098 67.661308) (mid 195.333556 67.31235) (end 195.478099 66.963393) (width 0.127) (layer "In5.Cu") (net 326))
  (arc (start 193.904073 70.631159) (mid 194.05009 70.691642) (end 194.196108 70.63116) (width 0.127) (layer "In5.Cu") (net 326))
  (arc (start 194.196108 70.631159) (mid 194.256591 70.485141) (end 194.196108 70.339123) (width 0.127) (layer "In5.Cu") (net 326))
  (arc (start 194.488147 67.953345) (mid 194.837106 67.808801) (end 195.186063 67.953345) (width 0.127) (layer "In5.Cu") (net 326))
  (arc (start 195.883977 68.651257) (mid 196.029995 68.711739) (end 196.176012 68.651256) (width 0.127) (layer "In5.Cu") (net 326))
  (segment (start 193.136328 79.560008) (end 193.636328 79.060008) (width 0.127) (layer "F.Cu") (net 327))
  (segment (start 213.224828 55.936508) (end 213.486328 55.675008) (width 0.127) (layer "F.Cu") (net 327))
  (segment (start 213.486328 55.675008) (end 213.486328 55.060008) (width 0.127) (layer "F.Cu") (net 327))
  (segment (start 213.386328 56.63501) (end 213.224828 56.47351) (width 0.127) (layer "F.Cu") (net 327))
  (segment (start 213.224828 56.47351) (end 213.224828 55.936508) (width 0.127) (layer "F.Cu") (net 327))
  (segment (start 193.636328 79.060008) (end 193.655836 79.060008) (width 0.127) (layer "F.Cu") (net 327))
  (via blind (at 213.386328 56.63501) (size 0.5) (drill 0.2) (layers "F.Cu" "In5.Cu") (net 327))
  (via blind (at 193.655836 79.060008) (size 0.5) (drill 0.2) (layers "F.Cu" "In5.Cu") (net 327))
  (segment (start 212.833211 55.730271) (end 212.166789 55.730271) (width 0.127) (layer "In5.Cu") (net 327))
  (segment (start 197.64056 68.0565) (end 193.9465 71.75056) (width 0.127) (layer "In5.Cu") (net 327))
  (segment (start 213.386328 56.63501) (end 213.204828 56.45351) (width 0.127) (layer "In5.Cu") (net 327))
  (segment (start 213.3065 62.61056) (end 207.86056 68.0565) (width 0.127) (layer "In5.Cu") (net 327))
  (segment (start 213.204828 56.101888) (end 212.833211 55.730271) (width 0.127) (layer "In5.Cu") (net 327))
  (segment (start 193.950855 78.33835) (end 193.950855 75.797887) (width 0.09) (layer "In5.Cu") (net 327))
  (segment (start 193.9465 71.75056) (end 193.9465 75.56) (width 0.127) (layer "In5.Cu") (net 327))
  (segment (start 211.8265 57.813449) (end 213.3065 59.293449) (width 0.127) (layer "In5.Cu") (net 327))
  (segment (start 213.204828 56.45351) (end 213.204828 56.101888) (width 0.127) (layer "In5.Cu") (net 327))
  (segment (start 207.86056 68.0565) (end 197.64056 68.0565) (width 0.127) (layer "In5.Cu") (net 327))
  (segment (start 194.010836 78.398331) (end 193.950855 78.33835) (width 0.09) (layer "In5.Cu") (net 327))
  (segment (start 193.950845 75.564345) (end 193.9465 75.56) (width 0.09) (layer "In5.Cu") (net 327))
  (segment (start 194.010836 78.705008) (end 194.010836 78.398331) (width 0.09) (layer "In5.Cu") (net 327))
  (segment (start 193.655836 79.060008) (end 194.010836 78.705008) (width 0.09) (layer "In5.Cu") (net 327))
  (segment (start 211.8265 56.07056) (end 211.8265 57.813449) (width 0.127) (layer "In5.Cu") (net 327))
  (segment (start 212.166789 55.730271) (end 211.8265 56.07056) (width 0.127) (layer "In5.Cu") (net 327))
  (segment (start 193.950855 75.797887) (end 193.950845 75.797877) (width 0.09) (layer "In5.Cu") (net 327))
  (segment (start 193.950845 75.797877) (end 193.950845 75.564345) (width 0.09) (layer "In5.Cu") (net 327))
  (segment (start 213.3065 59.293449) (end 213.3065 62.61056) (width 0.127) (layer "In5.Cu") (net 327))
  (segment (start 212.636328 60.960008) (end 212.374828 60.698508) (width 0.127) (layer "F.Cu") (net 328))
  (segment (start 193.43 76.96) (end 193.43 77.12) (width 0.127) (layer "F.Cu") (net 328))
  (segment (start 212.374828 60.698508) (end 212.374828 60.536508) (width 0.127) (layer "F.Cu") (net 328))
  (segment (start 193.43 77.12) (end 193.136328 77.413672) (width 0.127) (layer "F.Cu") (net 328))
  (segment (start 193.136328 77.413672) (end 193.136328 77.560008) (width 0.127) (layer "F.Cu") (net 328))
  (segment (start 212.636328 60.275008) (end 212.636328 59.660008) (width 0.127) (layer "F.Cu") (net 328))
  (segment (start 212.374828 60.536508) (end 212.636328 60.275008) (width 0.127) (layer "F.Cu") (net 328))
  (via blind (at 193.43 76.96) (size 0.5) (drill 0.2) (layers "F.Cu" "In5.Cu") (net 328))
  (via blind (at 212.636328 60.960008) (size 0.5) (drill 0.2) (layers "F.Cu" "In5.Cu") (net 328))
  (segment (start 195.389001 69.844147) (end 195.389 69.844148) (width 0.127) (layer "In5.Cu") (net 328))
  (segment (start 212.354828 61.241508) (end 212.636328 60.960008) (width 0.127) (layer "In5.Cu") (net 328))
  (segment (start 195.681039 67.166333) (end 195.681039 67.166332) (width 0.127) (layer "In5.Cu") (net 328))
  (segment (start 193.993173 69.146234) (end 194.691086 69.844148) (width 0.127) (layer "In5.Cu") (net 328))
  (segment (start 193.16 74.6) (end 193.16 70.88026) (width 0.127) (layer "In5.Cu") (net 328))
  (segment (start 197.859025 66.390975) (end 197.859025 66.3) (width 0.127) (layer "In5.Cu") (net 328))
  (segment (start 195.389 69.146232) (end 195.389 69.146233) (width 0.127) (layer "In5.Cu") (net 328))
  (segment (start 193.39 76.96) (end 193.43 76.96) (width 0.09) (layer "In5.Cu") (net 328))
  (segment (start 197.261668 66.8435) (end 197.4065 66.8435) (width 0.127) (layer "In5.Cu") (net 328))
  (segment (start 207.82944 66.8435) (end 212.354828 62.318112) (width 0.127) (layer "In5.Cu") (net 328))
  (segment (start 194.983124 68.156283) (end 195.681037 68.854197) (width 0.127) (layer "In5.Cu") (net 328))
  (segment (start 198.02455 66.134475) (end 198.0565 66.134475) (width 0.127) (layer "In5.Cu") (net 328))
  (segment (start 193.36 75.2) (end 193.371129 75.2) (width 0.127) (layer "In5.Cu") (net 328))
  (segment (start 193.16 76.73) (end 193.39 76.96) (width 0.09) (layer "In5.Cu") (net 328))
  (segment (start 196.378951 68.156281) (end 196.378951 68.156282) (width 0.127) (layer "In5.Cu") (net 328))
  (segment (start 198.67455 66.8435) (end 207.82944 66.8435) (width 0.127) (layer "In5.Cu") (net 328))
  (segment (start 193.16 70.88026) (end 193.307629 70.732629) (width 0.127) (layer "In5.Cu") (net 328))
  (segment (start 195.973075 67.166332) (end 196.074545 67.267802) (width 0.127) (layer "In5.Cu") (net 328))
  (segment (start 194.399048 70.136182) (end 194.399048 70.136183) (width 0.127) (layer "In5.Cu") (net 328))
  (segment (start 196.77246 67.267803) (end 196.772459 67.267803) (width 0.127) (layer "In5.Cu") (net 328))
  (segment (start 196.772459 67.267803) (end 197.150864 66.889397) (width 0.127) (layer "In5.Cu") (net 328))
  (segment (start 198.222025 66.3) (end 198.222025 66.390975) (width 0.127) (layer "In5.Cu") (net 328))
  (segment (start 196.378951 68.156282) (end 195.681038 67.458368) (width 0.127) (layer "In5.Cu") (net 328))
  (segment (start 193.599664 70.732629) (end 193.701133 70.834098) (width 0.127) (layer "In5.Cu") (net 328))
  (segment (start 196.378952 68.854196) (end 196.378951 68.854197) (width 0.127) (layer "In5.Cu") (net 328))
  (segment (start 193.599665 70.732629) (end 193.599664 70.732629) (width 0.127) (layer "In5.Cu") (net 328))
  (segment (start 193.16 75.58) (end 193.16 75.4) (width 0.127) (layer "In5.Cu") (net 328))
  (segment (start 212.354828 62.318112) (end 212.354828 61.241508) (width 0.127) (layer "In5.Cu") (net 328))
  (segment (start 193.371129 74.8) (end 193.36 74.8) (width 0.127) (layer "In5.Cu") (net 328))
  (segment (start 194.399048 70.834099) (end 194.399048 70.834098) (width 0.127) (layer "In5.Cu") (net 328))
  (segment (start 194.691088 68.156284) (end 194.691088 68.156283) (width 0.127) (layer "In5.Cu") (net 328))
  (segment (start 193.16 75.58) (end 193.16 76.73) (width 0.09) (layer "In5.Cu") (net 328))
  (segment (start 195.389 69.146233) (end 194.691087 68.448319) (width 0.127) (layer "In5.Cu") (net 328))
  (segment (start 193.701137 69.146235) (end 193.701137 69.146234) (width 0.127) (layer "In5.Cu") (net 328))
  (segment (start 194.399048 70.136183) (end 193.701136 69.43827) (width 0.127) (layer "In5.Cu") (net 328))
  (arc (start 197.150864 66.889397) (mid 197.201701 66.855428) (end 197.261668 66.8435) (width 0.127) (layer "In5.Cu") (net 328))
  (arc (start 195.681038 67.458368) (mid 195.620556 67.31235) (end 195.681039 67.166333) (width 0.127) (layer "In5.Cu") (net 328))
  (arc (start 193.307629 70.732629) (mid 193.453647 70.672146) (end 193.599665 70.732629) (width 0.127) (layer "In5.Cu") (net 328))
  (arc (start 197.4065 66.8435) (mid 197.726483 66.710958) (end 197.859025 66.390975) (width 0.127) (layer "In5.Cu") (net 328))
  (arc (start 193.571129 75) (mid 193.51255 74.858579) (end 193.371129 74.8) (width 0.127) (layer "In5.Cu") (net 328))
  (arc (start 193.701136 69.43827) (mid 193.640654 69.292252) (end 193.701137 69.146235) (width 0.127) (layer "In5.Cu") (net 328))
  (arc (start 193.701133 70.834098) (mid 194.05009 70.978641) (end 194.399048 70.834099) (width 0.127) (layer "In5.Cu") (net 328))
  (arc (start 193.36 74.8) (mid 193.218579 74.741421) (end 193.16 74.6) (width 0.127) (layer "In5.Cu") (net 328))
  (arc (start 196.074545 67.267802) (mid 196.423502 67.412345) (end 196.77246 67.267803) (width 0.127) (layer "In5.Cu") (net 328))
  (arc (start 197.859025 66.3) (mid 197.907506 66.182956) (end 198.02455 66.134475) (width 0.127) (layer "In5.Cu") (net 328))
  (arc (start 194.399048 70.834098) (mid 194.543591 70.48514) (end 194.399048 70.136182) (width 0.127) (layer "In5.Cu") (net 328))
  (arc (start 193.16 75.4) (mid 193.218579 75.258579) (end 193.36 75.2) (width 0.127) (layer "In5.Cu") (net 328))
  (arc (start 195.389 69.844148) (mid 195.533543 69.49519) (end 195.389 69.146232) (width 0.127) (layer "In5.Cu") (net 328))
  (arc (start 193.701137 69.146234) (mid 193.847154 69.085752) (end 193.993173 69.146234) (width 0.127) (layer "In5.Cu") (net 328))
  (arc (start 193.371129 75.2) (mid 193.51255 75.141421) (end 193.571129 75) (width 0.127) (layer "In5.Cu") (net 328))
  (arc (start 194.691086 69.844148) (mid 195.040044 69.98869) (end 195.389001 69.844147) (width 0.127) (layer "In5.Cu") (net 328))
  (arc (start 194.691088 68.156283) (mid 194.837105 68.095801) (end 194.983124 68.156283) (width 0.127) (layer "In5.Cu") (net 328))
  (arc (start 195.681039 67.166332) (mid 195.827056 67.10585) (end 195.973075 67.166332) (width 0.127) (layer "In5.Cu") (net 328))
  (arc (start 194.691087 68.448319) (mid 194.630605 68.302301) (end 194.691088 68.156284) (width 0.127) (layer "In5.Cu") (net 328))
  (arc (start 198.0565 66.134475) (mid 198.173544 66.182956) (end 198.222025 66.3) (width 0.127) (layer "In5.Cu") (net 328))
  (arc (start 198.222025 66.390975) (mid 198.354567 66.710958) (end 198.67455 66.8435) (width 0.127) (layer "In5.Cu") (net 328))
  (arc (start 196.378951 68.854197) (mid 196.523494 68.505239) (end 196.378951 68.156281) (width 0.127) (layer "In5.Cu") (net 328))
  (arc (start 195.681037 68.854197) (mid 196.029995 68.998739) (end 196.378952 68.854196) (width 0.127) (layer "In5.Cu") (net 328))
  (segment (start 212.897828 55.936508) (end 212.636328 55.675008) (width 0.127) (layer "F.Cu") (net 329))
  (segment (start 212.636328 55.675008) (end 212.636328 55.060008) (width 0.127) (layer "F.Cu") (net 329))
  (segment (start 194.636328 79.060008) (end 194.655836 79.060008) (width 0.127) (layer "F.Cu") (net 329))
  (segment (start 212.897828 56.47351) (end 212.897828 55.936508) (width 0.127) (layer "F.Cu") (net 329))
  (segment (start 194.136328 79.560008) (end 194.636328 79.060008) (width 0.127) (layer "F.Cu") (net 329))
  (segment (start 212.736328 56.63501) (end 212.897828 56.47351) (width 0.127) (layer "F.Cu") (net 329))
  (via blind (at 212.736328 56.63501) (size 0.5) (drill 0.2) (layers "F.Cu" "In5.Cu") (net 329))
  (via blind (at 194.655836 79.060008) (size 0.5) (drill 0.2) (layers "F.Cu" "In5.Cu") (net 329))
  (segment (start 194.2335 75.56) (end 194.2335 75.3565) (width 0.127) (layer "In5.Cu") (net 329))
  (segment (start 212.885161 58.098185) (end 212.885162 58.098184) (width 0.127) (layer "In5.Cu") (net 329))
  (segment (start 212.1135 56.18944) (end 212.1135 57.694569) (width 0.127) (layer "In5.Cu") (net 329))
  (segment (start 212.1135 57.694569) (end 212.524362 58.105431) (width 0.127) (layer "In5.Cu") (net 329))
  (segment (start 212.285669 56.017271) (end 212.1135 56.18944) (width 0.127) (layer "In5.Cu") (net 329))
  (segment (start 213.23147 58.812539) (end 213.5935 59.174569) (width 0.127) (layer "In5.Cu") (net 329))
  (segment (start 194.240845 75.567345) (end 194.2335 75.56) (width 0.09) (layer "In5.Cu") (net 329))
  (segment (start 194.2335 74.6565) (end 194.2335 71.86944) (width 0.127) (layer "In5.Cu") (net 329))
  (segment (start 194.240836 75.797886) (end 194.240845 75.797877) (width 0.09) (layer "In5.Cu") (net 329))
  (segment (start 194.240836 78.218235) (end 194.240836 75.797886) (width 0.09) (layer "In5.Cu") (net 329))
  (segment (start 197.75944 68.3435) (end 207.97944 68.3435) (width 0.127) (layer "In5.Cu") (net 329))
  (segment (start 212.714331 56.017271) (end 212.285669 56.017271) (width 0.127) (layer "In5.Cu") (net 329))
  (segment (start 194.240845 75.797877) (end 194.240845 75.567345) (width 0.09) (layer "In5.Cu") (net 329))
  (segment (start 194.655836 79.060008) (end 194.300836 78.705008) (width 0.09) (layer "In5.Cu") (net 329))
  (segment (start 194.2335 71.86944) (end 197.75944 68.3435) (width 0.127) (layer "In5.Cu") (net 329))
  (segment (start 212.877915 58.10543) (end 212.885161 58.098185) (width 0.127) (layer "In5.Cu") (net 329))
  (segment (start 213.238715 58.098185) (end 213.238716 58.098186) (width 0.127) (layer "In5.Cu") (net 329))
  (segment (start 213.23147 58.458985) (end 213.231469 58.458986) (width 0.127) (layer "In5.Cu") (net 329))
  (segment (start 194.300836 78.705008) (end 194.300836 78.278235) (width 0.09) (layer "In5.Cu") (net 329))
  (segment (start 207.97944 68.3435) (end 213.5935 62.72944) (width 0.127) (layer "In5.Cu") (net 329))
  (segment (start 212.917828 56.220768) (end 212.714331 56.017271) (width 0.127) (layer "In5.Cu") (net 329))
  (segment (start 194.300836 78.278235) (end 194.240836 78.218235) (width 0.09) (layer "In5.Cu") (net 329))
  (segment (start 212.736328 56.63501) (end 212.917828 56.45351) (width 0.127) (layer "In5.Cu") (net 329))
  (segment (start 213.238715 58.451739) (end 213.23147 58.458985) (width 0.127) (layer "In5.Cu") (net 329))
  (segment (start 213.5935 59.174569) (end 213.5935 62.72944) (width 0.127) (layer "In5.Cu") (net 329))
  (segment (start 212.917828 56.45351) (end 212.917828 56.220768) (width 0.127) (layer "In5.Cu") (net 329))
  (arc (start 213.231469 58.458986) (mid 213.158246 58.635763) (end 213.23147 58.812539) (width 0.127) (layer "In5.Cu") (net 329))
  (arc (start 194.5835 75.0065) (mid 194.532244 74.882756) (end 194.4085 74.8315) (width 0.127) (layer "In5.Cu") (net 329))
  (arc (start 212.885162 58.098184) (mid 213.061939 58.024961) (end 213.238715 58.098185) (width 0.127) (layer "In5.Cu") (net 329))
  (arc (start 212.524362 58.105431) (mid 212.701139 58.178654) (end 212.877915 58.10543) (width 0.127) (layer "In5.Cu") (net 329))
  (arc (start 194.2335 75.3565) (mid 194.284756 75.232756) (end 194.4085 75.1815) (width 0.127) (layer "In5.Cu") (net 329))
  (arc (start 213.238716 58.098186) (mid 213.311939 58.274963) (end 213.238715 58.451739) (width 0.127) (layer "In5.Cu") (net 329))
  (arc (start 194.4085 75.1815) (mid 194.532244 75.130244) (end 194.5835 75.0065) (width 0.127) (layer "In5.Cu") (net 329))
  (arc (start 194.4085 74.8315) (mid 194.284756 74.780244) (end 194.2335 74.6565) (width 0.127) (layer "In5.Cu") (net 329))
  (segment (start 180.136328 78.560008) (end 179.636328 78.060008) (width 0.127) (layer "F.Cu") (net 330))
  (segment (start 156.536328 59.660008) (end 156.536328 60.960008) (width 0.1) (layer "F.Cu") (net 330))
  (segment (start 179.636328 78.060008) (end 179.636328 78.0405) (width 0.127) (layer "F.Cu") (net 330))
  (via blind (at 156.536328 60.960008) (size 0.5) (drill 0.2) (layers "F.Cu" "In5.Cu") (net 330))
  (via blind (at 179.636328 78.0405) (size 0.5) (drill 0.2) (layers "F.Cu" "In5.Cu") (net 330))
  (segment (start 179.575008 77.6855) (end 179.290438 77.6855) (width 0.09) (layer "In5.Cu") (net 330))
  (segment (start 178.942933 75.538696) (end 178.942933 74.115873) (width 0.127) (layer "In5.Cu") (net 330))
  (segment (start 156.817828 62.570768) (end 156.817828 61.241508) (width 0.127) (layer "In5.Cu") (net 330))
  (segment (start 178.942933 74.115873) (end 175.17056 70.3435) (width 0.127) (layer "In5.Cu") (net 330))
  (segment (start 179.290438 77.6855) (end 178.938167 77.333229) (width 0.09) (layer "In5.Cu") (net 330))
  (segment (start 173.194 69.424144) (end 173.194 69.85) (width 0.127) (layer "In5.Cu") (net 330))
  (segment (start 173.607 70.975856) (end 173.607 69.424144) (width 0.127) (layer "In5.Cu") (net 330))
  (segment (start 168.04056 70.3435) (end 172.7005 70.3435) (width 0.127) (layer "In5.Cu") (net 330))
  (segment (start 179.636328 77.74682) (end 179.575008 77.6855) (width 0.09) (layer "In5.Cu") (net 330))
  (segment (start 178.938167 75.543462) (end 178.942933 75.538696) (width 0.09) (layer "In5.Cu") (net 330))
  (segment (start 168.04056 70.3435) (end 163.84056 66.1435) (width 0.127) (layer "In5.Cu") (net 330))
  (segment (start 175.17056 70.3435) (end 174.8005 70.3435) (width 0.127) (layer "In5.Cu") (net 330))
  (segment (start 179.636328 78.0405) (end 179.636328 77.74682) (width 0.09) (layer "In5.Cu") (net 330))
  (segment (start 160.39056 66.1435) (end 156.817828 62.570768) (width 0.127) (layer "In5.Cu") (net 330))
  (segment (start 163.84056 66.1435) (end 160.39056 66.1435) (width 0.127) (layer "In5.Cu") (net 330))
  (segment (start 178.938167 77.333229) (end 178.938167 75.543462) (width 0.09) (layer "In5.Cu") (net 330))
  (segment (start 156.817828 61.241508) (end 156.536328 60.960008) (width 0.127) (layer "In5.Cu") (net 330))
  (segment (start 174.594 70.55) (end 174.594 70.975856) (width 0.127) (layer "In5.Cu") (net 330))
  (arc (start 173.194 69.85) (mid 173.049457 70.198957) (end 172.7005 70.3435) (width 0.127) (layer "In5.Cu") (net 330))
  (arc (start 174.594 70.975856) (mid 174.449457 71.324813) (end 174.1005 71.469356) (width 0.127) (layer "In5.Cu") (net 330))
  (arc (start 174.1005 71.469356) (mid 173.751543 71.324813) (end 173.607 70.975856) (width 0.127) (layer "In5.Cu") (net 330))
  (arc (start 173.4005 69.217644) (mid 173.254482 69.278126) (end 173.194 69.424144) (width 0.127) (layer "In5.Cu") (net 330))
  (arc (start 174.8005 70.3435) (mid 174.654482 70.403982) (end 174.594 70.55) (width 0.127) (layer "In5.Cu") (net 330))
  (arc (start 173.607 69.424144) (mid 173.546518 69.278126) (end 173.4005 69.217644) (width 0.127) (layer "In5.Cu") (net 330))
  (segment (start 182.136328 79.560008) (end 181.636328 79.060008) (width 0.127) (layer "F.Cu") (net 331))
  (segment (start 158.136328 56.63501) (end 157.974828 56.47351) (width 0.127) (layer "F.Cu") (net 331))
  (segment (start 157.974828 56.47351) (end 157.974828 55.936508) (width 0.127) (layer "F.Cu") (net 331))
  (segment (start 158.236328 55.675008) (end 158.236328 55.060008) (width 0.127) (layer "F.Cu") (net 331))
  (segment (start 157.974828 55.936508) (end 158.236328 55.675008) (width 0.127) (layer "F.Cu") (net 331))
  (via blind (at 181.636328 79.060008) (size 0.5) (drill 0.2) (layers "F.Cu" "In5.Cu") (net 331))
  (via blind (at 158.136328 56.63501) (size 0.5) (drill 0.2) (layers "F.Cu" "In5.Cu") (net 331))
  (segment (start 167.84056 68.6435) (end 175.04056 68.6435) (width 0.127) (layer "In5.Cu") (net 331))
  (segment (start 181.180054 78.705008) (end 181.577664 78.705008) (width 0.09) (layer "In5.Cu") (net 331))
  (segment (start 180.503692 78.898754) (end 180.986308 78.898754) (width 0.09) (layer "In5.Cu") (net 331))
  (segment (start 175.04056 68.6435) (end 180.0465 73.64944) (width 0.127) (layer "In5.Cu") (net 331))
  (segment (start 156.88056 55.8265) (end 156.6165 56.09056) (width 0.127) (layer "In5.Cu") (net 331))
  (segment (start 157.954828 56.45351) (end 157.954828 56.171888) (width 0.127) (layer "In5.Cu") (net 331))
  (segment (start 158.136328 56.63501) (end 157.954828 56.45351) (width 0.127) (layer "In5.Cu") (net 331))
  (segment (start 181.636328 78.763672) (end 181.636328 79.060008) (width 0.09) (layer "In5.Cu") (net 331))
  (segment (start 180.986308 78.898754) (end 181.180054 78.705008) (width 0.09) (layer "In5.Cu") (net 331))
  (segment (start 164.07056 64.8735) (end 167.84056 68.6435) (width 0.127) (layer "In5.Cu") (net 331))
  (segment (start 156.6165 57.749395) (end 158.2065 59.339395) (width 0.127) (layer "In5.Cu") (net 331))
  (segment (start 181.577664 78.705008) (end 181.636328 78.763672) (width 0.09) (layer "In5.Cu") (net 331))
  (segment (start 157.954828 56.171888) (end 157.60944 55.8265) (width 0.127) (layer "In5.Cu") (net 331))
  (segment (start 180.0465 73.64944) (end 180.0465 75.54) (width 0.127) (layer "In5.Cu") (net 331))
  (segment (start 180.051318 75.544818) (end 180.051318 75.82) (width 0.09) (layer "In5.Cu") (net 331))
  (segment (start 180.051328 75.82001) (end 180.051328 78.44639) (width 0.09) (layer "In5.Cu") (net 331))
  (segment (start 157.60944 55.8265) (end 156.88056 55.8265) (width 0.127) (layer "In5.Cu") (net 331))
  (segment (start 180.051318 75.82) (end 180.051328 75.82001) (width 0.09) (layer "In5.Cu") (net 331))
  (segment (start 158.2065 62.44944) (end 160.63056 64.8735) (width 0.127) (layer "In5.Cu") (net 331))
  (segment (start 180.051328 78.44639) (end 180.503692 78.898754) (width 0.09) (layer "In5.Cu") (net 331))
  (segment (start 156.6165 56.09056) (end 156.6165 57.749395) (width 0.127) (layer "In5.Cu") (net 331))
  (segment (start 160.63056 64.8735) (end 164.07056 64.8735) (width 0.127) (layer "In5.Cu") (net 331))
  (segment (start 180.0465 75.54) (end 180.051318 75.544818) (width 0.09) (layer "In5.Cu") (net 331))
  (segment (start 158.2065 59.339395) (end 158.2065 62.44944) (width 0.127) (layer "In5.Cu") (net 331))
  (segment (start 157.386328 59.660008) (end 157.386328 60.960008) (width 0.1) (layer "F.Cu") (net 332))
  (segment (start 180.136328 77.560008) (end 179.636328 77.060008) (width 0.127) (layer "F.Cu") (net 332))
  (segment (start 179.636328 77.060008) (end 179.636328 77.0405) (width 0.127) (layer "F.Cu") (net 332))
  (via blind (at 179.636328 77.0405) (size 0.5) (drill 0.2) (layers "F.Cu" "In5.Cu") (net 332))
  (via blind (at 157.386328 60.960008) (size 0.5) (drill 0.2) (layers "F.Cu" "In5.Cu") (net 332))
  (segment (start 179.229933 75.538696) (end 179.229933 75.337067) (width 0.127) (layer "In5.Cu") (net 332))
  (segment (start 173.894 70.975856) (end 173.894 69.424144) (width 0.127) (layer "In5.Cu") (net 332))
  (segment (start 157.104828 61.241508) (end 157.386328 60.960008) (width 0.127) (layer "In5.Cu") (net 332))
  (segment (start 179.636328 77.0405) (end 179.636328 77.314164) (width 0.09) (layer "In5.Cu") (net 332))
  (segment (start 174.307 70.55) (end 174.307 70.975856) (width 0.127) (layer "In5.Cu") (net 332))
  (segment (start 179.585936 74.812067) (end 179.404933 74.812067) (width 0.127) (layer "In5.Cu") (net 332))
  (segment (start 179.554992 77.3955) (end 179.410562 77.3955) (width 0.09) (layer "In5.Cu") (net 332))
  (segment (start 179.636328 77.314164) (end 179.554992 77.3955) (width 0.09) (layer "In5.Cu") (net 332))
  (segment (start 175.28944 70.0565) (end 174.8005 70.0565) (width 0.127) (layer "In5.Cu") (net 332))
  (segment (start 163.95944 65.8565) (end 160.50944 65.8565) (width 0.127) (layer "In5.Cu") (net 332))
  (segment (start 179.229933 74.637067) (end 179.229933 73.996993) (width 0.127) (layer "In5.Cu") (net 332))
  (segment (start 179.404933 75.162067) (end 179.585936 75.162067) (width 0.127) (layer "In5.Cu") (net 332))
  (segment (start 157.104828 62.451888) (end 157.104828 61.241508) (width 0.127) (layer "In5.Cu") (net 332))
  (segment (start 172.907 69.424144) (end 172.907 69.85) (width 0.127) (layer "In5.Cu") (net 332))
  (segment (start 160.50944 65.8565) (end 157.104828 62.451888) (width 0.127) (layer "In5.Cu") (net 332))
  (segment (start 168.15944 70.0565) (end 163.95944 65.8565) (width 0.127) (layer "In5.Cu") (net 332))
  (segment (start 168.15944 70.0565) (end 172.7005 70.0565) (width 0.127) (layer "In5.Cu") (net 332))
  (segment (start 179.228167 77.213105) (end 179.228167 75.540462) (width 0.09) (layer "In5.Cu") (net 332))
  (segment (start 179.228167 75.540462) (end 179.229933 75.538696) (width 0.09) (layer "In5.Cu") (net 332))
  (segment (start 179.229933 73.996993) (end 175.28944 70.0565) (width 0.127) (layer "In5.Cu") (net 332))
  (segment (start 179.410562 77.3955) (end 179.228167 77.213105) (width 0.09) (layer "In5.Cu") (net 332))
  (arc (start 179.585936 75.162067) (mid 179.70968 75.110811) (end 179.760936 74.987067) (width 0.127) (layer "In5.Cu") (net 332))
  (arc (start 179.229933 75.337067) (mid 179.281189 75.213323) (end 179.404933 75.162067) (width 0.127) (layer "In5.Cu") (net 332))
  (arc (start 172.907 69.85) (mid 172.846518 69.996018) (end 172.7005 70.0565) (width 0.127) (layer "In5.Cu") (net 332))
  (arc (start 174.307 70.975856) (mid 174.246518 71.121874) (end 174.1005 71.182356) (width 0.127) (layer "In5.Cu") (net 332))
  (arc (start 174.1005 71.182356) (mid 173.954482 71.121874) (end 173.894 70.975856) (width 0.127) (layer "In5.Cu") (net 332))
  (arc (start 179.404933 74.812067) (mid 179.281189 74.760811) (end 179.229933 74.637067) (width 0.127) (layer "In5.Cu") (net 332))
  (arc (start 179.760936 74.987067) (mid 179.70968 74.863323) (end 179.585936 74.812067) (width 0.127) (layer "In5.Cu") (net 332))
  (arc (start 173.894 69.424144) (mid 173.749457 69.075187) (end 173.4005 68.930644) (width 0.127) (layer "In5.Cu") (net 332))
  (arc (start 173.4005 68.930644) (mid 173.051543 69.075187) (end 172.907 69.424144) (width 0.127) (layer "In5.Cu") (net 332))
  (arc (start 174.8005 70.0565) (mid 174.451543 70.201043) (end 174.307 70.55) (width 0.127) (layer "In5.Cu") (net 332))
  (segment (start 157.647828 55.936508) (end 157.386328 55.675008) (width 0.127) (layer "F.Cu") (net 333))
  (segment (start 157.647828 56.47351) (end 157.647828 55.936508) (width 0.127) (layer "F.Cu") (net 333))
  (segment (start 157.386328 55.675008) (end 157.386328 55.060008) (width 0.127) (layer "F.Cu") (net 333))
  (segment (start 157.486328 56.63501) (end 157.647828 56.47351) (width 0.127) (layer "F.Cu") (net 333))
  (segment (start 182.136328 78.560008) (end 181.636328 78.060008) (width 0.127) (layer "F.Cu") (net 333))
  (via blind (at 181.636328 78.060008) (size 0.5) (drill 0.2) (layers "F.Cu" "In5.Cu") (net 333))
  (via blind (at 157.486328 56.63501) (size 0.5) (drill 0.2) (layers "F.Cu" "In5.Cu") (net 333))
  (segment (start 157.810377 58.331907) (end 157.796021 58.34626) (width 0.127) (layer "In5.Cu") (net 333))
  (segment (start 175.15944 68.3565) (end 180.3335 73.53056) (width 0.127) (layer "In5.Cu") (net 333))
  (segment (start 156.9035 57.630515) (end 157.44247 58.169485) (width 0.127) (layer "In5.Cu") (net 333))
  (segment (start 181.636328 78.363672) (end 181.636328 78.060008) (width 0.09) (layer "In5.Cu") (net 333))
  (segment (start 180.341309 75.820009) (end 180.341309 78.326247) (width 0.09) (layer "In5.Cu") (net 333))
  (segment (start 157.796021 58.523036) (end 158.4935 59.220515) (width 0.127) (layer "In5.Cu") (net 333))
  (segment (start 180.341318 75.547818) (end 180.341318 75.82) (width 0.09) (layer "In5.Cu") (net 333))
  (segment (start 180.623816 78.608754) (end 180.866184 78.608754) (width 0.09) (layer "In5.Cu") (net 333))
  (segment (start 157.667828 56.45351) (end 157.667828 56.290768) (width 0.127) (layer "In5.Cu") (net 333))
  (segment (start 181.05993 78.415008) (end 181.584992 78.415008) (width 0.09) (layer "In5.Cu") (net 333))
  (segment (start 158.4935 59.220515) (end 158.4935 62.33056) (width 0.127) (layer "In5.Cu") (net 333))
  (segment (start 164.18944 64.5865) (end 167.95944 68.3565) (width 0.127) (layer "In5.Cu") (net 333))
  (segment (start 158.4935 62.33056) (end 160.74944 64.5865) (width 0.127) (layer "In5.Cu") (net 333))
  (segment (start 180.866184 78.608754) (end 181.05993 78.415008) (width 0.09) (layer "In5.Cu") (net 333))
  (segment (start 156.99944 56.1135) (end 156.9035 56.20944) (width 0.127) (layer "In5.Cu") (net 333))
  (segment (start 156.9035 56.20944) (end 156.9035 57.630515) (width 0.127) (layer "In5.Cu") (net 333))
  (segment (start 180.341309 78.326247) (end 180.623816 78.608754) (width 0.09) (layer "In5.Cu") (net 333))
  (segment (start 157.49056 56.1135) (end 156.99944 56.1135) (width 0.127) (layer "In5.Cu") (net 333))
  (segment (start 157.486328 56.63501) (end 157.667828 56.45351) (width 0.127) (layer "In5.Cu") (net 333))
  (segment (start 157.810378 58.155132) (end 157.810377 58.155131) (width 0.127) (layer "In5.Cu") (net 333))
  (segment (start 180.3335 73.53056) (end 180.3335 75.54) (width 0.127) (layer "In5.Cu") (net 333))
  (segment (start 180.341318 75.82) (end 180.341309 75.820009) (width 0.09) (layer "In5.Cu") (net 333))
  (segment (start 157.619247 58.169484) (end 157.619246 58.169485) (width 0.127) (layer "In5.Cu") (net 333))
  (segment (start 181.584992 78.415008) (end 181.636328 78.363672) (width 0.09) (layer "In5.Cu") (net 333))
  (segment (start 157.810376 58.331908) (end 157.810377 58.331907) (width 0.127) (layer "In5.Cu") (net 333))
  (segment (start 180.3335 75.54) (end 180.341318 75.547818) (width 0.09) (layer "In5.Cu") (net 333))
  (segment (start 157.796022 58.523037) (end 157.796021 58.523036) (width 0.127) (layer "In5.Cu") (net 333))
  (segment (start 157.667828 56.290768) (end 157.49056 56.1135) (width 0.127) (layer "In5.Cu") (net 333))
  (segment (start 157.619246 58.169485) (end 157.633601 58.155131) (width 0.127) (layer "In5.Cu") (net 333))
  (segment (start 160.74944 64.5865) (end 164.18944 64.5865) (width 0.127) (layer "In5.Cu") (net 333))
  (segment (start 167.95944 68.3565) (end 175.15944 68.3565) (width 0.127) (layer "In5.Cu") (net 333))
  (arc (start 157.633601 58.155131) (mid 157.72199 58.11852) (end 157.810378 58.155132) (width 0.127) (layer "In5.Cu") (net 333))
  (arc (start 157.796021 58.34626) (mid 157.75941 58.434649) (end 157.796022 58.523037) (width 0.127) (layer "In5.Cu") (net 333))
  (arc (start 157.44247 58.169485) (mid 157.530859 58.206096) (end 157.619247 58.169484) (width 0.127) (layer "In5.Cu") (net 333))
  (arc (start 157.810377 58.155131) (mid 157.846988 58.24352) (end 157.810376 58.331908) (width 0.127) (layer "In5.Cu") (net 333))
  (segment (start 179.136328 80.560008) (end 178.636328 80.060008) (width 0.127) (layer "F.Cu") (net 334))
  (segment (start 147.186328 59.660008) (end 147.186328 60.960008) (width 0.1) (layer "F.Cu") (net 334))
  (via blind (at 147.186328 60.960008) (size 0.5) (drill 0.2) (layers "F.Cu" "In2.Cu") (net 334))
  (via blind (at 178.636328 80.060008) (size 0.5) (drill 0.2) (layers "F.Cu" "In2.Cu") (net 334))
  (segment (start 150.124457 67.07752) (end 150.124455 67.077519) (width 0.143) (layer "In2.Cu") (net 334))
  (segment (start 173.64733 71.90455) (end 173.64733 71.904551) (width 0.143) (layer "In2.Cu") (net 334))
  (segment (start 150.513007 68.385848) (end 150.513008 68.385848) (width 0.143) (layer "In2.Cu") (net 334))
  (segment (start 149.135384 67.502322) (end 149.842322 66.795385) (width 0.143) (layer "In2.Cu") (net 334))
  (segment (start 148.745517 65.91142) (end 148.745517 65.911419) (width 0.143) (layer "In2.Cu") (net 334))
  (segment (start 149.770986 67.430986) (end 149.417517 67.784454) (width 0.143) (layer "In2.Cu") (net 334))
  (segment (start 171.68766 71.0605) (end 172.027963 71.400802) (width 0.143) (layer "In2.Cu") (net 334))
  (segment (start 174.565 76.98092) (end 175.065 77.48092) (width 0.1) (layer "In2.Cu") (net 334))
  (segment (start 173.576619 71.833839) (end 173.64733 71.90455) (width 0.143) (layer "In2.Cu") (net 334))
  (segment (start 149.135384 67.502323) (end 149.135384 67.502322) (width 0.143) (layer "In2.Cu") (net 334))
  (segment (start 173.64733 72.151331) (end 173.645546 72.151331) (width 0.143) (layer "In2.Cu") (net 334))
  (segment (start 174.2495 75.832363) (end 174.565 76.147863) (width 0.1) (layer "In2.Cu") (net 334))
  (segment (start 172.666505 72.497173) (end 173.329839 71.833839) (width 0.143) (layer "In2.Cu") (net 334))
  (segment (start 174.2495 75.5) (end 174.2495 75.832363) (width 0.1) (layer "In2.Cu") (net 334))
  (segment (start 178.636328 79.756328) (end 178.636328 80.060008) (width 0.1) (layer "In2.Cu") (net 334))
  (segment (start 173.72538 73.557838) (end 173.831799 73.451418) (width 0.143) (layer "In2.Cu") (net 334))
  (segment (start 148.78104 66.44104) (end 148.427571 66.794508) (width 0.143) (layer "In2.Cu") (net 334))
  (segment (start 148.427571 67.501446) (end 148.428447 67.502322) (width 0.143) (layer "In2.Cu") (net 334))
  (segment (start 153.18766 71.0605) (end 171.68766 71.0605) (width 0.143) (layer "In2.Cu") (net 334))
  (segment (start 172.027963 71.647582) (end 171.921545 71.754003) (width 0.143) (layer "In2.Cu") (net 334))
  (segment (start 149.133195 65.805) (end 149.133195 65.804999) (width 0.143) (layer "In2.Cu") (net 334))
  (segment (start 175.065 77.48092) (end 175.065 78.45592) (width 0.1) (layer "In2.Cu") (net 334))
  (segment (start 171.992255 72.497172) (end 171.992257 72.497173) (width 0.143) (layer "In2.Cu") (net 334))
  (segment (start 175.065 78.45592) (end 176.34408 79.735) (width 0.1) (layer "In2.Cu") (net 334))
  (segment (start 147.186328 60.960008) (end 147.460827 61.234507) (width 0.143) (layer "In2.Cu") (net 334))
  (segment (start 174.565 76.147863) (end 174.565 76.98092) (width 0.1) (layer "In2.Cu") (net 334))
  (segment (start 150.12533 68.492269) (end 150.12533 68.492268) (width 0.143) (layer "In2.Cu") (net 334))
  (segment (start 150.12533 68.492268) (end 150.231749 68.385848) (width 0.143) (layer "In2.Cu") (net 334))
  (segment (start 173.05292 73.557837) (end 173.052922 73.557838) (width 0.143) (layer "In2.Cu") (net 334))
  (segment (start 150.12358 66.795385) (end 150.124456 66.796261) (width 0.143) (layer "In2.Cu") (net 334))
  (segment (start 149.770987 67.430988) (end 149.770986 67.430986) (width 0.143) (layer "In2.Cu") (net 334))
  (segment (start 173.645546 72.151331) (end 172.982209 72.814668) (width 0.143) (layer "In2.Cu") (net 334))
  (segment (start 149.134072 66.087134) (end 149.134072 66.087135) (width 0.143) (layer "In2.Cu") (net 334))
  (segment (start 172.664715 72.497173) (end 172.666505 72.497173) (width 0.143) (layer "In2.Cu") (net 334))
  (segment (start 176.34408 79.735) (end 177.39887 79.735) (width 0.1) (layer "In2.Cu") (net 334))
  (segment (start 171.921544 72.426461) (end 171.992255 72.497172) (width 0.143) (layer "In2.Cu") (net 334))
  (segment (start 150.513008 68.385848) (end 153.18766 71.0605) (width 0.143) (layer "In2.Cu") (net 334))
  (segment (start 174.078579 73.451418) (end 174.2495 73.62234) (width 0.143) (layer "In2.Cu") (net 334))
  (segment (start 177.39887 79.735) (end 177.446087 79.687783) (width 0.1) (layer "In2.Cu") (net 334))
  (segment (start 171.921545 71.754003) (end 171.921544 71.754003) (width 0.143) (layer "In2.Cu") (net 334))
  (segment (start 147.460827 65.333667) (end 148.038579 65.911418) (width 0.143) (layer "In2.Cu") (net 334))
  (segment (start 172.982209 73.487126) (end 173.05292 73.557837) (width 0.143) (layer "In2.Cu") (net 334))
  (segment (start 178.567783 79.687783) (end 178.636328 79.756328) (width 0.1) (layer "In2.Cu") (net 334))
  (segment (start 149.134072 66.087135) (end 148.780602 66.440602) (width 0.143) (layer "In2.Cu") (net 334))
  (segment (start 147.460827 61.234507) (end 147.460827 65.333667) (width 0.143) (layer "In2.Cu") (net 334))
  (segment (start 149.133195 65.804999) (end 149.134071 65.805875) (width 0.143) (layer "In2.Cu") (net 334))
  (segment (start 148.780602 66.440602) (end 148.78104 66.44104) (width 0.143) (layer "In2.Cu") (net 334))
  (segment (start 174.2495 73.62234) (end 174.2495 75.5) (width 0.143) (layer "In2.Cu") (net 334))
  (segment (start 149.417517 68.491392) (end 149.418393 68.492268) (width 0.143) (layer "In2.Cu") (net 334))
  (segment (start 148.745517 65.911419) (end 148.851937 65.805) (width 0.143) (layer "In2.Cu") (net 334))
  (segment (start 177.446087 79.687783) (end 178.567783 79.687783) (width 0.1) (layer "In2.Cu") (net 334))
  (segment (start 150.124455 67.077519) (end 149.770987 67.430988) (width 0.143) (layer "In2.Cu") (net 334))
  (arc (start 148.427571 66.794508) (mid 148.281159 67.147977) (end 148.427571 67.501446) (width 0.143) (layer "In2.Cu") (net 334))
  (arc (start 149.418393 68.492268) (mid 149.771861 68.63868) (end 150.12533 68.492269) (width 0.143) (layer "In2.Cu") (net 334))
  (arc (start 148.428447 67.502322) (mid 148.781915 67.648734) (end 149.135384 67.502323) (width 0.143) (layer "In2.Cu") (net 334))
  (arc (start 148.851937 65.805) (mid 148.992565 65.746749) (end 149.133195 65.805) (width 0.143) (layer "In2.Cu") (net 334))
  (arc (start 173.831799 73.451418) (mid 173.955189 73.400308) (end 174.078579 73.451418) (width 0.143) (layer "In2.Cu") (net 334))
  (arc (start 149.842322 66.795385) (mid 149.98295 66.737134) (end 150.12358 66.795385) (width 0.143) (layer "In2.Cu") (net 334))
  (arc (start 171.921544 71.754003) (mid 171.782273 72.090232) (end 171.921544 72.426461) (width 0.143) (layer "In2.Cu") (net 334))
  (arc (start 148.038579 65.911418) (mid 148.392048 66.05783) (end 148.745517 65.91142) (width 0.143) (layer "In2.Cu") (net 334))
  (arc (start 173.64733 71.904551) (mid 173.69844 72.027941) (end 173.64733 72.151331) (width 0.143) (layer "In2.Cu") (net 334))
  (arc (start 173.329839 71.833839) (mid 173.453229 71.782729) (end 173.576619 71.833839) (width 0.143) (layer "In2.Cu") (net 334))
  (arc (start 149.134071 65.805875) (mid 149.192322 65.946504) (end 149.134072 66.087134) (width 0.143) (layer "In2.Cu") (net 334))
  (arc (start 149.417517 67.784454) (mid 149.271105 68.137923) (end 149.417517 68.491392) (width 0.143) (layer "In2.Cu") (net 334))
  (arc (start 171.992257 72.497173) (mid 172.328486 72.636444) (end 172.664715 72.497173) (width 0.143) (layer "In2.Cu") (net 334))
  (arc (start 172.982209 72.814668) (mid 172.842938 73.150897) (end 172.982209 73.487126) (width 0.143) (layer "In2.Cu") (net 334))
  (arc (start 172.027963 71.400802) (mid 172.079073 71.524192) (end 172.027963 71.647582) (width 0.143) (layer "In2.Cu") (net 334))
  (arc (start 173.052922 73.557838) (mid 173.389151 73.697109) (end 173.72538 73.557838) (width 0.143) (layer "In2.Cu") (net 334))
  (arc (start 150.124456 66.796261) (mid 150.182707 66.93689) (end 150.124457 67.07752) (width 0.143) (layer "In2.Cu") (net 334))
  (arc (start 150.231749 68.385848) (mid 150.372378 68.327598) (end 150.513007 68.385848) (width 0.143) (layer "In2.Cu") (net 334))
  (segment (start 177.136328 79.560008) (end 176.636328 79.060008) (width 0.127) (layer "F.Cu") (net 335))
  (segment (start 148.886328 55.675008) (end 148.886328 55.060008) (width 0.143) (layer "F.Cu") (net 335))
  (segment (start 176.636328 79.060008) (end 176.636328 79.0405) (width 0.127) (layer "F.Cu") (net 335))
  (segment (start 148.632828 56.48151) (end 148.632828 55.928508) (width 0.143) (layer "F.Cu") (net 335))
  (segment (start 148.786328 56.63501) (end 148.632828 56.48151) (width 0.143) (layer "F.Cu") (net 335))
  (segment (start 148.632828 55.928508) (end 148.886328 55.675008) (width 0.143) (layer "F.Cu") (net 335))
  (via blind (at 148.786328 56.63501) (size 0.5) (drill 0.2) (layers "F.Cu" "In2.Cu") (net 335))
  (via blind (at 176.636328 79.0405) (size 0.5) (drill 0.2) (layers "F.Cu" "In2.Cu") (net 335))
  (segment (start 148.611829 55.861829) (end 148.611829 56.460511) (width 0.143) (layer "In2.Cu") (net 335))
  (segment (start 175.733 78.12392) (end 176.29458 78.6855) (width 0.1) (layer "In2.Cu") (net 335))
  (segment (start 148.70324 57.980739) (end 148.496798 58.18718) (width 0.143) (layer "In2.Cu") (net 335))
  (segment (start 175.7195 72.81234) (end 172.65766 69.7505) (width 0.143) (layer "In2.Cu") (net 335))
  (segment (start 148.74358 58.433961) (end 148.950021 58.227519) (width 0.143) (layer "In2.Cu") (net 335))
  (segment (start 148.70324 57.980738) (end 148.70324 57.980739) (width 0.143) (layer "In2.Cu") (net 335))
  (segment (start 172.65766 69.7505) (end 154.14766 69.7505) (width 0.143) (layer "In2.Cu") (net 335))
  (segment (start 176.636328 78.761328) (end 176.636328 79.0405) (width 0.1) (layer "In2.Cu") (net 335))
  (segment (start 176.5605 78.6855) (end 176.636328 78.761328) (width 0.1) (layer "In2.Cu") (net 335))
  (segment (start 175.7195 75.502022) (end 175.7195 72.81234) (width 0.143) (layer "In2.Cu") (net 335))
  (segment (start 154.14766 69.7505) (end 148.9095 64.51234) (width 0.143) (layer "In2.Cu") (net 335))
  (segment (start 148.9095 59.27234) (end 148.74358 59.106419) (width 0.143) (layer "In2.Cu") (net 335))
  (segment (start 175.733 76.567076) (end 175.733 78.12392) (width 0.1) (layer "In2.Cu") (net 335))
  (segment (start 175.7195 75.502022) (end 175.729906 75.512428) (width 0.1) (layer "In2.Cu") (net 335))
  (segment (start 176.29458 78.6855) (end 176.5605 78.6855) (width 0.1) (layer "In2.Cu") (net 335))
  (segment (start 147.824339 58.187179) (end 147.82434 58.18718) (width 0.143) (layer "In2.Cu") (net 335))
  (segment (start 147.291648 55.595512) (end 148.345512 55.595512) (width 0.143) (layer "In2.Cu") (net 335))
  (segment (start 146.78669 56.10047) (end 147.291648 55.595512) (width 0.143) (layer "In2.Cu") (net 335))
  (segment (start 148.345512 55.595512) (end 148.611829 55.861829) (width 0.143) (layer "In2.Cu") (net 335))
  (segment (start 148.611829 56.460511) (end 148.786328 56.63501) (width 0.143) (layer "In2.Cu") (net 335))
  (segment (start 175.729906 76.563982) (end 175.733 76.567076) (width 0.1) (layer "In2.Cu") (net 335))
  (segment (start 146.78669 57.14953) (end 146.78669 56.10047) (width 0.143) (layer "In2.Cu") (net 335))
  (segment (start 148.9095 64.51234) (end 148.9095 59.27234) (width 0.143) (layer "In2.Cu") (net 335))
  (segment (start 147.82434 58.18718) (end 146.78669 57.14953) (width 0.143) (layer "In2.Cu") (net 335))
  (segment (start 175.729906 75.512428) (end 175.729906 76.563982) (width 0.1) (layer "In2.Cu") (net 335))
  (arc (start 148.950021 57.980739) (mid 148.826631 57.929628) (end 148.70324 57.980738) (width 0.143) (layer "In2.Cu") (net 335))
  (arc (start 148.950021 58.227519) (mid 149.001131 58.104129) (end 148.950021 57.980739) (width 0.143) (layer "In2.Cu") (net 335))
  (arc (start 148.496798 58.18718) (mid 148.160568 58.32645) (end 147.824339 58.187179) (width 0.143) (layer "In2.Cu") (net 335))
  (arc (start 148.74358 59.106419) (mid 148.604309 58.77019) (end 148.74358 58.433961) (width 0.143) (layer "In2.Cu") (net 335))
  (segment (start 148.036328 59.660008) (end 148.036328 60.960008) (width 0.1) (layer "F.Cu") (net 336))
  (segment (start 179.136328 79.560008) (end 178.636328 79.060008) (width 0.127) (layer "F.Cu") (net 336))
  (segment (start 178.636328 79.060008) (end 178.636328 79.0405) (width 0.127) (layer "F.Cu") (net 336))
  (via blind (at 148.036328 60.960008) (size 0.5) (drill 0.2) (layers "F.Cu" "In2.Cu") (net 336))
  (via blind (at 178.636328 79.0405) (size 0.5) (drill 0.2) (layers "F.Cu" "In2.Cu") (net 336))
  (segment (start 148.993441 66.653441) (end 148.993879 66.653879) (width 0.143) (layer "In2.Cu") (net 336))
  (segment (start 148.922546 67.289482) (end 149.62948 66.582543) (width 0.143) (layer "In2.Cu") (net 336))
  (segment (start 148.640411 67.288606) (end 148.641287 67.289482) (width 0.143) (layer "In2.Cu") (net 336))
  (segment (start 172.451876 72.284334) (end 172.453665 72.284334) (width 0.143) (layer "In2.Cu") (net 336))
  (segment (start 171.81234 70.7595) (end 172.240803 71.187965) (width 0.143) (layer "In2.Cu") (net 336))
  (segment (start 150.337295 67.290357) (end 149.983827 67.643826) (width 0.143) (layer "In2.Cu") (net 336))
  (segment (start 149.346911 66.299973) (end 149.346911 66.299974) (width 0.143) (layer "In2.Cu") (net 336))
  (segment (start 177.334258 79.417802) (end 178.593198 79.417802) (width 0.1) (layer "In2.Cu") (net 336))
  (segment (start 148.532678 65.69858) (end 148.639098 65.592161) (width 0.143) (layer "In2.Cu") (net 336))
  (segment (start 172.453665 72.284334) (end 173.117 71.621) (width 0.143) (layer "In2.Cu") (net 336))
  (segment (start 150.33642 66.582545) (end 150.337296 66.583421) (width 0.143) (layer "In2.Cu") (net 336))
  (segment (start 178.636328 79.374672) (end 178.636328 79.0405) (width 0.1) (layer "In2.Cu") (net 336))
  (segment (start 148.922546 67.289483) (end 148.922546 67.289482) (width 0.143) (layer "In2.Cu") (net 336))
  (segment (start 149.983827 67.643826) (end 149.983825 67.643825) (width 0.143) (layer "In2.Cu") (net 336))
  (segment (start 174.5505 75.801111) (end 174.835 76.085611) (width 0.1) (layer "In2.Cu") (net 336))
  (segment (start 173.789458 71.621) (end 173.860169 71.691711) (width 0.143) (layer "In2.Cu") (net 336))
  (segment (start 149.346035 65.59216) (end 149.346034 65.59216) (width 0.143) (layer "In2.Cu") (net 336))
  (segment (start 172.134383 72.213622) (end 172.205094 72.284333) (width 0.143) (layer "In2.Cu") (net 336))
  (segment (start 174.5505 75.5) (end 174.5505 75.801111) (width 0.1) (layer "In2.Cu") (net 336))
  (segment (start 176.45592 79.465) (end 177.287059 79.465) (width 0.1) (layer "In2.Cu") (net 336))
  (segment (start 150.725848 68.173008) (end 153.31234 70.7595) (width 0.143) (layer "In2.Cu") (net 336))
  (segment (start 174.291418 73.238579) (end 174.5505 73.49766) (width 0.143) (layer "In2.Cu") (net 336))
  (segment (start 149.912492 68.279429) (end 149.912492 68.279428) (width 0.143) (layer "In2.Cu") (net 336))
  (segment (start 172.240803 71.860423) (end 172.134383 71.966842) (width 0.143) (layer "In2.Cu") (net 336))
  (segment (start 149.912492 68.279428) (end 150.018911 68.173008) (width 0.143) (layer "In2.Cu") (net 336))
  (segment (start 150.337297 67.290358) (end 150.337295 67.290357) (width 0.143) (layer "In2.Cu") (net 336))
  (segment (start 153.31234 70.7595) (end 171.81234 70.7595) (width 0.143) (layer "In2.Cu") (net 336))
  (segment (start 150.725848 68.173007) (end 150.725848 68.173008) (width 0.143) (layer "In2.Cu") (net 336))
  (segment (start 173.19505 73.274288) (end 173.265761 73.344999) (width 0.143) (layer "In2.Cu") (net 336))
  (segment (start 174.835 76.86908) (end 175.335 77.36908) (width 0.1) (layer "In2.Cu") (net 336))
  (segment (start 149.346911 66.299974) (end 148.993441 66.653441) (width 0.143) (layer "In2.Cu") (net 336))
  (segment (start 149.630357 68.278552) (end 149.631233 68.279428) (width 0.143) (layer "In2.Cu") (net 336))
  (segment (start 148.036328 60.960008) (end 147.761829 61.234507) (width 0.143) (layer "In2.Cu") (net 336))
  (segment (start 173.860169 72.36417) (end 173.196831 73.027508) (width 0.143) (layer "In2.Cu") (net 336))
  (segment (start 149.346034 65.59216) (end 149.34691 65.593036) (width 0.143) (layer "In2.Cu") (net 336))
  (segment (start 147.761829 65.208989) (end 148.251418 65.698579) (width 0.143) (layer "In2.Cu") (net 336))
  (segment (start 147.761829 61.234507) (end 147.761829 65.208989) (width 0.143) (layer "In2.Cu") (net 336))
  (segment (start 178.593198 79.417802) (end 178.636328 79.374672) (width 0.1) (layer "In2.Cu") (net 336))
  (segment (start 173.860169 71.691711) (end 173.860169 71.691712) (width 0.143) (layer "In2.Cu") (net 336))
  (segment (start 174.835 76.085611) (end 174.835 76.86908) (width 0.1) (layer "In2.Cu") (net 336))
  (segment (start 149.983825 67.643825) (end 149.630357 67.997294) (width 0.143) (layer "In2.Cu") (net 336))
  (segment (start 175.335 77.36908) (end 175.335 78.34408) (width 0.1) (layer "In2.Cu") (net 336))
  (segment (start 175.335 78.34408) (end 176.45592 79.465) (width 0.1) (layer "In2.Cu") (net 336))
  (segment (start 173.196831 73.027508) (end 173.19505 73.027508) (width 0.143) (layer "In2.Cu") (net 336))
  (segment (start 174.5505 73.49766) (end 174.5505 75.5) (width 0.143) (layer "In2.Cu") (net 336))
  (segment (start 172.205094 72.284333) (end 172.205096 72.284334) (width 0.143) (layer "In2.Cu") (net 336))
  (segment (start 148.993879 66.653879) (end 148.640411 67.007348) (width 0.143) (layer "In2.Cu") (net 336))
  (segment (start 173.512541 73.344999) (end 173.61896 73.238579) (width 0.143) (layer "In2.Cu") (net 336))
  (segment (start 177.287059 79.465) (end 177.334258 79.417802) (width 0.1) (layer "In2.Cu") (net 336))
  (segment (start 148.532678 65.698581) (end 148.532678 65.69858) (width 0.143) (layer "In2.Cu") (net 336))
  (arc (start 172.134383 71.966842) (mid 172.083273 72.090232) (end 172.134383 72.213622) (width 0.143) (layer "In2.Cu") (net 336))
  (arc (start 173.117 71.621) (mid 173.453229 71.481729) (end 173.789458 71.621) (width 0.143) (layer "In2.Cu") (net 336))
  (arc (start 173.19505 73.027508) (mid 173.14394 73.150898) (end 173.19505 73.274288) (width 0.143) (layer "In2.Cu") (net 336))
  (arc (start 149.34691 65.593036) (mid 149.493322 65.946504) (end 149.346911 66.299973) (width 0.143) (layer "In2.Cu") (net 336))
  (arc (start 150.018911 68.173008) (mid 150.372379 68.026596) (end 150.725848 68.173007) (width 0.143) (layer "In2.Cu") (net 336))
  (arc (start 173.265761 73.344999) (mid 173.389151 73.396109) (end 173.512541 73.344999) (width 0.143) (layer "In2.Cu") (net 336))
  (arc (start 172.240803 71.187965) (mid 172.380074 71.524194) (end 172.240803 71.860423) (width 0.143) (layer "In2.Cu") (net 336))
  (arc (start 173.61896 73.238579) (mid 173.955189 73.099308) (end 174.291418 73.238579) (width 0.143) (layer "In2.Cu") (net 336))
  (arc (start 148.640411 67.007348) (mid 148.582161 67.147977) (end 148.640411 67.288606) (width 0.143) (layer "In2.Cu") (net 336))
  (arc (start 150.337296 66.583421) (mid 150.483708 66.936889) (end 150.337297 67.290358) (width 0.143) (layer "In2.Cu") (net 336))
  (arc (start 148.639098 65.592161) (mid 148.992566 65.445749) (end 149.346035 65.59216) (width 0.143) (layer "In2.Cu") (net 336))
  (arc (start 149.630357 67.997294) (mid 149.572107 68.137923) (end 149.630357 68.278552) (width 0.143) (layer "In2.Cu") (net 336))
  (arc (start 148.641287 67.289482) (mid 148.781916 67.347733) (end 148.922546 67.289483) (width 0.143) (layer "In2.Cu") (net 336))
  (arc (start 149.631233 68.279428) (mid 149.771862 68.337679) (end 149.912492 68.279429) (width 0.143) (layer "In2.Cu") (net 336))
  (arc (start 149.62948 66.582543) (mid 149.98295 66.436132) (end 150.33642 66.582545) (width 0.143) (layer "In2.Cu") (net 336))
  (arc (start 172.205096 72.284334) (mid 172.328486 72.335444) (end 172.451876 72.284334) (width 0.143) (layer "In2.Cu") (net 336))
  (arc (start 148.251418 65.698579) (mid 148.392048 65.75683) (end 148.532678 65.698581) (width 0.143) (layer "In2.Cu") (net 336))
  (arc (start 173.860169 71.691712) (mid 173.99944 72.027941) (end 173.860169 72.36417) (width 0.143) (layer "In2.Cu") (net 336))
  (segment (start 148.136328 56.63501) (end 148.289828 56.48151) (width 0.143) (layer "F.Cu") (net 337))
  (segment (start 177.136328 78.560008) (end 177.136328 78.5405) (width 0.127) (layer "F.Cu") (net 337))
  (segment (start 148.289828 56.48151) (end 148.289828 55.928508) (width 0.143) (layer "F.Cu") (net 337))
  (segment (start 148.036328 55.675008) (end 148.036328 55.060008) (width 0.143) (layer "F.Cu") (net 337))
  (segment (start 177.136328 78.5405) (end 176.636328 78.0405) (width 0.127) (layer "F.Cu") (net 337))
  (segment (start 148.289828 55.928508) (end 148.036328 55.675008) (width 0.143) (layer "F.Cu") (net 337))
  (via blind (at 148.136328 56.63501) (size 0.5) (drill 0.2) (layers "F.Cu" "In2.Cu") (net 337))
  (via blind (at 176.636328 78.0405) (size 0.5) (drill 0.2) (layers "F.Cu" "In2.Cu") (net 337))
  (segment (start 176.0205 75.502022) (end 176.0205 72.68766) (width 0.143) (layer "In2.Cu") (net 337))
  (segment (start 176.149906 76.420094) (end 176.201094 76.420094) (width 0.1) (layer "In2.Cu") (net 337))
  (segment (start 172.78234 69.4495) (end 154.27234 69.4495) (width 0.143) (layer "In2.Cu") (net 337))
  (segment (start 147.95642 57.610737) (end 148.110671 57.456485) (width 0.143) (layer "In2.Cu") (net 337))
  (segment (start 149.162859 57.767899) (end 149.16286 57.7679) (width 0.143) (layer "In2.Cu") (net 337))
  (segment (start 147.827828 57.173641) (end 147.827828 57.173642) (width 0.143) (layer "In2.Cu") (net 337))
  (segment (start 175.999906 76.870094) (end 175.999906 76.920094) (width 0.1) (layer "In2.Cu") (net 337))
  (segment (start 148.956419 58.6468) (end 149.16286 58.440358) (width 0.143) (layer "In2.Cu") (net 337))
  (segment (start 148.110672 57.173642) (end 148.110671 57.173642) (width 0.143) (layer "In2.Cu") (net 337))
  (segment (start 148.310828 56.048668) (end 148.310827 56.460511) (width 0.143) (layer "In2.Cu") (net 337))
  (segment (start 176.636328 78.313672) (end 176.636328 78.0405) (width 0.1) (layer "In2.Cu") (net 337))
  (segment (start 149.2105 64.38766) (end 149.2105 59.14766) (width 0.143) (layer "In2.Cu") (net 337))
  (segment (start 148.037179 57.974341) (end 148.03718 57.974341) (width 0.143) (layer "In2.Cu") (net 337))
  (segment (start 148.490401 57.7679) (end 148.283959 57.974341) (width 0.143) (layer "In2.Cu") (net 337))
  (segment (start 176.0205 72.68766) (end 172.78234 69.4495) (width 0.143) (layer "In2.Cu") (net 337))
  (segment (start 176.149906 75.820094) (end 176.201094 75.820094) (width 0.1) (layer "In2.Cu") (net 337))
  (segment (start 147.827828 57.173642) (end 147.673576 57.327893) (width 0.143) (layer "In2.Cu") (net 337))
  (segment (start 154.27234 69.4495) (end 149.2105 64.38766) (width 0.143) (layer "In2.Cu") (net 337))
  (segment (start 147.390733 57.327894) (end 147.390733 57.327893) (width 0.143) (layer "In2.Cu") (net 337))
  (segment (start 176.0205 75.502022) (end 175.999906 75.522616) (width 0.1) (layer "In2.Cu") (net 337))
  (segment (start 148.158672 55.896512) (end 148.310828 56.048668) (width 0.143) (layer "In2.Cu") (net 337))
  (segment (start 176.201094 76.720094) (end 176.149906 76.720094) (width 0.1) (layer "In2.Cu") (net 337))
  (segment (start 148.490401 57.767899) (end 148.490401 57.7679) (width 0.143) (layer "In2.Cu") (net 337))
  (segment (start 176.38642 78.3955) (end 176.554992 78.3955) (width 0.1) (layer "In2.Cu") (net 337))
  (segment (start 175.999906 76.920094) (end 175.999906 78.008986) (width 0.1) (layer "In2.Cu") (net 337))
  (segment (start 147.08769 57.02485) (end 147.08769 56.22515) (width 0.143) (layer "In2.Cu") (net 337))
  (segment (start 148.310827 56.460511) (end 148.136328 56.63501) (width 0.143) (layer "In2.Cu") (net 337))
  (segment (start 148.03718 57.974341) (end 147.95642 57.89358) (width 0.143) (layer "In2.Cu") (net 337))
  (segment (start 147.416328 55.896512) (end 148.158672 55.896512) (width 0.143) (layer "In2.Cu") (net 337))
  (segment (start 147.390733 57.327893) (end 147.08769 57.02485) (width 0.143) (layer "In2.Cu") (net 337))
  (segment (start 147.956419 57.610737) (end 147.95642 57.610737) (width 0.143) (layer "In2.Cu") (net 337))
  (segment (start 176.201094 76.120094) (end 176.149906 76.120094) (width 0.1) (layer "In2.Cu") (net 337))
  (segment (start 149.2105 59.14766) (end 148.956419 58.89358) (width 0.143) (layer "In2.Cu") (net 337))
  (segment (start 176.554992 78.395008) (end 176.636328 78.313672) (width 0.1) (layer "In2.Cu") (net 337))
  (segment (start 147.08769 56.22515) (end 147.416328 55.896512) (width 0.143) (layer "In2.Cu") (net 337))
  (segment (start 175.999906 75.522616) (end 175.999906 75.670094) (width 0.1) (layer "In2.Cu") (net 337))
  (segment (start 175.999906 78.008986) (end 176.38642 78.3955) (width 0.1) (layer "In2.Cu") (net 337))
  (segment (start 176.554992 78.3955) (end 176.554992 78.395008) (width 0.1) (layer "In2.Cu") (net 337))
  (arc (start 176.201094 76.420094) (mid 176.30716 76.464028) (end 176.351094 76.570094) (width 0.1) (layer "In2.Cu") (net 337))
  (arc (start 176.351094 76.570094) (mid 176.30716 76.67616) (end 176.201094 76.720094) (width 0.1) (layer "In2.Cu") (net 337))
  (arc (start 176.149906 76.120094) (mid 176.04384 76.164028) (end 175.999906 76.270094) (width 0.1) (layer "In2.Cu") (net 337))
  (arc (start 176.201094 75.820094) (mid 176.30716 75.864028) (end 176.351094 75.970094) (width 0.1) (layer "In2.Cu") (net 337))
  (arc (start 148.956419 58.89358) (mid 148.905309 58.77019) (end 148.956419 58.6468) (width 0.143) (layer "In2.Cu") (net 337))
  (arc (start 175.999906 76.270094) (mid 176.04384 76.37616) (end 176.149906 76.420094) (width 0.1) (layer "In2.Cu") (net 337))
  (arc (start 148.110671 57.456485) (mid 148.16925 57.315064) (end 148.110672 57.173642) (width 0.143) (layer "In2.Cu") (net 337))
  (arc (start 176.351094 75.970094) (mid 176.30716 76.07616) (end 176.201094 76.120094) (width 0.1) (layer "In2.Cu") (net 337))
  (arc (start 147.673576 57.327893) (mid 147.532155 57.386472) (end 147.390733 57.327894) (width 0.143) (layer "In2.Cu") (net 337))
  (arc (start 148.283959 57.974341) (mid 148.160569 58.025451) (end 148.037179 57.974341) (width 0.143) (layer "In2.Cu") (net 337))
  (arc (start 149.16286 57.7679) (mid 148.826631 57.628629) (end 148.490401 57.767899) (width 0.143) (layer "In2.Cu") (net 337))
  (arc (start 148.110671 57.173642) (mid 147.96925 57.115063) (end 147.827828 57.173641) (width 0.143) (layer "In2.Cu") (net 337))
  (arc (start 147.95642 57.89358) (mid 147.897841 57.752159) (end 147.956419 57.610737) (width 0.143) (layer "In2.Cu") (net 337))
  (arc (start 176.149906 76.720094) (mid 176.04384 76.764028) (end 175.999906 76.870094) (width 0.1) (layer "In2.Cu") (net 337))
  (arc (start 149.16286 58.440358) (mid 149.30213 58.104128) (end 149.162859 57.767899) (width 0.143) (layer "In2.Cu") (net 337))
  (arc (start 175.999906 75.670094) (mid 176.04384 75.77616) (end 176.149906 75.820094) (width 0.1) (layer "In2.Cu") (net 337))
  (segment (start 137.836328 59.660008) (end 137.836328 60.960008) (width 0.1) (layer "F.Cu") (net 338))
  (segment (start 179.71 83.04) (end 179.71 83.07) (width 0.127) (layer "F.Cu") (net 338))
  (segment (start 180.136328 83.496328) (end 180.136328 83.560008) (width 0.127) (layer "F.Cu") (net 338))
  (segment (start 179.71 83.07) (end 180.136328 83.496328) (width 0.127) (layer "F.Cu") (net 338))
  (via blind (at 179.71 83.04) (size 0.5) (drill 0.2) (layers "F.Cu" "In5.Cu") (net 338))
  (via blind (at 137.836328 60.960008) (size 0.5) (drill 0.2) (layers "F.Cu" "In5.Cu") (net 338))
  (segment (start 148.367964 72.95076) (end 148.367963 72.95076) (width 0.127) (layer "In5.Cu") (net 338))
  (segment (start 159.24056 74.2435) (end 148.83056 74.2435) (width 0.127) (layer "In5.Cu") (net 338))
  (segment (start 179.71 83.04) (end 179.45 83.04) (width 0.09) (layer "In5.Cu") (net 338))
  (segment (start 148.55853 73.344266) (end 148.659999 73.242796) (width 0.127) (layer "In5.Cu") (net 338))
  (segment (start 146.962938 72.375877) (end 146.750804 72.588008) (width 0.127) (layer "In5.Cu") (net 338))
  (segment (start 148.659999 73.021471) (end 148.589288 72.95076) (width 0.127) (layer "In5.Cu") (net 338))
  (segment (start 146.052889 71.890092) (end 146.680092 71.262888) (width 0.127) (layer "In5.Cu") (net 338))
  (segment (start 169.755 80.427006) (end 169.755 79.960062) (width 0.09) (layer "In5.Cu") (net 338))
  (segment (start 145.164406 70.577344) (end 145.164404 70.577343) (width 0.127) (layer "In5.Cu") (net 338))
  (segment (start 146.074454 71.284453) (end 146.074452 71.284452) (width 0.127) (layer "In5.Cu") (net 338))
  (segment (start 179.45 83.04) (end 179.389572 83.100428) (width 0.09) (layer "In5.Cu") (net 338))
  (segment (start 148.05436 73.26436) (end 147.952892 73.365831) (width 0.127) (layer "In5.Cu") (net 338))
  (segment (start 169.437248 79.64231) (end 169.10119 79.64231) (width 0.09) (layer "In5.Cu") (net 338))
  (segment (start 147.042843 72.880046) (end 147.670046 72.252842) (width 0.127) (layer "In5.Cu") (net 338))
  (segment (start 146.074452 71.284452) (end 145.963791 71.395116) (width 0.127) (layer "In5.Cu") (net 338))
  (segment (start 147.064406 72.274406) (end 146.962938 72.375877) (width 0.127) (layer "In5.Cu") (net 338))
  (segment (start 138.117828 63.530768) (end 138.117828 61.241508) (width 0.127) (layer "In5.Cu") (net 338))
  (segment (start 177.975 80.700062) (end 177.710938 80.436) (width 0.09) (layer "In5.Cu") (net 338))
  (segment (start 145.062935 70.900138) (end 145.164405 70.798669) (width 0.127) (layer "In5.Cu") (net 338))
  (segment (start 164.64056 79.6435) (end 159.24056 74.2435) (width 0.127) (layer "In5.Cu") (net 338))
  (segment (start 138.117828 61.241508) (end 137.836328 60.960008) (width 0.127) (layer "In5.Cu") (net 338))
  (segment (start 145.963791 71.395116) (end 145.76085 71.598054) (width 0.127) (layer "In5.Cu") (net 338))
  (segment (start 147.952892 73.365831) (end 147.740758 73.577962) (width 0.127) (layer "In5.Cu") (net 338))
  (segment (start 146.1236 72.588007) (end 146.052889 72.517296) (width 0.127) (layer "In5.Cu") (net 338))
  (segment (start 169.755 79.960062) (end 169.437248 79.64231) (width 0.09) (layer "In5.Cu") (net 338))
  (segment (start 147.113554 73.577961) (end 147.042843 73.50725) (width 0.127) (layer "In5.Cu") (net 338))
  (segment (start 145.164404 70.577343) (end 138.117828 63.530768) (width 0.127) (layer "In5.Cu") (net 338))
  (segment (start 173.515062 80.865) (end 170.192994 80.865) (width 0.09) (layer "In5.Cu") (net 338))
  (segment (start 179.109785 83.725277) (end 178.460215 83.725277) (width 0.09) (layer "In5.Cu") (net 338))
  (segment (start 147.37801 71.960806) (end 147.064408 72.274407) (width 0.127) (layer "In5.Cu") (net 338))
  (segment (start 146.123601 72.588007) (end 146.1236 72.588007) (width 0.127) (layer "In5.Cu") (net 338))
  (segment (start 147.378011 71.960806) (end 147.37801 71.960806) (width 0.127) (layer "In5.Cu") (net 338))
  (segment (start 177.975 82.586008) (end 177.975 80.700062) (width 0.09) (layer "In5.Cu") (net 338))
  (segment (start 178.047577 82.658585) (end 177.975 82.586008) (width 0.09) (layer "In5.Cu") (net 338))
  (segment (start 170.192994 80.865) (end 169.755 80.427006) (width 0.09) (layer "In5.Cu") (net 338))
  (segment (start 178.460215 83.725277) (end 178.047577 83.312639) (width 0.09) (layer "In5.Cu") (net 338))
  (segment (start 179.389572 83.100428) (end 179.389572 83.44549) (width 0.09) (layer "In5.Cu") (net 338))
  (segment (start 173.944062 80.436) (end 173.515062 80.865) (width 0.09) (layer "In5.Cu") (net 338))
  (segment (start 177.710938 80.436) (end 173.944062 80.436) (width 0.09) (layer "In5.Cu") (net 338))
  (segment (start 146.680092 71.041563) (end 146.609381 70.970852) (width 0.127) (layer "In5.Cu") (net 338))
  (segment (start 148.66 73.021471) (end 148.659999 73.021471) (width 0.127) (layer "In5.Cu") (net 338))
  (segment (start 146.680091 71.041563) (end 146.680092 71.041563) (width 0.127) (layer "In5.Cu") (net 338))
  (segment (start 178.047577 83.312639) (end 178.047577 82.658585) (width 0.09) (layer "In5.Cu") (net 338))
  (segment (start 147.113555 73.577961) (end 147.113554 73.577961) (width 0.127) (layer "In5.Cu") (net 338))
  (segment (start 146.388056 70.970852) (end 146.074454 71.284453) (width 0.127) (layer "In5.Cu") (net 338))
  (segment (start 147.670046 72.031517) (end 147.599335 71.960806) (width 0.127) (layer "In5.Cu") (net 338))
  (segment (start 169.1 79.6435) (end 164.64056 79.6435) (width 0.127) (layer "In5.Cu") (net 338))
  (segment (start 148.367963 72.95076) (end 148.05436 73.26436) (width 0.127) (layer "In5.Cu") (net 338))
  (segment (start 169.10119 79.64231) (end 169.1 79.6435) (width 0.09) (layer "In5.Cu") (net 338))
  (segment (start 147.670045 72.031517) (end 147.670046 72.031517) (width 0.127) (layer "In5.Cu") (net 338))
  (segment (start 148.83056 74.2435) (end 148.55853 73.971469) (width 0.127) (layer "In5.Cu") (net 338))
  (segment (start 179.389572 83.44549) (end 179.109785 83.725277) (width 0.09) (layer "In5.Cu") (net 338))
  (segment (start 145.133646 71.598053) (end 145.062935 71.527342) (width 0.127) (layer "In5.Cu") (net 338))
  (segment (start 145.133647 71.598053) (end 145.133646 71.598053) (width 0.127) (layer "In5.Cu") (net 338))
  (segment (start 148.55853 73.344265) (end 148.55853 73.344266) (width 0.127) (layer "In5.Cu") (net 338))
  (segment (start 146.388057 70.970852) (end 146.388056 70.970852) (width 0.127) (layer "In5.Cu") (net 338))
  (segment (start 147.064408 72.274407) (end 147.064406 72.274406) (width 0.127) (layer "In5.Cu") (net 338))
  (arc (start 147.599335 71.960806) (mid 147.488673 71.914968) (end 147.378011 71.960806) (width 0.127) (layer "In5.Cu") (net 338))
  (arc (start 146.750804 72.588008) (mid 146.437203 72.717906) (end 146.123601 72.588007) (width 0.127) (layer "In5.Cu") (net 338))
  (arc (start 147.740758 73.577962) (mid 147.427157 73.70786) (end 147.113555 73.577961) (width 0.127) (layer "In5.Cu") (net 338))
  (arc (start 147.042843 73.50725) (mid 146.912945 73.193648) (end 147.042843 72.880046) (width 0.127) (layer "In5.Cu") (net 338))
  (arc (start 145.76085 71.598054) (mid 145.447249 71.727952) (end 145.133647 71.598053) (width 0.127) (layer "In5.Cu") (net 338))
  (arc (start 148.55853 73.971469) (mid 148.428632 73.657867) (end 148.55853 73.344265) (width 0.127) (layer "In5.Cu") (net 338))
  (arc (start 146.609381 70.970852) (mid 146.498719 70.925014) (end 146.388057 70.970852) (width 0.127) (layer "In5.Cu") (net 338))
  (arc (start 146.052889 72.517296) (mid 145.922991 72.203694) (end 146.052889 71.890092) (width 0.127) (layer "In5.Cu") (net 338))
  (arc (start 148.589288 72.95076) (mid 148.478626 72.904922) (end 148.367964 72.95076) (width 0.127) (layer "In5.Cu") (net 338))
  (arc (start 145.164405 70.798669) (mid 145.210243 70.688007) (end 145.164406 70.577344) (width 0.127) (layer "In5.Cu") (net 338))
  (arc (start 145.062935 71.527342) (mid 144.933037 71.21374) (end 145.062935 70.900138) (width 0.127) (layer "In5.Cu") (net 338))
  (arc (start 148.659999 73.242796) (mid 148.705837 73.132134) (end 148.66 73.021471) (width 0.127) (layer "In5.Cu") (net 338))
  (arc (start 147.670046 72.252842) (mid 147.715883 72.142179) (end 147.670045 72.031517) (width 0.127) (layer "In5.Cu") (net 338))
  (arc (start 146.680092 71.262888) (mid 146.725929 71.152225) (end 146.680091 71.041563) (width 0.127) (layer "In5.Cu") (net 338))
  (segment (start 139.236328 55.975008) (end 139.236328 56.43501) (width 0.1) (layer "F.Cu") (net 339))
  (segment (start 180.136328 82.560008) (end 179.663828 82.087508) (width 0.127) (layer "F.Cu") (net 339))
  (segment (start 139.536328 55.675008) (end 139.236328 55.975008) (width 0.1) (layer "F.Cu") (net 339))
  (segment (start 139.236328 56.43501) (end 139.436328 56.63501) (width 0.1) (layer "F.Cu") (net 339))
  (segment (start 179.663828 82.087508) (end 179.663828 82.0405) (width 0.127) (layer "F.Cu") (net 339))
  (segment (start 139.536328 55.060008) (end 139.536328 55.675008) (width 0.1) (layer "F.Cu") (net 339))
  (via blind (at 139.436328 56.63501) (size 0.5) (drill 0.2) (layers "F.Cu" "In5.Cu") (net 339))
  (via blind (at 179.663828 82.0405) (size 0.5) (drill 0.2) (layers "F.Cu" "In5.Cu") (net 339))
  (segment (start 144.328172 67.528172) (end 144.699666 67.156678) (width 0.127) (layer "In5.Cu") (net 339))
  (segment (start 139.6935 58.64056) (end 139.254828 58.201888) (width 0.127) (layer "In5.Cu") (net 339))
  (segment (start 143.072791 66.94507) (end 143.072792 66.945069) (width 0.127) (layer "In5.Cu") (net 339))
  (segment (start 179.341309 80.748486) (end 178.142823 79.55) (width 0.09) (layer "In5.Cu") (net 339))
  (segment (start 168.621142 78.314142) (end 168.536476 78.314142) (width 0.127) (layer "In5.Cu") (net 339))
  (segment (start 179.3905 82.0405) (end 179.326664 81.976664) (width 0.09) (layer "In5.Cu") (net 339))
  (segment (start 149.85944 72.8565) (end 146.396469 69.39353) (width 0.127) (layer "In5.Cu") (net 339))
  (segment (start 144.699666 66.49412) (end 144.699666 66.494119) (width 0.127) (layer "In5.Cu") (net 339))
  (segment (start 146.538152 68.332606) (end 146.538153 68.332606) (width 0.127) (layer "In5.Cu") (net 339))
  (segment (start 172.958846 79.414522) (end 171.319584 79.414522) (width 0.09) (layer "In5.Cu") (net 339))
  (segment (start 178.142823 79.55) (end 173.094324 79.55) (width 0.09) (layer "In5.Cu") (net 339))
  (segment (start 145.875593 68.332606) (end 145.167958 69.040235) (width 0.127) (layer "In5.Cu") (net 339))
  (segment (start 170.362752 78.45769) (end 169.10119 78.45769) (width 0.09) (layer "In5.Cu") (net 339))
  (segment (start 169.10119 78.45769) (end 169.1 78.4565) (width 0.09) (layer "In5.Cu") (net 339))
  (segment (start 143.992035 67.864312) (end 144.328174 67.528174) (width 0.127) (layer "In5.Cu") (net 339))
  (segment (start 144.95635 67.413361) (end 144.956349 67.413362) (width 0.127) (layer "In5.Cu") (net 339))
  (segment (start 144.956349 67.413362) (end 144.248715 68.120992) (width 0.127) (layer "In5.Cu") (net 339))
  (segment (start 179.341309 81.332513) (end 179.341309 80.748486) (width 0.09) (layer "In5.Cu") (net 339))
  (segment (start 173.094324 79.55) (end 172.958846 79.414522) (width 0.09) (layer "In5.Cu") (net 339))
  (segment (start 144.037106 66.494119) (end 143.329472 67.201749) (width 0.127) (layer "In5.Cu") (net 339))
  (segment (start 145.875594 68.332605) (end 145.875593 68.332606) (width 0.127) (layer "In5.Cu") (net 339))
  (segment (start 146.396469 69.13685) (end 146.538153 68.995165) (width 0.127) (layer "In5.Cu") (net 339))
  (segment (start 145.247417 68.447417) (end 145.247415 68.447415) (width 0.127) (layer "In5.Cu") (net 339))
  (segment (start 144.911277 68.783556) (end 144.911278 68.783555) (width 0.127) (layer "In5.Cu") (net 339))
  (segment (start 179.663828 82.0405) (end 179.3905 82.0405) (width 0.09) (layer "In5.Cu") (net 339))
  (segment (start 145.247415 68.447415) (end 145.618909 68.075921) (width 0.127) (layer "In5.Cu") (net 339))
  (segment (start 139.254828 56.81651) (end 139.436328 56.63501) (width 0.127) (layer "In5.Cu") (net 339))
  (segment (start 143.072792 66.945069) (end 143.179122 66.83874) (width 0.127) (layer "In5.Cu") (net 339))
  (segment (start 139.254828 58.201888) (end 139.254828 56.81651) (width 0.127) (layer "In5.Cu") (net 339))
  (segment (start 145.618909 67.413363) (end 145.618909 67.413362) (width 0.127) (layer "In5.Cu") (net 339))
  (segment (start 139.6935 62.69056) (end 139.6935 58.64056) (width 0.127) (layer "In5.Cu") (net 339))
  (segment (start 144.037107 66.494118) (end 144.037106 66.494119) (width 0.127) (layer "In5.Cu") (net 339))
  (segment (start 159.74944 72.8565) (end 149.85944 72.8565) (width 0.127) (layer "In5.Cu") (net 339))
  (segment (start 143.179121 66.17618) (end 139.6935 62.69056) (width 0.127) (layer "In5.Cu") (net 339))
  (segment (start 179.326664 81.976664) (end 179.326664 81.347158) (width 0.09) (layer "In5.Cu") (net 339))
  (segment (start 168.394124 78.4565) (end 168.3095 78.4565) (width 0.127) (layer "In5.Cu") (net 339))
  (segment (start 144.911278 68.783555) (end 145.247417 68.447417) (width 0.127) (layer "In5.Cu") (net 339))
  (segment (start 171.319584 79.414522) (end 170.362752 78.45769) (width 0.09) (layer "In5.Cu") (net 339))
  (segment (start 179.326664 81.347158) (end 179.341309 81.332513) (width 0.09) (layer "In5.Cu") (net 339))
  (segment (start 169.1 78.4565) (end 168.763532 78.4565) (width 0.127) (layer "In5.Cu") (net 339))
  (segment (start 168.3095 78.4565) (end 165.34944 78.4565) (width 0.127) (layer "In5.Cu") (net 339))
  (segment (start 165.34944 78.4565) (end 159.74944 72.8565) (width 0.127) (layer "In5.Cu") (net 339))
  (segment (start 143.992034 67.864313) (end 143.992035 67.864312) (width 0.127) (layer "In5.Cu") (net 339))
  (segment (start 144.911279 69.040236) (end 144.911278 69.040235) (width 0.127) (layer "In5.Cu") (net 339))
  (segment (start 143.179121 66.176181) (end 143.179121 66.17618) (width 0.127) (layer "In5.Cu") (net 339))
  (segment (start 143.072793 67.20175) (end 143.072792 67.201749) (width 0.127) (layer "In5.Cu") (net 339))
  (segment (start 143.992036 68.120993) (end 143.992035 68.120992) (width 0.127) (layer "In5.Cu") (net 339))
  (segment (start 144.328174 67.528174) (end 144.328172 67.528172) (width 0.127) (layer "In5.Cu") (net 339))
  (arc (start 144.699666 67.156678) (mid 144.836886 66.825399) (end 144.699666 66.49412) (width 0.127) (layer "In5.Cu") (net 339))
  (arc (start 144.911278 69.040235) (mid 144.858119 68.911897) (end 144.911277 68.783556) (width 0.127) (layer "In5.Cu") (net 339))
  (arc (start 144.699666 66.494119) (mid 144.368387 66.356898) (end 144.037107 66.494118) (width 0.127) (layer "In5.Cu") (net 339))
  (arc (start 143.179122 66.83874) (mid 143.316342 66.50746) (end 143.179121 66.176181) (width 0.127) (layer "In5.Cu") (net 339))
  (arc (start 146.538153 68.332606) (mid 146.206874 68.195385) (end 145.875594 68.332605) (width 0.127) (layer "In5.Cu") (net 339))
  (arc (start 143.329472 67.201749) (mid 143.201134 67.25491) (end 143.072793 67.20175) (width 0.127) (layer "In5.Cu") (net 339))
  (arc (start 168.536476 78.314142) (mid 168.486154 78.33499) (end 168.465321 78.385321) (width 0.127) (layer "In5.Cu") (net 339))
  (arc (start 145.167958 69.040235) (mid 145.03962 69.093396) (end 144.911279 69.040236) (width 0.127) (layer "In5.Cu") (net 339))
  (arc (start 168.692321 78.385321) (mid 168.671473 78.33499) (end 168.621142 78.314142) (width 0.127) (layer "In5.Cu") (net 339))
  (arc (start 146.538153 68.995165) (mid 146.675373 68.663885) (end 146.538152 68.332606) (width 0.127) (layer "In5.Cu") (net 339))
  (arc (start 145.618909 68.075921) (mid 145.756129 67.744642) (end 145.618909 67.413363) (width 0.127) (layer "In5.Cu") (net 339))
  (arc (start 168.465321 78.385321) (mid 168.44446 78.435655) (end 168.394124 78.4565) (width 0.127) (layer "In5.Cu") (net 339))
  (arc (start 168.763532 78.4565) (mid 168.713186 78.43565) (end 168.692321 78.385321) (width 0.127) (layer "In5.Cu") (net 339))
  (arc (start 143.072792 67.201749) (mid 143.019633 67.073411) (end 143.072791 66.94507) (width 0.127) (layer "In5.Cu") (net 339))
  (arc (start 146.396469 69.39353) (mid 146.343309 69.26519) (end 146.396469 69.13685) (width 0.127) (layer "In5.Cu") (net 339))
  (arc (start 144.248715 68.120992) (mid 144.120377 68.174153) (end 143.992036 68.120993) (width 0.127) (layer "In5.Cu") (net 339))
  (arc (start 143.992035 68.120992) (mid 143.938876 67.992654) (end 143.992034 67.864313) (width 0.127) (layer "In5.Cu") (net 339))
  (arc (start 145.618909 67.413362) (mid 145.28763 67.276141) (end 144.95635 67.413361) (width 0.127) (layer "In5.Cu") (net 339))
  (segment (start 138.686328 59.660008) (end 138.686328 60.960008) (width 0.1) (layer "F.Cu") (net 340))
  (segment (start 178.779776 83.079776) (end 179.136328 83.436328) (width 0.127) (layer "F.Cu") (net 340))
  (segment (start 178.779776 83.041955) (end 178.779776 83.079776) (width 0.127) (layer "F.Cu") (net 340))
  (segment (start 179.136328 83.436328) (end 179.136328 83.560008) (width 0.127) (layer "F.Cu") (net 340))
  (via blind (at 178.778 83.043) (size 0.5) (drill 0.2) (layers "F.Cu" "In5.Cu") (net 340))
  (via blind (at 138.686328 60.960008) (size 0.5) (drill 0.2) (layers "F.Cu" "In5.Cu") (net 340))
  (segment (start 148.862938 73.445735) (end 148.761469 73.547205) (width 0.127) (layer "In5.Cu") (net 340))
  (segment (start 146.81232 70.767913) (end 146.883031 70.838624) (width 0.127) (layer "In5.Cu") (net 340))
  (segment (start 138.404828 63.411888) (end 145.367343 70.374404) (width 0.127) (layer "In5.Cu") (net 340))
  (segment (start 148.761469 73.547205) (end 148.761469 73.547204) (width 0.127) (layer "In5.Cu") (net 340))
  (segment (start 147.802274 71.757867) (end 147.872985 71.828578) (width 0.127) (layer "In5.Cu") (net 340))
  (segment (start 148.761469 73.76853) (end 148.94944 73.9565) (width 0.127) (layer "In5.Cu") (net 340))
  (segment (start 147.245783 73.082987) (end 147.245782 73.082987) (width 0.127) (layer "In5.Cu") (net 340))
  (segment (start 178.264981 80.847795) (end 178.241828 80.870948) (width 0.09) (layer "In5.Cu") (net 340))
  (segment (start 178.580358 83.435296) (end 178.989642 83.435296) (width 0.09) (layer "In5.Cu") (net 340))
  (segment (start 168.9335 79.3565) (end 169.1 79.3565) (width 0.127) (layer "In5.Cu") (net 340))
  (segment (start 145.760849 71.192174) (end 146.185116 70.767913) (width 0.127) (layer "In5.Cu") (net 340))
  (segment (start 169.1 79.3565) (end 169.10419 79.35231) (width 0.09) (layer "In5.Cu") (net 340))
  (segment (start 168.4835 79.2065) (end 168.4835 79.196376) (width 0.127) (layer "In5.Cu") (net 340))
  (segment (start 170.045 79.839938) (end 170.045 80.306882) (width 0.09) (layer "In5.Cu") (net 340))
  (segment (start 178.264981 81.237899) (end 178.264981 82.585989) (width 0.09) (layer "In5.Cu") (net 340))
  (segment (start 166.6835 79.2065) (end 166.6835 79.196376) (width 0.127) (layer "In5.Cu") (net 340))
  (segment (start 167.8835 79.2065) (end 167.8835 79.196376) (width 0.127) (layer "In5.Cu") (net 340))
  (segment (start 168.1835 79.196376) (end 168.1835 79.2065) (width 0.127) (layer "In5.Cu") (net 340))
  (segment (start 146.255828 72.314357) (end 146.326539 72.385068) (width 0.127) (layer "In5.Cu") (net 340))
  (segment (start 170.310484 80.572366) (end 173.397572 80.572366) (width 0.09) (layer "In5.Cu") (net 340))
  (segment (start 169.10419 79.35231) (end 169.557372 79.35231) (width 0.09) (layer "In5.Cu") (net 340))
  (segment (start 148.94944 73.9565) (end 159.35944 73.9565) (width 0.127) (layer "In5.Cu") (net 340))
  (segment (start 179.099572 83.079572) (end 179.061955 83.041955) (width 0.09) (layer "In5.Cu") (net 340))
  (segment (start 145.367343 71.001608) (end 145.265875 71.103079) (width 0.127) (layer "In5.Cu") (net 340))
  (segment (start 173.397572 80.572366) (end 173.823938 80.146) (width 0.09) (layer "In5.Cu") (net 340))
  (segment (start 167.5835 79.196376) (end 167.5835 79.2065) (width 0.127) (layer "In5.Cu") (net 340))
  (segment (start 178.264981 80.579919) (end 178.264981 80.847795) (width 0.09) (layer "In5.Cu") (net 340))
  (segment (start 164.75944 79.3565) (end 165.9335 79.3565) (width 0.127) (layer "In5.Cu") (net 340))
  (segment (start 178.241828 81.214746) (end 178.264981 81.237899) (width 0.09) (layer "In5.Cu") (net 340))
  (segment (start 170.045 80.306882) (end 170.310484 80.572366) (width 0.09) (layer "In5.Cu") (net 340))
  (segment (start 145.557911 71.395115) (end 145.760849 71.192174) (width 0.127) (layer "In5.Cu") (net 340))
  (segment (start 166.0835 79.2065) (end 166.0835 79.196376) (width 0.127) (layer "In5.Cu") (net 340))
  (segment (start 166.3835 79.196376) (end 166.3835 79.2065) (width 0.127) (layer "In5.Cu") (net 340))
  (segment (start 178.337577 82.658585) (end 178.337577 83.192515) (width 0.09) (layer "In5.Cu") (net 340))
  (segment (start 145.265875 71.103079) (end 145.265874 71.103079) (width 0.127) (layer "In5.Cu") (net 340))
  (segment (start 147.245782 73.304311) (end 147.316493 73.375022) (width 0.127) (layer "In5.Cu") (net 340))
  (segment (start 147.872985 71.828578) (end 147.872984 71.828578) (width 0.127) (layer "In5.Cu") (net 340))
  (segment (start 179.061955 83.041955) (end 178.779776 83.041955) (width 0.09) (layer "In5.Cu") (net 340))
  (segment (start 169.557372 79.35231) (end 170.045 79.839938) (width 0.09) (layer "In5.Cu") (net 340))
  (segment (start 177.831062 80.146) (end 178.264981 80.579919) (width 0.09) (layer "In5.Cu") (net 340))
  (segment (start 179.099572 83.325366) (end 179.099572 83.079572) (width 0.09) (layer "In5.Cu") (net 340))
  (segment (start 146.883031 71.465827) (end 146.255829 72.093033) (width 0.127) (layer "In5.Cu") (net 340))
  (segment (start 159.35944 73.9565) (end 164.75944 79.3565) (width 0.127) (layer "In5.Cu") (net 340))
  (segment (start 173.823938 80.146) (end 177.831062 80.146) (width 0.09) (layer "In5.Cu") (net 340))
  (segment (start 146.883031 70.838624) (end 146.88303 70.838624) (width 0.127) (layer "In5.Cu") (net 340))
  (segment (start 146.326539 72.385068) (end 146.32654 72.385068) (width 0.127) (layer "In5.Cu") (net 340))
  (segment (start 146.255829 72.093033) (end 146.255828 72.093033) (width 0.127) (layer "In5.Cu") (net 340))
  (segment (start 178.989642 83.435296) (end 179.099572 83.325366) (width 0.09) (layer "In5.Cu") (net 340))
  (segment (start 167.2835 79.2065) (end 167.2835 79.196376) (width 0.127) (layer "In5.Cu") (net 340))
  (segment (start 178.337577 83.192515) (end 178.580358 83.435296) (width 0.09) (layer "In5.Cu") (net 340))
  (segment (start 138.686328 60.960008) (end 138.404828 61.241508) (width 0.127) (layer "In5.Cu") (net 340))
  (segment (start 145.265874 71.324403) (end 145.336585 71.395114) (width 0.127) (layer "In5.Cu") (net 340))
  (segment (start 178.241828 80.870948) (end 178.241828 81.214746) (width 0.09) (layer "In5.Cu") (net 340))
  (segment (start 145.336585 71.395114) (end 145.336586 71.395114) (width 0.127) (layer "In5.Cu") (net 340))
  (segment (start 147.316493 73.375022) (end 147.316494 73.375022) (width 0.127) (layer "In5.Cu") (net 340))
  (segment (start 146.547865 72.385069) (end 147.17507 71.757867) (width 0.127) (layer "In5.Cu") (net 340))
  (segment (start 166.9835 79.196376) (end 166.9835 79.2065) (width 0.127) (layer "In5.Cu") (net 340))
  (segment (start 178.264981 82.585989) (end 178.337577 82.658585) (width 0.09) (layer "In5.Cu") (net 340))
  (segment (start 138.404828 61.241508) (end 138.404828 63.411888) (width 0.127) (layer "In5.Cu") (net 340))
  (segment (start 168.7835 79.196376) (end 168.7835 79.2065) (width 0.127) (layer "In5.Cu") (net 340))
  (segment (start 147.537819 73.375023) (end 148.165023 72.74782) (width 0.127) (layer "In5.Cu") (net 340))
  (segment (start 148.792227 72.74782) (end 148.862938 72.818531) (width 0.127) (layer "In5.Cu") (net 340))
  (segment (start 147.872985 72.455781) (end 147.245783 73.082987) (width 0.127) (layer "In5.Cu") (net 340))
  (arc (start 168.4835 79.196376) (mid 168.527434 79.09031) (end 168.6335 79.046376) (width 0.127) (layer "In5.Cu") (net 340))
  (arc (start 146.255828 72.093033) (mid 146.20999 72.203695) (end 146.255828 72.314357) (width 0.127) (layer "In5.Cu") (net 340))
  (arc (start 166.5335 79.3565) (mid 166.639566 79.312566) (end 166.6835 79.2065) (width 0.127) (layer "In5.Cu") (net 340))
  (arc (start 148.862938 72.818531) (mid 148.992836 73.132133) (end 148.862938 73.445735) (width 0.127) (layer "In5.Cu") (net 340))
  (arc (start 147.17507 71.757867) (mid 147.488672 71.627969) (end 147.802274 71.757867) (width 0.127) (layer "In5.Cu") (net 340))
  (arc (start 168.1835 79.2065) (mid 168.227434 79.312566) (end 168.3335 79.3565) (width 0.127) (layer "In5.Cu") (net 340))
  (arc (start 166.9835 79.2065) (mid 167.027434 79.312566) (end 167.1335 79.3565) (width 0.127) (layer "In5.Cu") (net 340))
  (arc (start 167.2835 79.196376) (mid 167.327434 79.09031) (end 167.4335 79.046376) (width 0.127) (layer "In5.Cu") (net 340))
  (arc (start 166.6835 79.196376) (mid 166.727434 79.09031) (end 166.8335 79.046376) (width 0.127) (layer "In5.Cu") (net 340))
  (arc (start 147.316494 73.375022) (mid 147.427156 73.42086) (end 147.537819 73.375023) (width 0.127) (layer "In5.Cu") (net 340))
  (arc (start 148.165023 72.74782) (mid 148.478625 72.617922) (end 148.792227 72.74782) (width 0.127) (layer "In5.Cu") (net 340))
  (arc (start 165.9335 79.3565) (mid 166.039566 79.312566) (end 166.0835 79.2065) (width 0.127) (layer "In5.Cu") (net 340))
  (arc (start 146.32654 72.385068) (mid 146.437202 72.430906) (end 146.547865 72.385069) (width 0.127) (layer "In5.Cu") (net 340))
  (arc (start 147.872984 71.828578) (mid 148.002882 72.142179) (end 147.872985 72.455781) (width 0.127) (layer "In5.Cu") (net 340))
  (arc (start 167.4335 79.046376) (mid 167.539566 79.09031) (end 167.5835 79.196376) (width 0.127) (layer "In5.Cu") (net 340))
  (arc (start 168.3335 79.3565) (mid 168.439566 79.312566) (end 168.4835 79.2065) (width 0.127) (layer "In5.Cu") (net 340))
  (arc (start 168.7835 79.2065) (mid 168.827434 79.312566) (end 168.9335 79.3565) (width 0.127) (layer "In5.Cu") (net 340))
  (arc (start 168.6335 79.046376) (mid 168.739566 79.09031) (end 168.7835 79.196376) (width 0.127) (layer "In5.Cu") (net 340))
  (arc (start 167.1335 79.3565) (mid 167.239566 79.312566) (end 167.2835 79.2065) (width 0.127) (layer "In5.Cu") (net 340))
  (arc (start 166.0835 79.196376) (mid 166.127434 79.09031) (end 166.2335 79.046376) (width 0.127) (layer "In5.Cu") (net 340))
  (arc (start 146.185116 70.767913) (mid 146.498718 70.638015) (end 146.81232 70.767913) (width 0.127) (layer "In5.Cu") (net 340))
  (arc (start 145.336586 71.395114) (mid 145.447248 71.440952) (end 145.557911 71.395115) (width 0.127) (layer "In5.Cu") (net 340))
  (arc (start 167.5835 79.2065) (mid 167.627434 79.312566) (end 167.7335 79.3565) (width 0.127) (layer "In5.Cu") (net 340))
  (arc (start 147.245782 73.082987) (mid 147.199944 73.193649) (end 147.245782 73.304311) (width 0.127) (layer "In5.Cu") (net 340))
  (arc (start 166.8335 79.046376) (mid 166.939566 79.09031) (end 166.9835 79.196376) (width 0.127) (layer "In5.Cu") (net 340))
  (arc (start 146.88303 70.838624) (mid 147.012928 71.152225) (end 146.883031 71.465827) (width 0.127) (layer "In5.Cu") (net 340))
  (arc (start 166.3835 79.2065) (mid 166.427434 79.312566) (end 166.5335 79.3565) (width 0.127) (layer "In5.Cu") (net 340))
  (arc (start 145.265874 71.103079) (mid 145.220036 71.213741) (end 145.265874 71.324403) (width 0.127) (layer "In5.Cu") (net 340))
  (arc (start 148.761469 73.547204) (mid 148.715631 73.657867) (end 148.761469 73.76853) (width 0.127) (layer "In5.Cu") (net 340))
  (arc (start 145.367343 70.374404) (mid 145.497241 70.688006) (end 145.367343 71.001608) (width 0.127) (layer "In5.Cu") (net 340))
  (arc (start 167.8835 79.196376) (mid 167.927434 79.09031) (end 168.0335 79.046376) (width 0.127) (layer "In5.Cu") (net 340))
  (arc (start 168.0335 79.046376) (mid 168.139566 79.09031) (end 168.1835 79.196376) (width 0.127) (layer "In5.Cu") (net 340))
  (arc (start 166.2335 79.046376) (mid 166.339566 79.09031) (end 166.3835 79.196376) (width 0.127) (layer "In5.Cu") (net 340))
  (arc (start 167.7335 79.3565) (mid 167.839566 79.312566) (end 167.8835 79.2065) (width 0.127) (layer "In5.Cu") (net 340))
  (segment (start 138.686328 55.060008) (end 138.686328 55.675008) (width 0.1) (layer "F.Cu") (net 341))
  (segment (start 138.986328 56.43501) (end 138.786328 56.63501) (width 0.1) (layer "F.Cu") (net 341))
  (segment (start 138.986328 55.975008) (end 138.986328 56.43501) (width 0.1) (layer "F.Cu") (net 341))
  (segment (start 179.136328 82.560008) (end 179.136328 82.456328) (width 0.127) (layer "F.Cu") (net 341))
  (segment (start 179.136328 82.456328) (end 178.71 82.03) (width 0.127) (layer "F.Cu") (net 341))
  (segment (start 138.686328 55.675008) (end 138.986328 55.975008) (width 0.1) (layer "F.Cu") (net 341))
  (via blind (at 178.71 82.03) (size 0.5) (drill 0.2) (layers "F.Cu" "In5.Cu") (net 341))
  (via blind (at 138.786328 56.63501) (size 0.5) (drill 0.2) (layers "F.Cu" "In5.Cu") (net 341))
  (segment (start 142.869854 66.74213) (end 142.976182 66.635799) (width 0.127) (layer "In5.Cu") (net 341))
  (segment (start 143.789096 68.323933) (end 143.789097 68.323933) (width 0.127) (layer "In5.Cu") (net 341))
  (segment (start 165.23056 78.7435) (end 159.63056 73.1435) (width 0.127) (layer "In5.Cu") (net 341))
  (segment (start 179.071828 81.214746) (end 179.071828 80.870948) (width 0.09) (layer "In5.Cu") (net 341))
  (segment (start 144.70834 68.580616) (end 145.41597 67.872982) (width 0.127) (layer "In5.Cu") (net 341))
  (segment (start 179.036664 81.24991) (end 179.071828 81.214746) (width 0.09) (layer "In5.Cu") (net 341))
  (segment (start 144.240047 66.697059) (end 143.868552 67.068553) (width 0.127) (layer "In5.Cu") (net 341))
  (segment (start 172.984229 79.85) (end 172.838732 79.704503) (width 0.09) (layer "In5.Cu") (net 341))
  (segment (start 172.838732 79.704503) (end 171.199441 79.704503) (width 0.09) (layer "In5.Cu") (net 341))
  (segment (start 159.63056 73.1435) (end 149.74056 73.1435) (width 0.127) (layer "In5.Cu") (net 341))
  (segment (start 139.4065 58.75944) (end 138.967828 58.320768) (width 0.127) (layer "In5.Cu") (net 341))
  (segment (start 169.1 78.7435) (end 165.23056 78.7435) (width 0.127) (layer "In5.Cu") (net 341))
  (segment (start 171.199441 79.704503) (end 170.242628 78.74769) (width 0.09) (layer "In5.Cu") (net 341))
  (segment (start 144.708339 68.580617) (end 144.70834 68.580616) (width 0.127) (layer "In5.Cu") (net 341))
  (segment (start 143.868551 67.068551) (end 143.532414 67.404691) (width 0.127) (layer "In5.Cu") (net 341))
  (segment (start 143.789097 67.661373) (end 144.496727 66.953739) (width 0.127) (layer "In5.Cu") (net 341))
  (segment (start 139.4065 62.80944) (end 139.4065 58.75944) (width 0.127) (layer "In5.Cu") (net 341))
  (segment (start 146.19353 68.933911) (end 146.19353 68.93391) (width 0.127) (layer "In5.Cu") (net 341))
  (segment (start 142.976181 66.37912) (end 142.976183 66.379121) (width 0.127) (layer "In5.Cu") (net 341))
  (segment (start 138.967828 58.320768) (end 138.967828 56.81651) (width 0.127) (layer "In5.Cu") (net 341))
  (segment (start 142.869853 67.40469) (end 142.869854 67.40469) (width 0.127) (layer "In5.Cu") (net 341))
  (segment (start 179.036664 81.943336) (end 179.036664 81.24991) (width 0.09) (layer "In5.Cu") (net 341))
  (segment (start 178.05088 79.85) (end 172.984229 79.85) (width 0.09) (layer "In5.Cu") (net 341))
  (segment (start 144.708339 69.243176) (end 144.70834 69.243176) (width 0.127) (layer "In5.Cu") (net 341))
  (segment (start 145.159291 67.616301) (end 145.15929 67.616302) (width 0.127) (layer "In5.Cu") (net 341))
  (segment (start 145.707039 68.907039) (end 145.707037 68.907037) (width 0.127) (layer "In5.Cu") (net 341))
  (segment (start 145.707037 68.907037) (end 145.3709 69.243177) (width 0.127) (layer "In5.Cu") (net 341))
  (segment (start 143.868552 67.068553) (end 143.868551 67.068551) (width 0.127) (layer "In5.Cu") (net 341))
  (segment (start 138.967828 56.81651) (end 138.786328 56.63501) (width 0.127) (layer "In5.Cu") (net 341))
  (segment (start 145.15929 67.616302) (end 144.787795 67.987796) (width 0.127) (layer "In5.Cu") (net 341))
  (segment (start 142.869853 66.742131) (end 142.869854 66.74213) (width 0.127) (layer "In5.Cu") (net 341))
  (segment (start 142.976183 66.379121) (end 139.4065 62.80944) (width 0.127) (layer "In5.Cu") (net 341))
  (segment (start 144.787794 67.987794) (end 144.451657 68.323934) (width 0.127) (layer "In5.Cu") (net 341))
  (segment (start 143.789096 67.661374) (end 143.789097 67.661373) (width 0.127) (layer "In5.Cu") (net 341))
  (segment (start 178.95 82.03) (end 178.71 82.03) (width 0.09) (layer "In5.Cu") (net 341))
  (segment (start 169.10419 78.74769) (end 169.1 78.7435) (width 0.09) (layer "In5.Cu") (net 341))
  (segment (start 146.078535 68.535544) (end 146.078534 68.535545) (width 0.127) (layer "In5.Cu") (net 341))
  (segment (start 144.787795 67.987796) (end 144.787794 67.987794) (width 0.127) (layer "In5.Cu") (net 341))
  (segment (start 149.74056 73.1435) (end 146.19353 69.596469) (width 0.127) (layer "In5.Cu") (net 341))
  (segment (start 179.071828 80.870948) (end 178.05088 79.85) (width 0.09) (layer "In5.Cu") (net 341))
  (segment (start 146.19353 68.93391) (end 146.335214 68.792225) (width 0.127) (layer "In5.Cu") (net 341))
  (segment (start 144.240048 66.697058) (end 144.240047 66.697059) (width 0.127) (layer "In5.Cu") (net 341))
  (segment (start 170.242628 78.74769) (end 169.10419 78.74769) (width 0.09) (layer "In5.Cu") (net 341))
  (segment (start 178.95 82.03) (end 179.036664 81.943336) (width 0.09) (layer "In5.Cu") (net 341))
  (segment (start 146.078534 68.535545) (end 145.707039 68.907039) (width 0.127) (layer "In5.Cu") (net 341))
  (arc (start 145.41597 67.616302) (mid 145.287631 67.563142) (end 145.159291 67.616301) (width 0.127) (layer "In5.Cu") (net 341))
  (arc (start 146.19353 69.596469) (mid 146.05631 69.26519) (end 146.19353 68.933911) (width 0.127) (layer "In5.Cu") (net 341))
  (arc (start 143.789097 68.323933) (mid 143.651876 67.992654) (end 143.789096 67.661374) (width 0.127) (layer "In5.Cu") (net 341))
  (arc (start 145.3709 69.243177) (mid 145.039621 69.380398) (end 144.708339 69.243176) (width 0.127) (layer "In5.Cu") (net 341))
  (arc (start 144.451657 68.323934) (mid 144.120378 68.461155) (end 143.789096 68.323933) (width 0.127) (layer "In5.Cu") (net 341))
  (arc (start 144.496727 66.697059) (mid 144.368388 66.643899) (end 144.240048 66.697058) (width 0.127) (layer "In5.Cu") (net 341))
  (arc (start 144.496727 66.953739) (mid 144.549887 66.825399) (end 144.496727 66.697059) (width 0.127) (layer "In5.Cu") (net 341))
  (arc (start 146.335214 68.792225) (mid 146.388374 68.663885) (end 146.335214 68.535545) (width 0.127) (layer "In5.Cu") (net 341))
  (arc (start 142.976182 66.635799) (mid 143.029342 66.50746) (end 142.976181 66.37912) (width 0.127) (layer "In5.Cu") (net 341))
  (arc (start 145.41597 67.872982) (mid 145.46913 67.744642) (end 145.41597 67.616302) (width 0.127) (layer "In5.Cu") (net 341))
  (arc (start 143.532414 67.404691) (mid 143.201135 67.541912) (end 142.869853 67.40469) (width 0.127) (layer "In5.Cu") (net 341))
  (arc (start 144.70834 69.243176) (mid 144.571119 68.911897) (end 144.708339 68.580617) (width 0.127) (layer "In5.Cu") (net 341))
  (arc (start 142.869854 67.40469) (mid 142.732633 67.073411) (end 142.869853 66.742131) (width 0.127) (layer "In5.Cu") (net 341))
  (arc (start 146.335214 68.535545) (mid 146.206875 68.482385) (end 146.078535 68.535544) (width 0.127) (layer "In5.Cu") (net 341))
  (segment (start 181.136328 85.560008) (end 180.636328 85.060008) (width 0.127) (layer "F.Cu") (net 342))
  (segment (start 128.486328 59.660008) (end 128.486328 60.960008) (width 0.1) (layer "F.Cu") (net 342))
  (via (at 128.486328 60.960008) (size 0.5) (drill 0.2) (layers "F.Cu" "B.Cu") (net 342))
  (via (at 180.636328 85.060008) (size 0.5) (drill 0.2) (layers "F.Cu" "B.Cu") (net 342))
  (segment (start 161.93766 72.3505) (end 161.6505 72.3505) (width 0.143) (layer "In9.Cu") (net 342))
  (segment (start 177.165 75.447453) (end 177.165 76.52408) (width 0.1) (layer "In9.Cu") (net 342))
  (segment (start 135.74409 72.20693) (end 160.21336 72.20693) (width 0.143) (layer "In9.Cu") (net 342))
  (segment (start 160.40643 72.69407) (end 160.40643 72.4) (width 0.143) (layer "In9.Cu") (net 342))
  (segment (start 177.165 76.52408) (end 176.845 76.84408) (width 0.1) (layer "In9.Cu") (net 342))
  (segment (start 178.9255 84.373126) (end 178.9255 85.42754) (width 0.1) (layer "In9.Cu") (net 342))
  (segment (start 177.14777 75.430223) (end 177.14777 73.45061) (width 0.143) (layer "In9.Cu") (net 342))
  (segment (start 180.339992 85.060008) (end 180.636328 85.060008) (width 0.1) (layer "In9.Cu") (net 342))
  (segment (start 161.45743 72.54357) (end 161.45743 72.69407) (width 0.143) (layer "In9.Cu") (net 342))
  (segment (start 176.845 80.30592) (end 179.045 82.50592) (width 0.1) (layer "In9.Cu") (net 342))
  (segment (start 177.14777 75.430223) (end 177.165 75.447453) (width 0.1) (layer "In9.Cu") (net 342))
  (segment (start 135.74409 72.20693) (end 128.760827 65.223667) (width 0.143) (layer "In9.Cu") (net 342))
  (segment (start 177.14777 73.45061) (end 176.34766 72.6505) (width 0.143) (layer "In9.Cu") (net 342))
  (segment (start 176.34766 72.6505) (end 162.23766 72.6505) (width 0.143) (layer "In9.Cu") (net 342))
  (segment (start 160.96336 73.18814) (end 160.9005 73.18814) (width 0.143) (layer "In9.Cu") (net 342))
  (segment (start 179.045 82.50592) (end 179.045 84.253626) (width 0.1) (layer "In9.Cu") (net 342))
  (segment (start 128.760827 65.223667) (end 128.760827 61.234507) (width 0.143) (layer "In9.Cu") (net 342))
  (segment (start 178.9255 85.42754) (end 179.252476 85.754516) (width 0.1) (layer "In9.Cu") (net 342))
  (segment (start 179.999772 85.754516) (end 180.271328 85.48296) (width 0.1) (layer "In9.Cu") (net 342))
  (segment (start 128.760827 61.234507) (end 128.486328 60.960008) (width 0.143) (layer "In9.Cu") (net 342))
  (segment (start 176.845 76.84408) (end 176.845 80.30592) (width 0.1) (layer "In9.Cu") (net 342))
  (segment (start 179.252476 85.754516) (end 179.999772 85.754516) (width 0.1) (layer "In9.Cu") (net 342))
  (segment (start 162.23766 72.6505) (end 161.93766 72.3505) (width 0.143) (layer "In9.Cu") (net 342))
  (segment (start 180.271328 85.48296) (end 180.271328 85.128672) (width 0.1) (layer "In9.Cu") (net 342))
  (segment (start 180.271328 85.128672) (end 180.339992 85.060008) (width 0.1) (layer "In9.Cu") (net 342))
  (segment (start 179.045 84.253626) (end 178.9255 84.373126) (width 0.1) (layer "In9.Cu") (net 342))
  (arc (start 160.9005 73.18814) (mid 160.55114 73.04343) (end 160.40643 72.69407) (width 0.143) (layer "In9.Cu") (net 342))
  (arc (start 161.45743 72.69407) (mid 161.31272 73.04343) (end 160.96336 73.18814) (width 0.143) (layer "In9.Cu") (net 342))
  (arc (start 161.6505 72.3505) (mid 161.513979 72.407049) (end 161.45743 72.54357) (width 0.143) (layer "In9.Cu") (net 342))
  (arc (start 160.40643 72.4) (mid 160.349881 72.263479) (end 160.21336 72.20693) (width 0.143) (layer "In9.Cu") (net 342))
  (segment (start 182.136328 84.560008) (end 181.636328 84.060008) (width 0.127) (layer "F.Cu") (net 343))
  (segment (start 129.886328 55.975008) (end 129.886328 56.43501) (width 0.1) (layer "F.Cu") (net 343))
  (segment (start 129.886328 56.43501) (end 130.086328 56.63501) (width 0.1) (layer "F.Cu") (net 343))
  (segment (start 130.186328 55.675008) (end 129.886328 55.975008) (width 0.1) (layer "F.Cu") (net 343))
  (via (at 130.086328 56.63501) (size 0.5) (drill 0.2) (layers "F.Cu" "B.Cu") (net 343))
  (via (at 181.636328 84.060008) (size 0.5) (drill 0.2) (layers "F.Cu" "B.Cu") (net 343))
  (segment (start 158.748477 70.2495) (end 136.26234 70.2495) (width 0.143) (layer "In9.Cu") (net 343))
  (segment (start 178.512448 74.422448) (end 178.593901 74.422448) (width 0.143) (layer "In9.Cu") (net 343))
  (segment (start 180.39592 83.345) (end 179.835 82.78408) (width 0.1) (layer "In9.Cu") (net 343))
  (segment (start 159.548477 69.396953) (end 159.450523 69.396953) (width 0.143) (layer "In9.Cu") (net 343))
  (segment (start 158.949 69.898476) (end 158.949 70.048977) (width 0.143) (layer "In9.Cu") (net 343))
  (segment (start 179.835 82.78408) (end 179.835 80.15408) (width 0.1) (layer "In9.Cu") (net 343))
  (segment (start 161.147954 69.446453) (end 161.05 69.446453) (width 0.143) (layer "In9.Cu") (net 343))
  (segment (start 181.271328 84.001344) (end 181.271328 83.730408) (width 0.1) (layer "In9.Cu") (net 343))
  (segment (start 163.36234 71.3495) (end 162.31184 70.299) (width 0.143) (layer "In9.Cu") (net 343))
  (segment (start 178.593901 73.522448) (end 178.512448 73.522448) (width 0.143) (layer "In9.Cu") (net 343))
  (segment (start 129.911829 59.198989) (end 129.911829 56.809509) (width 0.143) (layer "In9.Cu") (net 343))
  (segment (start 181.329992 84.060008) (end 181.271328 84.001344) (width 0.1) (layer "In9.Cu") (net 343))
  (segment (start 160.348477 71.050523) (end 160.250523 71.050523) (width 0.143) (layer "In9.Cu") (net 343))
  (segment (start 178.35059 75.401842) (end 178.362448 75.389984) (width 0.1) (layer "In9.Cu") (net 343))
  (segment (start 178.593901 74.722448) (end 178.512448 74.722448) (width 0.143) (layer "In9.Cu") (net 343))
  (segment (start 130.4005 64.38766) (end 130.4005 59.68766) (width 0.143) (layer "In9.Cu") (net 343))
  (segment (start 160.05 69.898476) (end 160.05 70.85) (width 0.143) (layer "In9.Cu") (net 343))
  (segment (start 178.512448 75.022448) (end 178.593901 75.022448) (width 0.143) (layer "In9.Cu") (net 343))
  (segment (start 178.35059 78.66967) (end 178.35059 75.401842) (width 0.1) (layer "In9.Cu") (net 343))
  (segment (start 181.636328 84.060008) (end 181.329992 84.060008) (width 0.1) (layer "In9.Cu") (net 343))
  (segment (start 176.89234 71.3495) (end 163.36234 71.3495) (width 0.143) (layer "In9.Cu") (net 343))
  (segment (start 181.271328 83.730408) (end 180.88592 83.345) (width 0.1) (layer "In9.Cu") (net 343))
  (segment (start 136.26234 70.2495) (end 130.4005 64.38766) (width 0.143) (layer "In9.Cu") (net 343))
  (segment (start 178.362448 75.389984) (end 178.362448 75.172448) (width 0.143) (layer "In9.Cu") (net 343))
  (segment (start 178.362448 72.819608) (end 176.89234 71.3495) (width 0.143) (layer "In9.Cu") (net 343))
  (segment (start 179.835 80.15408) (end 178.35059 78.66967) (width 0.1) (layer "In9.Cu") (net 343))
  (segment (start 129.911829 56.809509) (end 130.086328 56.63501) (width 0.143) (layer "In9.Cu") (net 343))
  (segment (start 178.362448 73.372448) (end 178.362448 72.819608) (width 0.143) (layer "In9.Cu") (net 343))
  (segment (start 160.548477 69.947976) (end 160.549 69.948499) (width 0.143) (layer "In9.Cu") (net 343))
  (segment (start 130.4005 59.68766) (end 129.911829 59.198989) (width 0.143) (layer "In9.Cu") (net 343))
  (segment (start 161.649477 70.112035) (end 161.649477 69.947976) (width 0.143) (layer "In9.Cu") (net 343))
  (segment (start 178.512448 73.822448) (end 178.593901 73.822448) (width 0.143) (layer "In9.Cu") (net 343))
  (segment (start 160.549 69.948499) (end 160.549 70.85) (width 0.143) (layer "In9.Cu") (net 343))
  (segment (start 178.593901 74.122448) (end 178.512448 74.122448) (width 0.143) (layer "In9.Cu") (net 343))
  (segment (start 162.31184 70.299) (end 161.836442 70.299) (width 0.143) (layer "In9.Cu") (net 343))
  (segment (start 180.88592 83.345) (end 180.39592 83.345) (width 0.1) (layer "In9.Cu") (net 343))
  (arc (start 178.593901 75.022448) (mid 178.699967 74.978514) (end 178.743901 74.872448) (width 0.143) (layer "In9.Cu") (net 343))
  (arc (start 161.05 69.446453) (mid 160.69537 69.593346) (end 160.548477 69.947976) (width 0.143) (layer "In9.Cu") (net 343))
  (arc (start 178.512448 74.722448) (mid 178.406382 74.678514) (end 178.362448 74.572448) (width 0.143) (layer "In9.Cu") (net 343))
  (arc (start 160.05 69.898476) (mid 159.903107 69.543846) (end 159.548477 69.396953) (width 0.143) (layer "In9.Cu") (net 343))
  (arc (start 160.549 70.85) (mid 160.490268 70.991791) (end 160.348477 71.050523) (width 0.143) (layer "In9.Cu") (net 343))
  (arc (start 178.362448 74.572448) (mid 178.406382 74.466382) (end 178.512448 74.422448) (width 0.143) (layer "In9.Cu") (net 343))
  (arc (start 160.250523 71.050523) (mid 160.108732 70.991791) (end 160.05 70.85) (width 0.143) (layer "In9.Cu") (net 343))
  (arc (start 158.949 70.048977) (mid 158.890268 70.190768) (end 158.748477 70.2495) (width 0.143) (layer "In9.Cu") (net 343))
  (arc (start 178.512448 74.122448) (mid 178.406382 74.078514) (end 178.362448 73.972448) (width 0.143) (layer "In9.Cu") (net 343))
  (arc (start 178.512448 73.522448) (mid 178.406382 73.478514) (end 178.362448 73.372448) (width 0.143) (layer "In9.Cu") (net 343))
  (arc (start 178.743901 74.872448) (mid 178.699967 74.766382) (end 178.593901 74.722448) (width 0.143) (layer "In9.Cu") (net 343))
  (arc (start 178.362448 75.172448) (mid 178.406382 75.066382) (end 178.512448 75.022448) (width 0.143) (layer "In9.Cu") (net 343))
  (arc (start 178.743901 74.272448) (mid 178.699967 74.166382) (end 178.593901 74.122448) (width 0.143) (layer "In9.Cu") (net 343))
  (arc (start 161.836442 70.299) (mid 161.704238 70.244239) (end 161.649477 70.112035) (width 0.143) (layer "In9.Cu") (net 343))
  (arc (start 159.450523 69.396953) (mid 159.095893 69.543846) (end 158.949 69.898476) (width 0.143) (layer "In9.Cu") (net 343))
  (arc (start 178.593901 73.822448) (mid 178.699967 73.778514) (end 178.743901 73.672448) (width 0.143) (layer "In9.Cu") (net 343))
  (arc (start 178.743901 73.672448) (mid 178.699967 73.566382) (end 178.593901 73.522448) (width 0.143) (layer "In9.Cu") (net 343))
  (arc (start 161.649477 69.947976) (mid 161.502584 69.593346) (end 161.147954 69.446453) (width 0.143) (layer "In9.Cu") (net 343))
  (arc (start 178.362448 73.972448) (mid 178.406382 73.866382) (end 178.512448 73.822448) (width 0.143) (layer "In9.Cu") (net 343))
  (arc (start 178.593901 74.422448) (mid 178.699967 74.378514) (end 178.743901 74.272448) (width 0.143) (layer "In9.Cu") (net 343))
  (segment (start 129.336328 59.660008) (end 129.336328 60.960008) (width 0.1) (layer "F.Cu") (net 344))
  (segment (start 180.136328 85.560008) (end 179.636328 85.060008) (width 0.127) (layer "F.Cu") (net 344))
  (via (at 129.336328 60.960008) (size 0.5) (drill 0.2) (layers "F.Cu" "B.Cu") (net 344))
  (via (at 179.636328 85.060008) (size 0.5) (drill 0.2) (layers "F.Cu" "B.Cu") (net 344))
  (segment (start 179.175 85.2952) (end 179.384816 85.505016) (width 0.1) (layer "In9.Cu") (net 344))
  (segment (start 179.900008 85.060008) (end 179.636328 85.060008) (width 0.1) (layer "In9.Cu") (net 344))
  (segment (start 179.384816 85.505016) (end 179.867432 85.505016) (width 0.1) (layer "In9.Cu") (net 344))
  (segment (start 180.001328 85.161328) (end 179.900008 85.060008) (width 0.1) (layer "In9.Cu") (net 344))
  (segment (start 177.44877 74.16677) (end 177.44877 73.32593) (width 0.143) (layer "In9.Cu") (net 344))
  (segment (start 162.06234 72.0495) (end 161.6505 72.0495) (width 0.143) (layer "In9.Cu") (net 344))
  (segment (start 177.44877 75.430223) (end 177.44877 75.338766) (width 0.143) (layer "In9.Cu") (net 344))
  (segment (start 135.86877 71.90593) (end 129.061829 65.098989) (width 0.143) (layer "In9.Cu") (net 344))
  (segment (start 161.15643 72.54357) (end 161.15643 72.69407) (width 0.143) (layer "In9.Cu") (net 344))
  (segment (start 177.44877 75.430223) (end 177.435 75.443993) (width 0.1) (layer "In9.Cu") (net 344))
  (segment (start 179.867432 85.505016) (end 180.001328 85.37112) (width 0.1) (layer "In9.Cu") (net 344))
  (segment (start 179.315 84.32087) (end 179.175 84.46087) (width 0.1) (layer "In9.Cu") (net 344))
  (segment (start 160.96336 72.88714) (end 160.9005 72.88714) (width 0.143) (layer "In9.Cu") (net 344))
  (segment (start 177.564706 74.343835) (end 177.564705 74.343835) (width 0.143) (layer "In9.Cu") (net 344))
  (segment (start 177.44877 74.2279) (end 177.44877 74.16677) (width 0.143) (layer "In9.Cu") (net 344))
  (segment (start 179.315 82.39408) (end 179.315 84.32087) (width 0.1) (layer "In9.Cu") (net 344))
  (segment (start 160.21336 71.90593) (end 135.86877 71.90593) (width 0.143) (layer "In9.Cu") (net 344))
  (segment (start 177.115 76.95592) (end 177.115 80.19408) (width 0.1) (layer "In9.Cu") (net 344))
  (segment (start 177.680641 75.1069) (end 177.680641 75.045768) (width 0.143) (layer "In9.Cu") (net 344))
  (segment (start 177.564705 75.222835) (end 177.564706 75.222835) (width 0.143) (layer "In9.Cu") (net 344))
  (segment (start 162.36234 72.3495) (end 162.06234 72.0495) (width 0.143) (layer "In9.Cu") (net 344))
  (segment (start 129.061829 65.098989) (end 129.061829 61.234507) (width 0.143) (layer "In9.Cu") (net 344))
  (segment (start 177.564706 74.929835) (end 177.564705 74.929835) (width 0.143) (layer "In9.Cu") (net 344))
  (segment (start 180.001328 85.37112) (end 180.001328 85.161328) (width 0.1) (layer "In9.Cu") (net 344))
  (segment (start 176.47234 72.3495) (end 162.36234 72.3495) (width 0.143) (layer "In9.Cu") (net 344))
  (segment (start 177.115 80.19408) (end 179.315 82.39408) (width 0.1) (layer "In9.Cu") (net 344))
  (segment (start 177.44877 73.32593) (end 176.47234 72.3495) (width 0.143) (layer "In9.Cu") (net 344))
  (segment (start 177.44877 74.813912) (end 177.44877 74.752758) (width 0.143) (layer "In9.Cu") (net 344))
  (segment (start 129.061829 61.234507) (end 129.336328 60.960008) (width 0.143) (layer "In9.Cu") (net 344))
  (segment (start 177.564705 74.636835) (end 177.564706 74.636835) (width 0.143) (layer "In9.Cu") (net 344))
  (segment (start 179.175 84.46087) (end 179.175 85.2952) (width 0.1) (layer "In9.Cu") (net 344))
  (segment (start 160.70743 72.69407) (end 160.70743 72.4) (width 0.143) (layer "In9.Cu") (net 344))
  (segment (start 177.435 75.443993) (end 177.435 76.63592) (width 0.1) (layer "In9.Cu") (net 344))
  (segment (start 177.680641 74.520895) (end 177.680641 74.459781) (width 0.143) (layer "In9.Cu") (net 344))
  (segment (start 177.435 76.63592) (end 177.115 76.95592) (width 0.1) (layer "In9.Cu") (net 344))
  (arc (start 160.70743 72.4) (mid 160.56272 72.05064) (end 160.21336 71.90593) (width 0.143) (layer "In9.Cu") (net 344))
  (arc (start 177.44877 74.752758) (mid 177.482725 74.670786) (end 177.564705 74.636835) (width 0.143) (layer "In9.Cu") (net 344))
  (arc (start 177.564706 74.636835) (mid 177.646685 74.602875) (end 177.680641 74.520895) (width 0.143) (layer "In9.Cu") (net 344))
  (arc (start 160.9005 72.88714) (mid 160.763979 72.830591) (end 160.70743 72.69407) (width 0.143) (layer "In9.Cu") (net 344))
  (arc (start 177.680641 75.045768) (mid 177.646687 74.963792) (end 177.564706 74.929835) (width 0.143) (layer "In9.Cu") (net 344))
  (arc (start 177.44877 75.338766) (mid 177.482727 75.256788) (end 177.564705 75.222835) (width 0.143) (layer "In9.Cu") (net 344))
  (arc (start 161.15643 72.69407) (mid 161.099881 72.830591) (end 160.96336 72.88714) (width 0.143) (layer "In9.Cu") (net 344))
  (arc (start 161.6505 72.0495) (mid 161.30114 72.19421) (end 161.15643 72.54357) (width 0.143) (layer "In9.Cu") (net 344))
  (arc (start 177.564706 75.222835) (mid 177.646684 75.188878) (end 177.680641 75.1069) (width 0.143) (layer "In9.Cu") (net 344))
  (arc (start 177.680641 74.459781) (mid 177.646683 74.377796) (end 177.564706 74.343835) (width 0.143) (layer "In9.Cu") (net 344))
  (arc (start 177.564705 74.929835) (mid 177.482726 74.895884) (end 177.44877 74.813912) (width 0.143) (layer "In9.Cu") (net 344))
  (arc (start 177.564705 74.343835) (mid 177.482727 74.309878) (end 177.44877 74.2279) (width 0.143) (layer "In9.Cu") (net 344))
  (segment (start 129.636328 56.43501) (end 129.436328 56.63501) (width 0.1) (layer "F.Cu") (net 345))
  (segment (start 181.136328 84.560008) (end 180.636328 84.060008) (width 0.127) (layer "F.Cu") (net 345))
  (segment (start 129.636328 55.975008) (end 129.636328 56.43501) (width 0.1) (layer "F.Cu") (net 345))
  (segment (start 129.336328 55.675008) (end 129.636328 55.975008) (width 0.1) (layer "F.Cu") (net 345))
  (via (at 180.636328 84.060008) (size 0.5) (drill 0.2) (layers "F.Cu" "B.Cu") (net 345))
  (via (at 129.436328 56.63501) (size 0.5) (drill 0.2) (layers "F.Cu" "B.Cu") (net 345))
  (segment (start 136.13766 70.5505) (end 130.0995 64.51234) (width 0.143) (layer "In9.Cu") (net 345))
  (segment (start 180.77408 83.615) (end 180.28408 83.615) (width 0.1) (layer "In9.Cu") (net 345))
  (segment (start 130.0995 59.81234) (end 129.610827 59.323667) (width 0.143) (layer "In9.Cu") (net 345))
  (segment (start 163.23766 71.6505) (end 162.18716 70.6) (width 0.143) (layer "In9.Cu") (net 345))
  (segment (start 180.929992 84.060008) (end 181.001328 83.988672) (width 0.1) (layer "In9.Cu") (net 345))
  (segment (start 178.061448 75.389984) (end 178.061448 72.944288) (width 0.143) (layer "In9.Cu") (net 345))
  (segment (start 129.610827 59.323667) (end 129.610827 56.809509) (width 0.143) (layer "In9.Cu") (net 345))
  (segment (start 130.0995 64.51234) (end 130.0995 59.81234) (width 0.143) (layer "In9.Cu") (net 345))
  (segment (start 159.548477 69.697953) (end 159.450523 69.697953) (width 0.143) (layer "In9.Cu") (net 345))
  (segment (start 178.08059 78.78151) (end 178.08059 75.409126) (width 0.1) (layer "In9.Cu") (net 345))
  (segment (start 162.18716 70.6) (end 161.832792 70.6) (width 0.143) (layer "In9.Cu") (net 345))
  (segment (start 179.565 80.26592) (end 178.08059 78.78151) (width 0.1) (layer "In9.Cu") (net 345))
  (segment (start 179.565 82.89592) (end 179.565 80.26592) (width 0.1) (layer "In9.Cu") (net 345))
  (segment (start 160.348477 71.351523) (end 160.250523 71.351523) (width 0.143) (layer "In9.Cu") (net 345))
  (segment (start 181.001328 83.842248) (end 180.77408 83.615) (width 0.1) (layer "In9.Cu") (net 345))
  (segment (start 129.610827 56.809509) (end 129.436328 56.63501) (width 0.143) (layer "In9.Cu") (net 345))
  (segment (start 158.748477 70.5505) (end 136.13766 70.5505) (width 0.143) (layer "In9.Cu") (net 345))
  (segment (start 180.636328 84.060008) (end 180.929992 84.060008) (width 0.1) (layer "In9.Cu") (net 345))
  (segment (start 176.76766 71.6505) (end 163.23766 71.6505) (width 0.143) (layer "In9.Cu") (net 345))
  (segment (start 160.85 70.85) (end 160.85 70.099) (width 0.143) (layer "In9.Cu") (net 345))
  (segment (start 160.849477 69.947976) (end 160.849477 70.098477) (width 0.143) (layer "In9.Cu") (net 345))
  (segment (start 180.28408 83.615) (end 179.565 82.89592) (width 0.1) (layer "In9.Cu") (net 345))
  (segment (start 159.749 69.898476) (end 159.749 70.85) (width 0.143) (layer "In9.Cu") (net 345))
  (segment (start 181.001328 83.988672) (end 181.001328 83.842248) (width 0.1) (layer "In9.Cu") (net 345))
  (segment (start 161.147954 69.747453) (end 161.05 69.747453) (width 0.143) (layer "In9.Cu") (net 345))
  (segment (start 159.25 69.898476) (end 159.25 70.048977) (width 0.143) (layer "In9.Cu") (net 345))
  (segment (start 178.08059 75.409126) (end 178.061448 75.389984) (width 0.1) (layer "In9.Cu") (net 345))
  (segment (start 161.348477 70.115685) (end 161.348477 69.947976) (width 0.143) (layer "In9.Cu") (net 345))
  (segment (start 160.849477 70.098477) (end 160.85 70.099) (width 0.143) (layer "In9.Cu") (net 345))
  (segment (start 178.061448 72.944288) (end 176.76766 71.6505) (width 0.143) (layer "In9.Cu") (net 345))
  (arc (start 160.85 70.85) (mid 160.703107 71.20463) (end 160.348477 71.351523) (width 0.143) (layer "In9.Cu") (net 345))
  (arc (start 161.832792 70.6) (mid 161.49033 70.458147) (end 161.348477 70.115685) (width 0.143) (layer "In9.Cu") (net 345))
  (arc (start 159.450523 69.697953) (mid 159.308732 69.756685) (end 159.25 69.898476) (width 0.143) (layer "In9.Cu") (net 345))
  (arc (start 159.25 70.048977) (mid 159.103107 70.403607) (end 158.748477 70.5505) (width 0.143) (layer "In9.Cu") (net 345))
  (arc (start 161.348477 69.947976) (mid 161.289745 69.806185) (end 161.147954 69.747453) (width 0.143) (layer "In9.Cu") (net 345))
  (arc (start 160.250523 71.351523) (mid 159.895893 71.20463) (end 159.749 70.85) (width 0.143) (layer "In9.Cu") (net 345))
  (arc (start 159.749 69.898476) (mid 159.690268 69.756685) (end 159.548477 69.697953) (width 0.143) (layer "In9.Cu") (net 345))
  (arc (start 161.05 69.747453) (mid 160.908209 69.806185) (end 160.849477 69.947976) (width 0.143) (layer "In9.Cu") (net 345))
  (segment (start 202.711327 60.685009) (end 202.436328 60.960008) (width 0.1) (layer "F.Cu") (net 346))
  (segment (start 202.711328 60.550008) (end 202.711327 60.685009) (width 0.1) (layer "F.Cu") (net 346))
  (segment (start 202.436328 60.275008) (end 202.711328 60.550008) (width 0.1) (layer "F.Cu") (net 346))
  (segment (start 202.436328 59.660008) (end 202.436328 60.275008) (width 0.1) (layer "F.Cu") (net 346))
  (segment (start 178.136328 89.560008) (end 177.636328 89.060008) (width 0.127) (layer "F.Cu") (net 346))
  (via (at 202.436328 60.960008) (size 0.5) (drill 0.2) (layers "F.Cu" "B.Cu") (net 346))
  (via (at 177.636328 89.060008) (size 0.5) (drill 0.2) (layers "F.Cu" "B.Cu") (net 346))
  (segment (start 188.165132 67.881545) (end 199.031975 67.881545) (width 0.166) (layer "In7.Cu") (net 346))
  (segment (start 177.086192 87.050939) (end 177.104968 87.032164) (width 0.09) (layer "In7.Cu") (net 346))
  (segment (start 177.63632 89.06) (end 177.34 89.06) (width 0.09) (layer "In7.Cu") (net 346))
  (segment (start 176.905 82.749938) (end 177.915 81.739938) (width 0.09) (layer "In7.Cu") (net 346))
  (segment (start 185.348619 67.374901) (end 184.988422 67.735098) (width 0.166) (layer "In7.Cu") (net 346))
  (segment (start 182.124993 67.118832) (end 182.495007 67.118832) (width 0.166) (layer "In7.Cu") (net 346))
  (segment (start 187.45 67.374902) (end 187.451382 67.374902) (width 0.166) (layer "In7.Cu") (net 346))
  (segment (start 178.3126 75.5126) (end 178.3126 70.63092) (width 0.166) (layer "In7.Cu") (net 346))
  (segment (start 178.147327 89.552623) (end 178.147328 89.552621) (width 0.09) (layer "In7.Cu") (net 346))
  (segment (start 177.3171 87.244294) (end 177.298325 87.26307) (width 0.09) (layer "In7.Cu") (net 346))
  (segment (start 177.620062 89.775) (end 178.094654 89.775) (width 0.09) (layer "In7.Cu") (net 346))
  (segment (start 178.555 88.38) (end 178.555 88.270062) (width 0.09) (layer "In7.Cu") (net 346))
  (segment (start 177.281328 89.436266) (end 177.620062 89.775) (width 0.09) (layer "In7.Cu") (net 346))
  (segment (start 187.451382 67.374902) (end 187.811579 67.735099) (width 0.166) (layer "In7.Cu") (net 346))
  (segment (start 177.34 89.06) (end 177.281328 89.118672) (width 0.09) (layer "In7.Cu") (net 346))
  (segment (start 186.937347 67.162554) (end 185.862652 67.162554) (width 0.166) (layer "In7.Cu") (net 346))
  (segment (start 199.031975 67.881545) (end 202.665828 64.247692) (width 0.166) (layer "In7.Cu") (net 346))
  (segment (start 176.905 86.620062) (end 176.905 82.749938) (width 0.09) (layer "In7.Cu") (net 346))
  (segment (start 178.355 78.019938) (end 178.355 75.555) (width 0.09) (layer "In7.Cu") (net 346))
  (segment (start 185.35 67.374901) (end 185.348619 67.374901) (width 0.166) (layer "In7.Cu") (net 346))
  (segment (start 178.309962 89.375846) (end 178.317034 89.382918) (width 0.09) (layer "In7.Cu") (net 346))
  (segment (start 178.094654 89.775) (end 178.147327 89.722327) (width 0.09) (layer "In7.Cu") (net 346))
  (segment (start 178.486739 89.382917) (end 178.555 89.314654) (width 0.09) (layer "In7.Cu") (net 346))
  (segment (start 177.281328 89.118672) (end 177.281328 89.436266) (width 0.09) (layer "In7.Cu") (net 346))
  (segment (start 178.147328 89.552621) (end 178.140257 89.54555) (width 0.09) (layer "In7.Cu") (net 346))
  (segment (start 178.355 75.555) (end 178.3126 75.5126) (width 0.09) (layer "In7.Cu") (net 346))
  (segment (start 177.636328 89.060008) (end 177.63632 89.06) (width 0.09) (layer "In7.Cu") (net 346))
  (segment (start 178.140258 89.375845) (end 178.140256 89.375846) (width 0.09) (layer "In7.Cu") (net 346))
  (segment (start 178.555 88.270062) (end 177.529232 87.244294) (width 0.09) (layer "In7.Cu") (net 346))
  (segment (start 177.104969 86.820031) (end 176.905 86.620062) (width 0.09) (layer "In7.Cu") (net 346))
  (segment (start 177.915 81.739938) (end 177.915 78.459938) (width 0.09) (layer "In7.Cu") (net 346))
  (segment (start 183.765132 67.881545) (end 184.634868 67.881545) (width 0.166) (layer "In7.Cu") (net 346))
  (segment (start 178.3126 70.63092) (end 181.612341 67.331179) (width 0.166) (layer "In7.Cu") (net 346))
  (segment (start 202.665828 61.189508) (end 202.436328 60.960008) (width 0.166) (layer "In7.Cu") (net 346))
  (segment (start 202.665828 64.247692) (end 202.665828 61.189508) (width 0.166) (layer "In7.Cu") (net 346))
  (segment (start 178.555 89.314654) (end 178.555 88.88) (width 0.09) (layer "In7.Cu") (net 346))
  (segment (start 177.915 78.459938) (end 178.355 78.019938) (width 0.09) (layer "In7.Cu") (net 346))
  (segment (start 183.00766 67.33118) (end 183.411579 67.735099) (width 0.166) (layer "In7.Cu") (net 346))
  (arc (start 186.937347 67.162554) (mid 187.214793 67.217741) (end 187.45 67.374902) (width 0.166) (layer "In7.Cu") (net 346))
  (arc (start 177.529232 87.244294) (mid 177.423166 87.20036) (end 177.3171 87.244294) (width 0.09) (layer "In7.Cu") (net 346))
  (arc (start 182.495007 67.118832) (mid 182.772453 67.174019) (end 183.00766 67.33118) (width 0.166) (layer "In7.Cu") (net 346))
  (arc (start 178.140256 89.375846) (mid 178.225109 89.340699) (end 178.309962 89.375846) (width 0.09) (layer "In7.Cu") (net 346))
  (arc (start 182.124993 67.118832) (mid 181.847548 67.174019) (end 181.612341 67.331179) (width 0.166) (layer "In7.Cu") (net 346))
  (arc (start 183.411579 67.735099) (mid 183.573791 67.843485) (end 183.765132 67.881545) (width 0.166) (layer "In7.Cu") (net 346))
  (arc (start 177.086192 87.263071) (mid 177.042258 87.157005) (end 177.086192 87.050939) (width 0.09) (layer "In7.Cu") (net 346))
  (arc (start 178.555 88.88) (mid 178.518388 88.791612) (end 178.43 88.755) (width 0.09) (layer "In7.Cu") (net 346))
  (arc (start 177.104968 87.032164) (mid 177.148903 86.926098) (end 177.104969 86.820031) (width 0.09) (layer "In7.Cu") (net 346))
  (arc (start 178.305 88.63) (mid 178.341612 88.541612) (end 178.43 88.505) (width 0.09) (layer "In7.Cu") (net 346))
  (arc (start 184.634868 67.881545) (mid 184.82621 67.843485) (end 184.988422 67.735098) (width 0.166) (layer "In7.Cu") (net 346))
  (arc (start 178.43 88.505) (mid 178.518388 88.468388) (end 178.555 88.38) (width 0.09) (layer "In7.Cu") (net 346))
  (arc (start 177.298325 87.26307) (mid 177.192259 87.307005) (end 177.086192 87.263071) (width 0.09) (layer "In7.Cu") (net 346))
  (arc (start 178.43 88.755) (mid 178.341612 88.718388) (end 178.305 88.63) (width 0.09) (layer "In7.Cu") (net 346))
  (arc (start 178.147327 89.722327) (mid 178.182475 89.637474) (end 178.147327 89.552623) (width 0.09) (layer "In7.Cu") (net 346))
  (arc (start 178.317034 89.382918) (mid 178.401887 89.418065) (end 178.486739 89.382917) (width 0.09) (layer "In7.Cu") (net 346))
  (arc (start 178.140257 89.54555) (mid 178.10511 89.460697) (end 178.140258 89.375845) (width 0.09) (layer "In7.Cu") (net 346))
  (arc (start 185.862652 67.162554) (mid 185.585207 67.217741) (end 185.35 67.374901) (width 0.166) (layer "In7.Cu") (net 346))
  (arc (start 187.811579 67.735099) (mid 187.973791 67.843485) (end 188.165132 67.881545) (width 0.166) (layer "In7.Cu") (net 346))
  (segment (start 203.861329 56.460011) (end 204.036328 56.63501) (width 0.1) (layer "F.Cu") (net 347))
  (segment (start 203.861328 55.950008) (end 203.861329 56.460011) (width 0.1) (layer "F.Cu") (net 347))
  (segment (start 204.136328 55.060008) (end 204.136328 55.675008) (width 0.1) (layer "F.Cu") (net 347))
  (segment (start 204.136328 55.675008) (end 203.861328 55.950008) (width 0.1) (layer "F.Cu") (net 347))
  (segment (start 180.636328 89.060008) (end 181.136328 88.560008) (width 0.127) (layer "F.Cu") (net 347))
  (via (at 180.636328 89.060008) (size 0.5) (drill 0.2) (layers "F.Cu" "B.Cu") (net 347))
  (via (at 204.036328 56.63501) (size 0.5) (drill 0.2) (layers "F.Cu" "B.Cu") (net 347))
  (segment (start 186.874548 69.6855) (end 187.460892 69.6855) (width 0.166) (layer "In7.Cu") (net 347))
  (segment (start 179.59681 72.07967) (end 181.361151 70.315329) (width 0.166) (layer "In7.Cu") (net 347))
  (segment (start 198.116636 69.745719) (end 198.410184 70.039267) (width 0.166) (layer "In7.Cu") (net 347))
  (segment (start 179.59681 75.49681) (end 179.59681 72.07967) (width 0.166) (layer "In7.Cu") (net 347))
  (segment (start 179.301106 82.503956) (end 179.665 82.140062) (width 0.09) (layer "In7.Cu") (net 347))
  (segment (start 189.397328 69.68632) (end 190.021712 69.68632) (width 0.166) (layer "In7.Cu") (net 347))
  (segment (start 187.602314 69.744079) (end 187.829961 69.971726) (width 0.166) (layer "In7.Cu") (net 347))
  (segment (start 185.079534 69.743259) (end 185.307181 69.970906) (width 0.166) (layer "In7.Cu") (net 347))
  (segment (start 192.685914 69.745719) (end 192.913561 69.973366) (width 0.166) (layer "In7.Cu") (net 347))
  (segment (start 204.3555 59.67902) (end 203.906828 59.230348) (width 0.166) (layer "In7.Cu") (net 347))
  (segment (start 180.281328 88.981328) (end 180.281328 88.366266) (width 0.09) (layer "In7.Cu") (net 347))
  (segment (start 203.906828 59.230348) (end 203.906828 56.76451) (width 0.166) (layer "In7.Cu") (net 347))
  (segment (start 186.5063 69.970905) (end 186.733127 69.744078) (width 0.166) (layer "In7.Cu") (net 347))
  (segment (start 194.313 69.973365) (end 194.540647 69.745718) (width 0.166) (layer "In7.Cu") (net 347))
  (segment (start 194.682068 69.68714) (end 195.306452 69.68714) (width 0.166) (layer "In7.Cu") (net 347))
  (segment (start 181.891481 70.095659) (end 183.681905 70.095659) (width 0.166) (layer "In7.Cu") (net 347))
  (segment (start 179.301106 84.720956) (end 179.301106 82.503956) (width 0.09) (layer "In7.Cu") (net 347))
  (segment (start 190.691301 70.097025) (end 191.251339 70.097025) (width 0.166) (layer "In7.Cu") (net 347))
  (segment (start 183.681905 70.095659) (end 183.682999 70.094565) (width 0.166) (layer "In7.Cu") (net 347))
  (segment (start 193.214081 70.097845) (end 194.012479 70.097845) (width 0.166) (layer "In7.Cu") (net 347))
  (segment (start 185.607701 70.095385) (end 186.205779 70.095385) (width 0.166) (layer "In7.Cu") (net 347))
  (segment (start 195.882843 70.097845) (end 196.681241 70.097845) (width 0.166) (layer "In7.Cu") (net 347))
  (segment (start 198.551605 70.097845) (end 199.225487 70.097845) (width 0.166) (layer "In7.Cu") (net 347))
  (segment (start 184.351768 69.68468) (end 184.938112 69.68468) (width 0.166) (layer "In7.Cu") (net 347))
  (segment (start 191.920108 69.68714) (end 192.544492 69.68714) (width 0.166) (layer "In7.Cu") (net 347))
  (segment (start 183.98352 69.970085) (end 184.210347 69.743258) (width 0.166) (layer "In7.Cu") (net 347))
  (segment (start 180.281328 88.366266) (end 179.219 87.303938) (width 0.09) (layer "In7.Cu") (net 347))
  (segment (start 179.545 75.595) (end 179.59681 75.54319) (width 0.09) (layer "In7.Cu") (net 347))
  (segment (start 180.636328 89.060008) (end 180.360008 89.060008) (width 0.09) (layer "In7.Cu") (net 347))
  (segment (start 179.219 87.303938) (end 179.219 84.803062) (width 0.09) (layer "In7.Cu") (net 347))
  (segment (start 199.879561 69.826919) (end 204.3555 65.35098) (width 0.166) (layer "In7.Cu") (net 347))
  (segment (start 179.665 82.140062) (end 179.665 79.875079) (width 0.09) (layer "In7.Cu") (net 347))
  (segment (start 179.545 78.460062) (end 179.545 75.595) (width 0.09) (layer "In7.Cu") (net 347))
  (segment (start 197.35083 69.68714) (end 197.975214 69.68714) (width 0.166) (layer "In7.Cu") (net 347))
  (segment (start 179.59681 75.54319) (end 179.59681 75.49681) (width 0.09) (layer "In7.Cu") (net 347))
  (segment (start 179.157556 78.847506) (end 179.545 78.460062) (width 0.09) (layer "In7.Cu") (net 347))
  (segment (start 203.906828 56.76451) (end 204.036328 56.63501) (width 0.166) (layer "In7.Cu") (net 347))
  (segment (start 189.02908 69.971725) (end 189.255907 69.744898) (width 0.166) (layer "In7.Cu") (net 347))
  (segment (start 179.665 79.875079) (end 179.157556 79.367635) (width 0.09) (layer "In7.Cu") (net 347))
  (segment (start 190.163134 69.744899) (end 190.390781 69.972546) (width 0.166) (layer "In7.Cu") (net 347))
  (segment (start 204.3555 65.35098) (end 204.3555 59.67902) (width 0.166) (layer "In7.Cu") (net 347))
  (segment (start 195.447874 69.745719) (end 195.741422 70.039267) (width 0.166) (layer "In7.Cu") (net 347))
  (segment (start 196.981762 69.973365) (end 197.209409 69.745718) (width 0.166) (layer "In7.Cu") (net 347))
  (segment (start 188.130481 70.096205) (end 188.728559 70.096205) (width 0.166) (layer "In7.Cu") (net 347))
  (segment (start 180.360008 89.060008) (end 180.281328 88.981328) (width 0.09) (layer "In7.Cu") (net 347))
  (segment (start 191.55186 69.972545) (end 191.778687 69.745718) (width 0.166) (layer "In7.Cu") (net 347))
  (segment (start 179.157556 79.367635) (end 179.157556 78.847506) (width 0.09) (layer "In7.Cu") (net 347))
  (segment (start 179.219 84.803062) (end 179.301106 84.720956) (width 0.09) (layer "In7.Cu") (net 347))
  (arc (start 195.741422 70.039267) (mid 195.806307 70.082621) (end 195.882843 70.097845) (width 0.166) (layer "In7.Cu") (net 347))
  (arc (start 198.410184 70.039267) (mid 198.475069 70.082621) (end 198.551605 70.097845) (width 0.166) (layer "In7.Cu") (net 347))
  (arc (start 199.225487 70.097845) (mid 199.579469 70.027434) (end 199.879561 69.826919) (width 0.166) (layer "In7.Cu") (net 347))
  (arc (start 196.681241 70.097845) (mid 196.843882 70.065494) (end 196.981762 69.973365) (width 0.166) (layer "In7.Cu") (net 347))
  (arc (start 185.307181 69.970906) (mid 185.445061 70.063034) (end 185.607701 70.095385) (width 0.166) (layer "In7.Cu") (net 347))
  (arc (start 190.021712 69.68632) (mid 190.098249 69.701544) (end 190.163134 69.744899) (width 0.166) (layer "In7.Cu") (net 347))
  (arc (start 186.205779 70.095385) (mid 186.36842 70.063034) (end 186.5063 69.970905) (width 0.166) (layer "In7.Cu") (net 347))
  (arc (start 188.728559 70.096205) (mid 188.8912 70.063854) (end 189.02908 69.971725) (width 0.166) (layer "In7.Cu") (net 347))
  (arc (start 181.361151 70.315329) (mid 181.604468 70.152749) (end 181.891481 70.095659) (width 0.166) (layer "In7.Cu") (net 347))
  (arc (start 191.251339 70.097025) (mid 191.41398 70.064674) (end 191.55186 69.972545) (width 0.166) (layer "In7.Cu") (net 347))
  (arc (start 192.544492 69.68714) (mid 192.621029 69.702364) (end 192.685914 69.745719) (width 0.166) (layer "In7.Cu") (net 347))
  (arc (start 197.209409 69.745718) (mid 197.274294 69.702364) (end 197.35083 69.68714) (width 0.166) (layer "In7.Cu") (net 347))
  (arc (start 194.012479 70.097845) (mid 194.17512 70.065494) (end 194.313 69.973365) (width 0.166) (layer "In7.Cu") (net 347))
  (arc (start 191.778687 69.745718) (mid 191.843572 69.702364) (end 191.920108 69.68714) (width 0.166) (layer "In7.Cu") (net 347))
  (arc (start 192.913561 69.973366) (mid 193.051441 70.065494) (end 193.214081 70.097845) (width 0.166) (layer "In7.Cu") (net 347))
  (arc (start 194.540647 69.745718) (mid 194.605532 69.702364) (end 194.682068 69.68714) (width 0.166) (layer "In7.Cu") (net 347))
  (arc (start 195.306452 69.68714) (mid 195.382989 69.702364) (end 195.447874 69.745719) (width 0.166) (layer "In7.Cu") (net 347))
  (arc (start 187.829961 69.971726) (mid 187.967841 70.063854) (end 188.130481 70.096205) (width 0.166) (layer "In7.Cu") (net 347))
  (arc (start 197.975214 69.68714) (mid 198.051751 69.702364) (end 198.116636 69.745719) (width 0.166) (layer "In7.Cu") (net 347))
  (arc (start 186.733127 69.744078) (mid 186.798012 69.700724) (end 186.874548 69.6855) (width 0.166) (layer "In7.Cu") (net 347))
  (arc (start 190.390781 69.972546) (mid 190.528661 70.064674) (end 190.691301 70.097025) (width 0.166) (layer "In7.Cu") (net 347))
  (arc (start 184.210347 69.743258) (mid 184.275232 69.699904) (end 184.351768 69.68468) (width 0.166) (layer "In7.Cu") (net 347))
  (arc (start 189.255907 69.744898) (mid 189.320792 69.701544) (end 189.397328 69.68632) (width 0.166) (layer "In7.Cu") (net 347))
  (arc (start 187.460892 69.6855) (mid 187.537429 69.700724) (end 187.602314 69.744079) (width 0.166) (layer "In7.Cu") (net 347))
  (arc (start 183.682999 70.094565) (mid 183.84564 70.062214) (end 183.98352 69.970085) (width 0.166) (layer "In7.Cu") (net 347))
  (arc (start 184.938112 69.68468) (mid 185.014649 69.699904) (end 185.079534 69.743259) (width 0.166) (layer "In7.Cu") (net 347))
  (segment (start 203.011329 60.685009) (end 203.286328 60.960008) (width 0.1) (layer "F.Cu") (net 348))
  (segment (start 203.286328 59.660008) (end 203.286328 60.275008) (width 0.1) (layer "F.Cu") (net 348))
  (segment (start 203.011328 60.550008) (end 203.011329 60.685009) (width 0.1) (layer "F.Cu") (net 348))
  (segment (start 177.136328 89.560008) (end 176.636328 89.060008) (width 0.127) (layer "F.Cu") (net 348))
  (segment (start 203.286328 60.275008) (end 203.011328 60.550008) (width 0.1) (layer "F.Cu") (net 348))
  (via (at 203.286328 60.960008) (size 0.5) (drill 0.2) (layers "F.Cu" "B.Cu") (net 348))
  (via (at 176.636328 89.060008) (size 0.5) (drill 0.2) (layers "F.Cu" "B.Cu") (net 348))
  (segment (start 188.09637 68.272545) (end 199.193935 68.272545) (width 0.166) (layer "In7.Cu") (net 348))
  (segment (start 182.193755 67.509832) (end 182.426245 67.509832) (width 0.166) (layer "In7.Cu") (net 348))
  (segment (start 185.931414 67.553554) (end 186.868585 67.553554) (width 0.166) (layer "In7.Cu") (net 348))
  (segment (start 185.57648 67.7) (end 185.216283 68.060197) (width 0.166) (layer "In7.Cu") (net 348))
  (segment (start 178.845 89.434778) (end 178.845 88.149938) (width 0.09) (layer "In7.Cu") (net 348))
  (segment (start 178.845 88.149938) (end 177.195 86.499938) (width 0.09) (layer "In7.Cu") (net 348))
  (segment (start 203.056828 64.409652) (end 203.056828 61.189508) (width 0.166) (layer "In7.Cu") (net 348))
  (segment (start 177.499938 90.065) (end 178.214778 90.065) (width 0.09) (layer "In7.Cu") (net 348))
  (segment (start 176.636328 89.060008) (end 176.920008 89.060008) (width 0.09) (layer "In7.Cu") (net 348))
  (segment (start 176.920008 89.060008) (end 176.991328 89.131328) (width 0.09) (layer "In7.Cu") (net 348))
  (segment (start 178.645 78.140062) (end 178.645 75.5586) (width 0.09) (layer "In7.Cu") (net 348))
  (segment (start 203.056828 61.189508) (end 203.286328 60.960008) (width 0.166) (layer "In7.Cu") (net 348))
  (segment (start 177.195 82.870062) (end 178.205 81.860062) (width 0.09) (layer "In7.Cu") (net 348))
  (segment (start 187.223521 67.700001) (end 187.583718 68.060198) (width 0.166) (layer "In7.Cu") (net 348))
  (segment (start 178.205 78.580062) (end 178.645 78.140062) (width 0.09) (layer "In7.Cu") (net 348))
  (segment (start 183.69637 68.272545) (end 184.70363 68.272545) (width 0.166) (layer "In7.Cu") (net 348))
  (segment (start 199.193935 68.272545) (end 203.056828 64.409652) (width 0.166) (layer "In7.Cu") (net 348))
  (segment (start 178.7036 75.5) (end 178.7036 70.79288) (width 0.166) (layer "In7.Cu") (net 348))
  (segment (start 176.991328 89.55639) (end 177.499938 90.065) (width 0.09) (layer "In7.Cu") (net 348))
  (segment (start 187.222139 67.700001) (end 187.223521 67.700001) (width 0.166) (layer "In7.Cu") (net 348))
  (segment (start 177.195 86.499938) (end 177.195 82.870062) (width 0.09) (layer "In7.Cu") (net 348))
  (segment (start 178.7036 70.79288) (end 181.840202 67.656278) (width 0.166) (layer "In7.Cu") (net 348))
  (segment (start 176.991328 89.131328) (end 176.991328 89.55639) (width 0.09) (layer "In7.Cu") (net 348))
  (segment (start 178.214778 90.065) (end 178.845 89.434778) (width 0.09) (layer "In7.Cu") (net 348))
  (segment (start 185.577861 67.7) (end 185.57648 67.7) (width 0.166) (layer "In7.Cu") (net 348))
  (segment (start 178.205 81.860062) (end 178.205 78.580062) (width 0.09) (layer "In7.Cu") (net 348))
  (segment (start 182.779799 67.656279) (end 183.183718 68.060198) (width 0.166) (layer "In7.Cu") (net 348))
  (segment (start 178.645 75.5586) (end 178.7036 75.5) (width 0.09) (layer "In7.Cu") (net 348))
  (arc (start 187.222139 67.700001) (mid 187.059927 67.591614) (end 186.868585 67.553554) (width 0.166) (layer "In7.Cu") (net 348))
  (arc (start 181.840202 67.656278) (mid 182.002414 67.547892) (end 182.193755 67.509832) (width 0.166) (layer "In7.Cu") (net 348))
  (arc (start 182.779799 67.656279) (mid 182.617587 67.547892) (end 182.426245 67.509832) (width 0.166) (layer "In7.Cu") (net 348))
  (arc (start 187.583718 68.060198) (mid 187.818925 68.217358) (end 188.09637 68.272545) (width 0.166) (layer "In7.Cu") (net 348))
  (arc (start 185.931414 67.553554) (mid 185.740073 67.591614) (end 185.577861 67.7) (width 0.166) (layer "In7.Cu") (net 348))
  (arc (start 185.216283 68.060197) (mid 184.981076 68.217358) (end 184.70363 68.272545) (width 0.166) (layer "In7.Cu") (net 348))
  (arc (start 183.183718 68.060198) (mid 183.418925 68.217358) (end 183.69637 68.272545) (width 0.166) (layer "In7.Cu") (net 348))
  (segment (start 179.636328 89.060008) (end 180.136328 88.560008) (width 0.127) (layer "F.Cu") (net 349))
  (segment (start 203.286328 55.675008) (end 203.561328 55.950008) (width 0.1) (layer "F.Cu") (net 349))
  (segment (start 203.561327 56.460011) (end 203.386328 56.63501) (width 0.1) (layer "F.Cu") (net 349))
  (segment (start 203.286328 55.060008) (end 203.286328 55.675008) (width 0.1) (layer "F.Cu") (net 349))
  (segment (start 203.561328 55.950008) (end 203.561327 56.460011) (width 0.1) (layer "F.Cu") (net 349))
  (via (at 203.386328 56.63501) (size 0.5) (drill 0.2) (layers "F.Cu" "B.Cu") (net 349))
  (via (at 179.636328 89.060008) (size 0.5) (drill 0.2) (layers "F.Cu" "B.Cu") (net 349))
  (segment (start 179.92 89.06) (end 179.96 89.02) (width 0.09) (layer "In7.Cu") (net 349))
  (segment (start 179.72 88.32) (end 179.72 88.215062) (width 0.09) (layer "In7.Cu") (net 349))
  (segment (start 179.20581 75.49419) (end 179.20581 71.91771) (width 0.166) (layer "In7.Cu") (net 349))
  (segment (start 188.199243 69.705205) (end 188.659797 69.705205) (width 0.166) (layer "In7.Cu") (net 349))
  (segment (start 196.753901 69.648266) (end 196.981548 69.420619) (width 0.166) (layer "In7.Cu") (net 349))
  (segment (start 189.328566 69.29532) (end 190.090474 69.29532) (width 0.166) (layer "In7.Cu") (net 349))
  (segment (start 181.822719 69.704659) (end 183.613143 69.704659) (width 0.166) (layer "In7.Cu") (net 349))
  (segment (start 184.283006 69.29368) (end 185.006874 69.29368) (width 0.166) (layer "In7.Cu") (net 349))
  (segment (start 186.278439 69.645806) (end 186.505266 69.418979) (width 0.166) (layer "In7.Cu") (net 349))
  (segment (start 203.9645 59.84098) (end 203.515828 59.392308) (width 0.166) (layer "In7.Cu") (net 349))
  (segment (start 179.55 88.15) (end 179.44 88.04) (width 0.09) (layer "In7.Cu") (net 349))
  (segment (start 179.72 88.215062) (end 179.654938 88.15) (width 0.09) (layer "In7.Cu") (net 349))
  (segment (start 187.830175 69.41898) (end 188.057822 69.646627) (width 0.166) (layer "In7.Cu") (net 349))
  (segment (start 179.914938 88.41) (end 179.81 88.41) (width 0.09) (layer "In7.Cu") (net 349))
  (segment (start 179.81 88.41) (end 179.72 88.32) (width 0.09) (layer "In7.Cu") (net 349))
  (segment (start 179.255 75.585) (end 179.20581 75.53581) (width 0.09) (layer "In7.Cu") (net 349))
  (segment (start 183.613143 69.704659) (end 183.614237 69.703565) (width 0.166) (layer "In7.Cu") (net 349))
  (segment (start 194.613306 69.29614) (end 195.375214 69.29614) (width 0.166) (layer "In7.Cu") (net 349))
  (segment (start 192.913775 69.42062) (end 193.141422 69.648267) (width 0.166) (layer "In7.Cu") (net 349))
  (segment (start 179.375 82.019938) (end 179.375 79.995203) (width 0.09) (layer "In7.Cu") (net 349))
  (segment (start 179.654938 88.15) (end 179.55 88.15) (width 0.09) (layer "In7.Cu") (net 349))
  (segment (start 199.651701 69.501819) (end 203.9645 65.18902) (width 0.166) (layer "In7.Cu") (net 349))
  (segment (start 179.636328 89.060008) (end 179.636336 89.06) (width 0.09) (layer "In7.Cu") (net 349))
  (segment (start 197.282068 69.29614) (end 198.043976 69.29614) (width 0.166) (layer "In7.Cu") (net 349))
  (segment (start 190.390995 69.4198) (end 190.618642 69.647447) (width 0.166) (layer "In7.Cu") (net 349))
  (segment (start 194.085139 69.648266) (end 194.312786 69.420619) (width 0.166) (layer "In7.Cu") (net 349))
  (segment (start 179.011106 84.600832) (end 179.011106 82.383832) (width 0.09) (layer "In7.Cu") (net 349))
  (segment (start 179.96 89.02) (end 179.96 88.455062) (width 0.09) (layer "In7.Cu") (net 349))
  (segment (start 203.515828 59.392308) (end 203.515828 56.76451) (width 0.166) (layer "In7.Cu") (net 349))
  (segment (start 191.323999 69.647446) (end 191.550826 69.420619) (width 0.166) (layer "In7.Cu") (net 349))
  (segment (start 185.307395 69.41816) (end 185.535042 69.645807) (width 0.166) (layer "In7.Cu") (net 349))
  (segment (start 183.755659 69.644986) (end 183.982486 69.418159) (width 0.166) (layer "In7.Cu") (net 349))
  (segment (start 186.805786 69.2945) (end 187.529654 69.2945) (width 0.166) (layer "In7.Cu") (net 349))
  (segment (start 179.96 88.455062) (end 179.914938 88.41) (width 0.09) (layer "In7.Cu") (net 349))
  (segment (start 179.011106 82.383832) (end 179.375 82.019938) (width 0.09) (layer "In7.Cu") (net 349))
  (segment (start 178.929 84.682938) (end 179.011106 84.600832) (width 0.09) (layer "In7.Cu") (net 349))
  (segment (start 188.801219 69.646626) (end 189.028046 69.419799) (width 0.166) (layer "In7.Cu") (net 349))
  (segment (start 179.636336 89.06) (end 179.92 89.06) (width 0.09) (layer "In7.Cu") (net 349))
  (segment (start 178.867556 79.487759) (end 178.867556 78.727382) (width 0.09) (layer "In7.Cu") (net 349))
  (segment (start 179.20581 71.91771) (end 181.13329 69.99023) (width 0.166) (layer "In7.Cu") (net 349))
  (segment (start 190.760063 69.706025) (end 191.182577 69.706025) (width 0.166) (layer "In7.Cu") (net 349))
  (segment (start 179.255 78.339938) (end 179.255 75.585) (width 0.09) (layer "In7.Cu") (net 349))
  (segment (start 193.282843 69.706845) (end 193.943717 69.706845) (width 0.166) (layer "In7.Cu") (net 349))
  (segment (start 179.44 87.935062) (end 178.929 87.424062) (width 0.09) (layer "In7.Cu") (net 349))
  (segment (start 178.867556 78.727382) (end 179.255 78.339938) (width 0.09) (layer "In7.Cu") (net 349))
  (segment (start 198.713565 69.706845) (end 199.156726 69.706845) (width 0.166) (layer "In7.Cu") (net 349))
  (segment (start 178.929 87.424062) (end 178.929 84.682938) (width 0.09) (layer "In7.Cu") (net 349))
  (segment (start 196.044803 69.706845) (end 196.612479 69.706845) (width 0.166) (layer "In7.Cu") (net 349))
  (segment (start 179.20581 75.53581) (end 179.20581 75.49419) (width 0.09) (layer "In7.Cu") (net 349))
  (segment (start 185.676463 69.704385) (end 186.137017 69.704385) (width 0.166) (layer "In7.Cu") (net 349))
  (segment (start 179.375 79.995203) (end 178.867556 79.487759) (width 0.09) (layer "In7.Cu") (net 349))
  (segment (start 203.515828 56.76451) (end 203.386328 56.63501) (width 0.166) (layer "In7.Cu") (net 349))
  (segment (start 195.675735 69.42062) (end 195.903382 69.648267) (width 0.166) (layer "In7.Cu") (net 349))
  (segment (start 191.851346 69.29614) (end 192.613254 69.29614) (width 0.166) (layer "In7.Cu") (net 349))
  (segment (start 179.44 88.04) (end 179.44 87.935062) (width 0.09) (layer "In7.Cu") (net 349))
  (segment (start 203.9645 65.18902) (end 203.9645 59.84098) (width 0.166) (layer "In7.Cu") (net 349))
  (segment (start 198.344497 69.42062) (end 198.572144 69.648267) (width 0.166) (layer "In7.Cu") (net 349))
  (arc (start 198.043976 69.29614) (mid 198.206617 69.328491) (end 198.344497 69.42062) (width 0.166) (layer "In7.Cu") (net 349))
  (arc (start 196.981548 69.420619) (mid 197.119428 69.328491) (end 197.282068 69.29614) (width 0.166) (layer "In7.Cu") (net 349))
  (arc (start 185.006874 69.29368) (mid 185.169515 69.326031) (end 185.307395 69.41816) (width 0.166) (layer "In7.Cu") (net 349))
  (arc (start 186.137017 69.704385) (mid 186.213554 69.689161) (end 186.278439 69.645806) (width 0.166) (layer "In7.Cu") (net 349))
  (arc (start 196.612479 69.706845) (mid 196.689016 69.691621) (end 196.753901 69.648266) (width 0.166) (layer "In7.Cu") (net 349))
  (arc (start 190.618642 69.647447) (mid 190.683527 69.690801) (end 190.760063 69.706025) (width 0.166) (layer "In7.Cu") (net 349))
  (arc (start 199.651701 69.501819) (mid 199.424605 69.65356) (end 199.156726 69.706845) (width 0.166) (layer "In7.Cu") (net 349))
  (arc (start 198.572144 69.648267) (mid 198.637029 69.691621) (end 198.713565 69.706845) (width 0.166) (layer "In7.Cu") (net 349))
  (arc (start 188.057822 69.646627) (mid 188.122707 69.689981) (end 188.199243 69.705205) (width 0.166) (layer "In7.Cu") (net 349))
  (arc (start 193.141422 69.648267) (mid 193.206307 69.691621) (end 193.282843 69.706845) (width 0.166) (layer "In7.Cu") (net 349))
  (arc (start 183.614237 69.703565) (mid 183.690774 69.688341) (end 183.755659 69.644986) (width 0.166) (layer "In7.Cu") (net 349))
  (arc (start 185.535042 69.645807) (mid 185.599927 69.689161) (end 185.676463 69.704385) (width 0.166) (layer "In7.Cu") (net 349))
  (arc (start 191.550826 69.420619) (mid 191.688706 69.328491) (end 191.851346 69.29614) (width 0.166) (layer "In7.Cu") (net 349))
  (arc (start 192.613254 69.29614) (mid 192.775895 69.328491) (end 192.913775 69.42062) (width 0.166) (layer "In7.Cu") (net 349))
  (arc (start 194.312786 69.420619) (mid 194.450666 69.328491) (end 194.613306 69.29614) (width 0.166) (layer "In7.Cu") (net 349))
  (arc (start 193.943717 69.706845) (mid 194.020254 69.691621) (end 194.085139 69.648266) (width 0.166) (layer "In7.Cu") (net 349))
  (arc (start 191.182577 69.706025) (mid 191.259114 69.690801) (end 191.323999 69.647446) (width 0.166) (layer "In7.Cu") (net 349))
  (arc (start 188.659797 69.705205) (mid 188.736334 69.689981) (end 188.801219 69.646626) (width 0.166) (layer "In7.Cu") (net 349))
  (arc (start 183.982486 69.418159) (mid 184.120366 69.326031) (end 184.283006 69.29368) (width 0.166) (layer "In7.Cu") (net 349))
  (arc (start 186.505266 69.418979) (mid 186.643146 69.326851) (end 186.805786 69.2945) (width 0.166) (layer "In7.Cu") (net 349))
  (arc (start 195.903382 69.648267) (mid 195.968267 69.691621) (end 196.044803 69.706845) (width 0.166) (layer "In7.Cu") (net 349))
  (arc (start 189.028046 69.419799) (mid 189.165926 69.327671) (end 189.328566 69.29532) (width 0.166) (layer "In7.Cu") (net 349))
  (arc (start 190.090474 69.29532) (mid 190.253115 69.327671) (end 190.390995 69.4198) (width 0.166) (layer "In7.Cu") (net 349))
  (arc (start 195.375214 69.29614) (mid 195.537855 69.328491) (end 195.675735 69.42062) (width 0.166) (layer "In7.Cu") (net 349))
  (arc (start 187.529654 69.2945) (mid 187.692295 69.326851) (end 187.830175 69.41898) (width 0.166) (layer "In7.Cu") (net 349))
  (arc (start 181.13329 69.99023) (mid 181.449603 69.778877) (end 181.822719 69.704659) (width 0.166) (layer "In7.Cu") (net 349))
  (segment (start 122.536328 63.710008) (end 122.536328 59.660008) (width 0.15) (layer "F.Cu") (net 350))
  (segment (start 121.205128 67.740008) (end 121.205128 66.343808) (width 0.15) (layer "F.Cu") (net 350))
  (segment (start 121.071328 66.210008) (end 121.071328 65.175008) (width 0.15) (layer "F.Cu") (net 350))
  (segment (start 121.071328 65.175008) (end 122.536328 63.710008) (width 0.15) (layer "F.Cu") (net 350))
  (segment (start 121.855128 67.740008) (end 121.855128 66.356208) (width 0.15) (layer "F.Cu") (net 351))
  (segment (start 122.001328 66.210008) (end 122.001328 65.160008) (width 0.15) (layer "F.Cu") (net 351))
  (segment (start 122.536328 55.060008) (end 122.536328 56.460008) (width 0.15) (layer "F.Cu") (net 351))
  (via (at 122.001328 65.160008) (size 0.5) (drill 0.2) (layers "F.Cu" "B.Cu") (net 351))
  (via (at 122.536328 56.460008) (size 0.5) (drill 0.2) (layers "F.Cu" "B.Cu") (net 351))
  (segment (start 122.536328 64.625008) (end 122.001328 65.160008) (width 0.15) (layer "B.Cu") (net 351))
  (segment (start 122.536328 56.460008) (end 122.536328 64.625008) (width 0.15) (layer "B.Cu") (net 351))
  (segment (start 184.311328 60.550008) (end 184.311329 60.685009) (width 0.1) (layer "F.Cu") (net 353))
  (segment (start 184.311329 60.685009) (end 184.586328 60.960008) (width 0.1) (layer "F.Cu") (net 353))
  (segment (start 184.586328 59.660008) (end 184.586328 60.275008) (width 0.1) (layer "F.Cu") (net 353))
  (segment (start 185.56807 80.975944) (end 185.56807 81.05193) (width 0.127) (layer "F.Cu") (net 353))
  (segment (start 185.56807 81.05193) (end 185.136328 81.483672) (width 0.127) (layer "F.Cu") (net 353))
  (segment (start 185.136328 81.483672) (end 185.136328 81.560008) (width 0.127) (layer "F.Cu") (net 353))
  (segment (start 184.586328 60.275008) (end 184.311328 60.550008) (width 0.1) (layer "F.Cu") (net 353))
  (via blind (at 184.586328 60.960008) (size 0.5) (drill 0.2) (layers "F.Cu" "In2.Cu") (net 353))
  (via blind (at 185.56807 80.975944) (size 0.5) (drill 0.2) (layers "F.Cu" "In2.Cu") (net 353))
  (segment (start 188.362913 64.526) (end 191.837087 64.526) (width 0.143) (layer "In2.Cu") (net 353))
  (segment (start 184.311829 61.498989) (end 184.311829 61.188171) (width 0.143) (layer "In2.Cu") (net 353))
  (segment (start 187.337731 75.5) (end 187.337731 70.775109) (width 0.143) (layer "In2.Cu") (net 353))
  (segment (start 184.311829 61.188171) (end 184.539992 60.960008) (width 0.143) (layer "In2.Cu") (net 353))
  (segment (start 184.56234 61.7495) (end 188.0005 61.7495) (width 0.143) (layer "In2.Cu") (net 353))
  (segment (start 186.945734 80.656044) (end 187.335 80.266778) (width 0.1) (layer "In2.Cu") (net 353))
  (segment (start 185.8 80.656044) (end 186.945734 80.656044) (width 0.1) (layer "In2.Cu") (net 353))
  (segment (start 185.56807 80.975944) (end 185.56807 80.887974) (width 0.1) (layer "In2.Cu") (net 353))
  (segment (start 190.575 65.075) (end 188.362913 65.075) (width 0.143) (layer "In2.Cu") (net 353))
  (segment (start 187.335 80.266778) (end 187.335 77.65592) (width 0.1) (layer "In2.Cu") (net 353))
  (segment (start 187.335 77.65592) (end 187.635 77.35592) (width 0.1) (layer "In2.Cu") (net 353))
  (segment (start 188.551 62.626296) (end 188.551 62.3) (width 0.143) (layer "In2.Cu") (net 353))
  (segment (start 191.1505 62.849561) (end 190.050439 61.7495) (width 0.143) (layer "In2.Cu") (net 353))
  (segment (start 187.335 75.94408) (end 187.335 75.502731) (width 0.1) (layer "In2.Cu") (net 353))
  (segment (start 187.337731 70.775109) (end 191.1505 66.96234) (width 0.143) (layer "In2.Cu") (net 353))
  (segment (start 185.56807 80.887974) (end 185.8 80.656044) (width 0.1) (layer "In2.Cu") (net 353))
  (segment (start 187.635 77.35592) (end 187.635 76.24408) (width 0.1) (layer "In2.Cu") (net 353))
  (segment (start 184.539992 60.960008) (end 184.586328 60.960008) (width 0.143) (layer "In2.Cu") (net 353))
  (segment (start 187.335 75.502731) (end 187.337731 75.5) (width 0.1) (layer "In2.Cu") (net 353))
  (segment (start 191.1505 63.1005) (end 191.1505 62.849561) (width 0.143) (layer "In2.Cu") (net 353))
  (segment (start 190.050439 61.7495) (end 189.6005 61.7495) (width 0.143) (layer "In2.Cu") (net 353))
  (segment (start 191.1505 66.96234) (end 191.1505 65.6505) (width 0.143) (layer "In2.Cu") (net 353))
  (segment (start 184.56234 61.7495) (end 184.311829 61.498989) (width 0.143) (layer "In2.Cu") (net 353))
  (segment (start 191.837087 63.375) (end 191.425 63.375) (width 0.143) (layer "In2.Cu") (net 353))
  (segment (start 187.635 76.24408) (end 187.335 75.94408) (width 0.1) (layer "In2.Cu") (net 353))
  (segment (start 189.05 62.3) (end 189.05 62.626296) (width 0.143) (layer "In2.Cu") (net 353))
  (arc (start 188.362913 65.075) (mid 188.168812 64.994601) (end 188.088413 64.8005) (width 0.143) (layer "In2.Cu") (net 353))
  (arc (start 188.551 62.3) (mid 188.389762 61.910738) (end 188.0005 61.7495) (width 0.143) (layer "In2.Cu") (net 353))
  (arc (start 191.837087 64.526) (mid 192.244027 64.35744) (end 192.412587 63.9505) (width 0.143) (layer "In2.Cu") (net 353))
  (arc (start 189.6005 61.7495) (mid 189.211238 61.910738) (end 189.05 62.3) (width 0.143) (layer "In2.Cu") (net 353))
  (arc (start 188.088413 64.8005) (mid 188.168812 64.606399) (end 188.362913 64.526) (width 0.143) (layer "In2.Cu") (net 353))
  (arc (start 192.412587 63.9505) (mid 192.244027 63.54356) (end 191.837087 63.375) (width 0.143) (layer "In2.Cu") (net 353))
  (arc (start 189.05 62.626296) (mid 188.976923 62.802719) (end 188.8005 62.875796) (width 0.143) (layer "In2.Cu") (net 353))
  (arc (start 191.1505 65.6505) (mid 190.98194 65.24356) (end 190.575 65.075) (width 0.143) (layer "In2.Cu") (net 353))
  (arc (start 188.8005 62.875796) (mid 188.624077 62.802719) (end 188.551 62.626296) (width 0.143) (layer "In2.Cu") (net 353))
  (arc (start 191.425 63.375) (mid 191.230899 63.294601) (end 191.1505 63.1005) (width 0.143) (layer "In2.Cu") (net 353))
  (segment (start 185.136328 80.463672) (end 185.136328 80.560008) (width 0.127) (layer "F.Cu") (net 354))
  (segment (start 184.011328 60.550008) (end 184.011327 60.685009) (width 0.1) (layer "F.Cu") (net 354))
  (segment (start 185.4955 80.1045) (end 185.136328 80.463672) (width 0.127) (layer "F.Cu") (net 354))
  (segment (start 183.736328 60.275008) (end 184.011328 60.550008) (width 0.1) (layer "F.Cu") (net 354))
  (segment (start 184.011327 60.685009) (end 183.736328 60.960008) (width 0.1) (layer "F.Cu") (net 354))
  (segment (start 183.736328 59.660008) (end 183.736328 60.275008) (width 0.1) (layer "F.Cu") (net 354))
  (segment (start 185.4955 80.088545) (end 185.4955 80.1045) (width 0.127) (layer "F.Cu") (net 354))
  (via blind (at 185.4955 80.088545) (size 0.5) (drill 0.2) (layers "F.Cu" "In2.Cu") (net 354))
  (via blind (at 183.736328 60.960008) (size 0.5) (drill 0.2) (layers "F.Cu" "In2.Cu") (net 354))
  (segment (start 186.861731 74.111731) (end 186.856749 74.111731) (width 0.143) (layer "In2.Cu") (net 354))
  (segment (start 186.856749 75.161731) (end 186.861731 75.161731) (width 0.143) (layer "In2.Cu") (net 354))
  (segment (start 184.010827 61.623667) (end 184.43766 62.0505) (width 0.143) (layer "In2.Cu") (net 354))
  (segment (start 185.4955 80.088545) (end 185.4955 80.0955) (width 0.1) (layer "In2.Cu") (net 354))
  (segment (start 186.856749 74.461731) (end 186.861731 74.461731) (width 0.143) (layer "In2.Cu") (net 354))
  (segment (start 183.736328 60.960008) (end 183.780008 60.960008) (width 0.143) (layer "In2.Cu") (net 354))
  (segment (start 189.925759 62.0505) (end 190.8495 62.974241) (width 0.143) (layer "In2.Cu") (net 354))
  (segment (start 189.351 62.626296) (end 189.351 62.3) (width 0.143) (layer "In2.Cu") (net 354))
  (segment (start 185.786044 80.386044) (end 186.862178 80.386044) (width 0.1) (layer "In2.Cu") (net 354))
  (segment (start 187.065 80.183222) (end 187.065 77.54408) (width 0.1) (layer "In2.Cu") (net 354))
  (segment (start 187.036731 70.650429) (end 187.036731 73.936731) (width 0.143) (layer "In2.Cu") (net 354))
  (segment (start 187.036731 76.027651) (end 187.036731 75.5) (width 0.1) (layer "In2.Cu") (net 354))
  (segment (start 186.862178 80.386044) (end 187.065 80.183222) (width 0.1) (layer "In2.Cu") (net 354))
  (segment (start 187.365 76.35592) (end 187.036731 76.027651) (width 0.1) (layer "In2.Cu") (net 354))
  (segment (start 189.6005 62.0505) (end 189.925759 62.0505) (width 0.143) (layer "In2.Cu") (net 354))
  (segment (start 186.861731 74.811731) (end 186.856749 74.811731) (width 0.143) (layer "In2.Cu") (net 354))
  (segment (start 190.8495 62.974241) (end 190.8495 63.1005) (width 0.143) (layer "In2.Cu") (net 354))
  (segment (start 184.010827 61.190827) (end 184.010827 61.623667) (width 0.143) (layer "In2.Cu") (net 354))
  (segment (start 185.4955 80.0955) (end 185.786044 80.386044) (width 0.1) (layer "In2.Cu") (net 354))
  (segment (start 187.036731 75.336731) (end 187.036731 75.5) (width 0.143) (layer "In2.Cu") (net 354))
  (segment (start 188.25 62.3) (end 188.25 62.626296) (width 0.143) (layer "In2.Cu") (net 354))
  (segment (start 187.065 77.54408) (end 187.365 77.24408) (width 0.1) (layer "In2.Cu") (net 354))
  (segment (start 190.8495 66.83766) (end 187.036731 70.650429) (width 0.143) (layer "In2.Cu") (net 354))
  (segment (start 188.362913 65.376) (end 190.575 65.376) (width 0.143) (layer "In2.Cu") (net 354))
  (segment (start 190.8495 65.6505) (end 190.8495 66.83766) (width 0.143) (layer "In2.Cu") (net 354))
  (segment (start 191.837087 64.225) (end 188.362913 64.225) (width 0.143) (layer "In2.Cu") (net 354))
  (segment (start 191.425 63.676) (end 191.837087 63.676) (width 0.143) (layer "In2.Cu") (net 354))
  (segment (start 187.365 77.24408) (end 187.365 76.35592) (width 0.1) (layer "In2.Cu") (net 354))
  (segment (start 184.43766 62.0505) (end 188.0005 62.0505) (width 0.143) (layer "In2.Cu") (net 354))
  (segment (start 183.780008 60.960008) (end 184.010827 61.190827) (width 0.143) (layer "In2.Cu") (net 354))
  (arc (start 187.787413 64.8005) (mid 187.955973 65.20744) (end 188.362913 65.376) (width 0.143) (layer "In2.Cu") (net 354))
  (arc (start 188.25 62.626296) (mid 188.411238 63.015558) (end 188.8005 63.176796) (width 0.143) (layer "In2.Cu") (net 354))
  (arc (start 186.681749 74.986731) (mid 186.733005 75.110475) (end 186.856749 75.161731) (width 0.143) (layer "In2.Cu") (net 354))
  (arc (start 188.0005 62.0505) (mid 188.176923 62.123577) (end 188.25 62.3) (width 0.143) (layer "In2.Cu") (net 354))
  (arc (start 186.861731 75.161731) (mid 186.985475 75.212987) (end 187.036731 75.336731) (width 0.143) (layer "In2.Cu") (net 354))
  (arc (start 192.111587 63.9505) (mid 192.031188 64.144601) (end 191.837087 64.225) (width 0.143) (layer "In2.Cu") (net 354))
  (arc (start 186.856749 74.811731) (mid 186.733005 74.862987) (end 186.681749 74.986731) (width 0.143) (layer "In2.Cu") (net 354))
  (arc (start 186.856749 74.111731) (mid 186.733005 74.162987) (end 186.681749 74.286731) (width 0.143) (layer "In2.Cu") (net 354))
  (arc (start 190.575 65.376) (mid 190.769101 65.456399) (end 190.8495 65.6505) (width 0.143) (layer "In2.Cu") (net 354))
  (arc (start 187.036731 73.936731) (mid 186.985475 74.060475) (end 186.861731 74.111731) (width 0.143) (layer "In2.Cu") (net 354))
  (arc (start 188.362913 64.225) (mid 187.955973 64.39356) (end 187.787413 64.8005) (width 0.143) (layer "In2.Cu") (net 354))
  (arc (start 188.8005 63.176796) (mid 189.189762 63.015558) (end 189.351 62.626296) (width 0.143) (layer "In2.Cu") (net 354))
  (arc (start 191.837087 63.676) (mid 192.031188 63.756399) (end 192.111587 63.9505) (width 0.143) (layer "In2.Cu") (net 354))
  (arc (start 187.036731 74.636731) (mid 186.985475 74.760475) (end 186.861731 74.811731) (width 0.143) (layer "In2.Cu") (net 354))
  (arc (start 186.681749 74.286731) (mid 186.733005 74.410475) (end 186.856749 74.461731) (width 0.143) (layer "In2.Cu") (net 354))
  (arc (start 186.861731 74.461731) (mid 186.985475 74.512987) (end 187.036731 74.636731) (width 0.143) (layer "In2.Cu") (net 354))
  (arc (start 189.351 62.3) (mid 189.424077 62.123577) (end 189.6005 62.0505) (width 0.143) (layer "In2.Cu") (net 354))
  (arc (start 190.8495 63.1005) (mid 191.01806 63.50744) (end 191.425 63.676) (width 0.143) (layer "In2.Cu") (net 354))
  (segment (start 185.6 78.096336) (end 185.6 78.060008) (width 0.127) (layer "F.Cu") (net 355))
  (segment (start 185.136328 78.560008) (end 185.6 78.096336) (width 0.127) (layer "F.Cu") (net 355))
  (segment (start 184.586328 56.360008) (end 184.311329 56.085009) (width 0.1) (layer "F.Cu") (net 355))
  (segment (start 184.311329 56.085009) (end 184.311328 55.950008) (width 0.1) (layer "F.Cu") (net 355))
  (segment (start 184.586328 55.675008) (end 184.586328 55.060008) (width 0.1) (layer "F.Cu") (net 355))
  (segment (start 184.311328 55.950008) (end 184.586328 55.675008) (width 0.1) (layer "F.Cu") (net 355))
  (via blind (at 184.586328 56.360008) (size 0.5) (drill 0.2) (layers "F.Cu" "In2.Cu") (net 355))
  (via blind (at 185.6 78.060008) (size 0.5) (drill 0.2) (layers "F.Cu" "In2.Cu") (net 355))
  (segment (start 184.839 65.948) (end 189.476428 65.948) (width 0.143) (layer "In2.Cu") (net 355))
  (segment (start 185.6 78.060008) (end 185.6 77.9) (width 0.1) (layer "In2.Cu") (net 355))
  (segment (start 186.55 67.749) (end 186.122572 67.749) (width 0.143) (layer "In2.Cu") (net 355))
  (segment (start 183.96234 63.1495) (end 182.8505 62.03766) (width 0.143) (layer "In2.Cu") (net 355))
  (segment (start 186.16234 63.1495) (end 183.96234 63.1495) (width 0.143) (layer "In2.Cu") (net 355))
  (segment (start 187.1505 64.13766) (end 186.16234 63.1495) (width 0.143) (layer "In2.Cu") (net 355))
  (segment (start 182.8505 60.46234) (end 184.311829 59.001011) (width 0.143) (layer "In2.Cu") (net 355))
  (segment (start 186.25756 69.45528) (end 187.1505 68.56234) (width 0.143) (layer "In2.Cu") (net 355))
  (segment (start 187.1505 68.56234) (end 187.1505 68.3495) (width 0.143) (layer "In2.Cu") (net 355))
  (segment (start 186.035809 77.765004) (end 186.459764 77.341049) (width 0.1) (layer "In2.Cu") (net 355))
  (segment (start 186.459764 77.341049) (end 186.459764 76.088844) (width 0.1) (layer "In2.Cu") (net 355))
  (segment (start 189.476428 65.948) (end 189.477428 65.949) (width 0.143) (layer "In2.Cu") (net 355))
  (segment (start 182.8505 62.03766) (end 182.8505 60.46234) (width 0.143) (layer "In2.Cu") (net 355))
  (segment (start 186.122572 67.15) (end 189.477428 67.15) (width 0.143) (layer "In2.Cu") (net 355))
  (segment (start 186.25756 75.88664) (end 186.25756 75.525) (width 0.1) (layer "In2.Cu") (net 355))
  (segment (start 184.311829 59.001011) (end 184.311829 56.634507) (width 0.143) (layer "In2.Cu") (net 355))
  (segment (start 186.459764 76.088844) (end 186.25756 75.88664) (width 0.1) (layer "In2.Cu") (net 355))
  (segment (start 187.1505 64.7495) (end 187.1505 64.13766) (width 0.143) (layer "In2.Cu") (net 355))
  (segment (start 186.549 65.349) (end 184.839 65.349) (width 0.143) (layer "In2.Cu") (net 355))
  (segment (start 185.734996 77.765004) (end 186.035809 77.765004) (width 0.1) (layer "In2.Cu") (net 355))
  (segment (start 186.549 65.349) (end 186.55 65.35) (width 0.143) (layer "In2.Cu") (net 355))
  (segment (start 185.6 77.9) (end 185.734996 77.765004) (width 0.1) (layer "In2.Cu") (net 355))
  (segment (start 186.25756 75.525) (end 186.25756 69.45528) (width 0.143) (layer "In2.Cu") (net 355))
  (segment (start 184.311829 56.634507) (end 184.586328 56.360008) (width 0.143) (layer "In2.Cu") (net 355))
  (arc (start 190.077928 66.5495) (mid 189.902046 66.124882) (end 189.477428 65.949) (width 0.143) (layer "In2.Cu") (net 355))
  (arc (start 186.122572 67.749) (mid 185.910794 67.661278) (end 185.823072 67.4495) (width 0.143) (layer "In2.Cu") (net 355))
  (arc (start 189.477428 67.15) (mid 189.902046 66.974118) (end 190.077928 66.5495) (width 0.143) (layer "In2.Cu") (net 355))
  (arc (start 185.823072 67.4495) (mid 185.910794 67.237722) (end 186.122572 67.15) (width 0.143) (layer "In2.Cu") (net 355))
  (arc (start 186.55 65.35) (mid 186.974618 65.174118) (end 187.1505 64.7495) (width 0.143) (layer "In2.Cu") (net 355))
  (arc (start 184.5395 65.6485) (mid 184.627222 65.436722) (end 184.839 65.349) (width 0.143) (layer "In2.Cu") (net 355))
  (arc (start 187.1505 68.3495) (mid 186.974618 67.924882) (end 186.55 67.749) (width 0.143) (layer "In2.Cu") (net 355))
  (arc (start 184.839 65.948) (mid 184.627222 65.860278) (end 184.5395 65.6485) (width 0.143) (layer "In2.Cu") (net 355))
  (segment (start 184.011327 56.085009) (end 184.011328 55.950008) (width 0.1) (layer "F.Cu") (net 356))
  (segment (start 183.736328 55.675008) (end 183.736328 55.060008) (width 0.1) (layer "F.Cu") (net 356))
  (segment (start 185.239992 77.560008) (end 185.6 77.2) (width 0.127) (layer "F.Cu") (net 356))
  (segment (start 183.736328 56.360008) (end 184.011327 56.085009) (width 0.1) (layer "F.Cu") (net 356))
  (segment (start 185.136328 77.560008) (end 185.239992 77.560008) (width 0.127) (layer "F.Cu") (net 356))
  (segment (start 184.011328 55.950008) (end 183.736328 55.675008) (width 0.1) (layer "F.Cu") (net 356))
  (via blind (at 183.736328 56.360008) (size 0.5) (drill 0.2) (layers "F.Cu" "In2.Cu") (net 356))
  (via blind (at 185.6 77.2) (size 0.5) (drill 0.2) (layers "F.Cu" "In2.Cu") (net 356))
  (segment (start 185.745004 77.495004) (end 185.6 77.35) (width 0.1) (layer "In2.Cu") (net 356))
  (segment (start 186.03766 63.4505) (end 183.83766 63.4505) (width 0.143) (layer "In2.Cu") (net 356))
  (segment (start 186.189764 76.200684) (end 185.95656 75.96748) (width 0.1) (layer "In2.Cu") (net 356))
  (segment (start 185.923969 77.495004) (end 185.745004 77.495004) (width 0.1) (layer "In2.Cu") (net 356))
  (segment (start 186.8495 68.43766) (end 186.8495 68.3495) (width 0.143) (layer "In2.Cu") (net 356))
  (segment (start 184.839 65.048) (end 184.84 65.049) (width 0.143) (layer "In2.Cu") (net 356))
  (segment (start 185.78156 74.47844) (end 185.75924 74.47844) (width 0.143) (layer "In2.Cu") (net 356))
  (segment (start 185.95656 69.3306) (end 186.8495 68.43766) (width 0.143) (layer "In2.Cu") (net 356))
  (segment (start 185.95656 73.95344) (end 185.95656 69.3306) (width 0.143) (layer "In2.Cu") (net 356))
  (segment (start 184.84 66.25) (end 184.839 66.249) (width 0.143) (layer "In2.Cu") (net 356))
  (segment (start 184.010827 56.634507) (end 183.736328 56.360008) (width 0.143) (layer "In2.Cu") (net 356))
  (segment (start 186.8495 64.26234) (end 186.03766 63.4505) (width 0.143) (layer "In2.Cu") (net 356))
  (segment (start 185.95656 75.96748) (end 185.95656 75.525) (width 0.1) (layer "In2.Cu") (net 356))
  (segment (start 185.75924 74.82844) (end 185.78156 74.82844) (width 0.143) (layer "In2.Cu") (net 356))
  (segment (start 182.5495 62.16234) (end 182.5495 60.33766) (width 0.143) (layer "In2.Cu") (net 356))
  (segment (start 184.84 65.049) (end 186.548 65.049) (width 0.143) (layer "In2.Cu") (net 356))
  (segment (start 185.6 77.35) (end 185.6 77.2) (width 0.1) (layer "In2.Cu") (net 356))
  (segment (start 185.78156 75.17844) (end 185.75924 75.17844) (width 0.143) (layer "In2.Cu") (net 356))
  (segment (start 185.923969 77.495004) (end 186.189764 77.229209) (width 0.1) (layer "In2.Cu") (net 356))
  (segment (start 189.477428 66.25) (end 184.84 66.25) (width 0.143) (layer "In2.Cu") (net 356))
  (segment (start 185.75924 74.12844) (end 185.78156 74.12844) (width 0.143) (layer "In2.Cu") (net 356))
  (segment (start 186.189764 77.229209) (end 186.189764 76.200684) (width 0.1) (layer "In2.Cu") (net 356))
  (segment (start 186.549 65.048) (end 186.55 65.049) (width 0.143) (layer "In2.Cu") (net 356))
  (segment (start 182.5495 60.33766) (end 184.010827 58.876333) (width 0.143) (layer "In2.Cu") (net 356))
  (segment (start 183.83766 63.4505) (end 182.5495 62.16234) (width 0.143) (layer "In2.Cu") (net 356))
  (segment (start 185.95656 75.525) (end 185.95656 75.35344) (width 0.143) (layer "In2.Cu") (net 356))
  (segment (start 186.8495 64.7495) (end 186.8495 64.26234) (width 0.143) (layer "In2.Cu") (net 356))
  (segment (start 186.548 65.049) (end 186.549 65.048) (width 0.143) (layer "In2.Cu") (net 356))
  (segment (start 186.55 68.05) (end 186.122572 68.05) (width 0.143) (layer "In2.Cu") (net 356))
  (segment (start 184.010827 58.876333) (end 184.010827 56.634507) (width 0.143) (layer "In2.Cu") (net 356))
  (segment (start 186.122572 66.849) (end 189.477428 66.849) (width 0.143) (layer "In2.Cu") (net 356))
  (arc (start 186.55 65.049) (mid 186.761778 64.961278) (end 186.8495 64.7495) (width 0.143) (layer "In2.Cu") (net 356))
  (arc (start 185.95656 75.35344) (mid 185.905304 75.229696) (end 185.78156 75.17844) (width 0.143) (layer "In2.Cu") (net 356))
  (arc (start 184.2385 65.6485) (mid 184.414382 65.223882) (end 184.839 65.048) (width 0.143) (layer "In2.Cu") (net 356))
  (arc (start 185.78156 74.82844) (mid 185.905304 74.777184) (end 185.95656 74.65344) (width 0.143) (layer "In2.Cu") (net 356))
  (arc (start 189.776928 66.5495) (mid 189.689206 66.337722) (end 189.477428 66.25) (width 0.143) (layer "In2.Cu") (net 356))
  (arc (start 186.122572 68.05) (mid 185.697954 67.874118) (end 185.522072 67.4495) (width 0.143) (layer "In2.Cu") (net 356))
  (arc (start 185.75924 75.17844) (mid 185.635496 75.127184) (end 185.58424 75.00344) (width 0.143) (layer "In2.Cu") (net 356))
  (arc (start 185.522072 67.4495) (mid 185.697954 67.024882) (end 186.122572 66.849) (width 0.143) (layer "In2.Cu") (net 356))
  (arc (start 185.75924 74.47844) (mid 185.635496 74.427184) (end 185.58424 74.30344) (width 0.143) (layer "In2.Cu") (net 356))
  (arc (start 185.95656 74.65344) (mid 185.905304 74.529696) (end 185.78156 74.47844) (width 0.143) (layer "In2.Cu") (net 356))
  (arc (start 185.78156 74.12844) (mid 185.905304 74.077184) (end 185.95656 73.95344) (width 0.143) (layer "In2.Cu") (net 356))
  (arc (start 186.8495 68.3495) (mid 186.761778 68.137722) (end 186.55 68.05) (width 0.143) (layer "In2.Cu") (net 356))
  (arc (start 184.839 66.249) (mid 184.414382 66.073118) (end 184.2385 65.6485) (width 0.143) (layer "In2.Cu") (net 356))
  (arc (start 185.58424 75.00344) (mid 185.635496 74.879696) (end 185.75924 74.82844) (width 0.143) (layer "In2.Cu") (net 356))
  (arc (start 185.58424 74.30344) (mid 185.635496 74.179696) (end 185.75924 74.12844) (width 0.143) (layer "In2.Cu") (net 356))
  (arc (start 189.477428 66.849) (mid 189.689206 66.761278) (end 189.776928 66.5495) (width 0.143) (layer "In2.Cu") (net 356))
  (segment (start 121.072128 74.994608) (end 121.072128 74.106008) (width 0.15) (layer "F.Cu") (net 357))
  (segment (start 171.136328 99.560008) (end 170.636328 100.060008) (width 0.1) (layer "F.Cu") (net 357))
  (segment (start 121.205128 72.140008) (end 121.205128 73.973008) (width 0.15) (layer "F.Cu") (net 357))
  (via (at 121.072128 74.994608) (size 0.5) (drill 0.2) (layers "F.Cu" "B.Cu") (net 357))
  (via (at 170.636328 100.060008) (size 0.5) (drill 0.2) (layers "F.Cu" "B.Cu") (net 357))
  (via (at 122 92.4) (size 0.5) (drill 0.2) (layers "F.Cu" "B.Cu") (net 357))
  (via (at 129.1 88.1) (size 0.5) (drill 0.2) (layers "F.Cu" "B.Cu") (net 357))
  (segment (start 164.80603 104.9) (end 165.22603 105.32) (width 0.1) (layer "In2.Cu") (net 357))
  (segment (start 130.05 89.55) (end 133.066362 89.55) (width 0.1) (layer "In2.Cu") (net 357))
  (segment (start 165.22603 105.32) (end 169.442656 105.32) (width 0.1) (layer "In2.Cu") (net 357))
  (segment (start 145.1625 103.1) (end 145.9925 103.93) (width 0.1) (layer "In2.Cu") (net 357))
  (segment (start 123.794171 74.994608) (end 121.072128 74.994608) (width 0.1) (layer "In2.Cu") (net 357))
  (segment (start 129.1 88.1) (end 129.1 87.475) (width 0.1) (layer "In2.Cu") (net 357))
  (segment (start 152.93 103.93) (end 153.9 104.9) (width 0.1) (layer "In2.Cu") (net 357))
  (segment (start 169.442656 105.32) (end 171.056328 103.706328) (width 0.1) (layer "In2.Cu") (net 357))
  (segment (start 129.85 86.725) (end 129.85 81.050437) (width 0.1) (layer "In2.Cu") (net 357))
  (segment (start 141.125 103.1) (end 145.1625 103.1) (width 0.1) (layer "In2.Cu") (net 357))
  (segment (start 153.9 104.9) (end 164.80603 104.9) (width 0.1) (layer "In2.Cu") (net 357))
  (segment (start 145.9925 103.93) (end 152.93 103.93) (width 0.1) (layer "In2.Cu") (net 357))
  (segment (start 171.056328 100.480008) (end 170.636328 100.060008) (width 0.1) (layer "In2.Cu") (net 357))
  (segment (start 129.1 87.475) (end 129.85 86.725) (width 0.1) (layer "In2.Cu") (net 357))
  (segment (start 129.85 81.050437) (end 123.794171 74.994608) (width 0.1) (layer "In2.Cu") (net 357))
  (segment (start 129.1 88.6) (end 130.05 89.55) (width 0.1) (layer "In2.Cu") (net 357))
  (segment (start 133.066362 89.55) (end 138.33 94.813638) (width 0.1) (layer "In2.Cu") (net 357))
  (segment (start 171.056328 103.706328) (end 171.056328 100.480008) (width 0.1) (layer "In2.Cu") (net 357))
  (segment (start 129.1 88.1) (end 129.1 88.6) (width 0.1) (layer "In2.Cu") (net 357))
  (segment (start 138.33 100.305) (end 141.125 103.1) (width 0.1) (layer "In2.Cu") (net 357))
  (segment (start 138.33 94.813638) (end 138.33 100.305) (width 0.1) (layer "In2.Cu") (net 357))
  (segment (start 128.7 90.5) (end 128.7 88.5) (width 0.1) (layer "In9.Cu") (net 357))
  (segment (start 126.8 92.4) (end 128.7 90.5) (width 0.1) (layer "In9.Cu") (net 357))
  (segment (start 128.7 88.5) (end 129.1 88.1) (width 0.1) (layer "In9.Cu") (net 357))
  (segment (start 122 92.4) (end 126.8 92.4) (width 0.1) (layer "In9.Cu") (net 357))
  (segment (start 118.2 92.275) (end 121.4 92.275) (width 0.1) (layer "B.Cu") (net 357))
  (segment (start 117.675 90.62897) (end 117.675 91.75) (width 0.1) (layer "B.Cu") (net 357))
  (segment (start 118.075 90.22897) (end 117.675 90.62897) (width 0.1) (layer "B.Cu") (net 357))
  (segment (start 128.575 90.05) (end 128.825 89.8) (width 0.1) (layer "B.Cu") (net 357))
  (segment (start 117.7 89.63603) (end 118.075 90.01103) (width 0.1) (layer "B.Cu") (net 357))
  (segment (start 128.825 88.375) (end 129.1 88.1) (width 0.1) (layer "B.Cu") (net 357))
  (segment (start 121.4 92.275) (end 121.525 92.4) (width 0.1) (layer "B.Cu") (net 357))
  (segment (start 117.675 91.75) (end 118.2 92.275) (width 0.1) (layer "B.Cu") (net 357))
  (segment (start 121.525 92.4) (end 122 92.4) (width 0.1) (layer "B.Cu") (net 357))
  (segment (start 117.8325 89.2675) (end 117.7 89.4) (width 0.1) (layer "B.Cu") (net 357))
  (segment (start 117.7 89.4) (end 117.7 89.63603) (width 0.1) (layer "B.Cu") (net 357))
  (segment (start 118.0975 89.2675) (end 117.8325 89.2675) (width 0.1) (layer "B.Cu") (net 357))
  (segment (start 128.825 89.8) (end 128.825 88.375) (width 0.1) (layer "B.Cu") (net 357))
  (segment (start 128.2625 90.05) (end 128.575 90.05) (width 0.1) (layer "B.Cu") (net 357))
  (segment (start 118.075 90.01103) (end 118.075 90.22897) (width 0.1) (layer "B.Cu") (net 357))
  (segment (start 121.855128 72.140008) (end 121.855128 73.959008) (width 0.15) (layer "F.Cu") (net 358))
  (segment (start 172.136328 98.560008) (end 171.636328 99.060008) (width 0.1) (layer "F.Cu") (net 358))
  (segment (start 122.002128 75.782008) (end 122.002128 74.106008) (width 0.15) (layer "F.Cu") (net 358))
  (via (at 128.4 88.1) (size 0.5) (drill 0.2) (layers "F.Cu" "B.Cu") (net 358))
  (via (at 122 91.7) (size 0.5) (drill 0.2) (layers "F.Cu" "B.Cu") (net 358))
  (via (at 122.002128 75.782008) (size 0.5) (drill 0.2) (layers "F.Cu" "B.Cu") (net 358))
  (via (at 171.636328 99.060008) (size 0.5) (drill 0.2) (layers "F.Cu" "B.Cu") (net 358))
  (segment (start 140.91692 103.5) (end 144.9 103.5) (width 0.1) (layer "In2.Cu") (net 358))
  (segment (start 138.009828 95.184828) (end 138.009828 100.592908) (width 0.1) (layer "In2.Cu") (net 358))
  (segment (start 164.55 105.3) (end 164.96 105.71) (width 0.1) (layer "In2.Cu") (net 358))
  (segment (start 123.957008 75.782008) (end 122.002128 75.782008) (width 0.1) (layer "In2.Cu") (net 358))
  (segment (start 145.7 104.3) (end 152.81447 104.3) (width 0.1) (layer "In2.Cu") (net 358))
  (segment (start 138.009828 100.592908) (end 140.91692 103.5) (width 0.1) (layer "In2.Cu") (net 358))
  (segment (start 152.81447 104.3) (end 153.81447 105.3) (width 0.1) (layer "In2.Cu") (net 358))
  (segment (start 129.325 86.475) (end 129.325 81.15) (width 0.1) (layer "In2.Cu") (net 358))
  (segment (start 128.4 88.1) (end 128.4 88.7) (width 0.1) (layer "In2.Cu") (net 358))
  (segment (start 128.4 88.1) (end 128.4 87.4) (width 0.1) (layer "In2.Cu") (net 358))
  (segment (start 153.81447 105.3) (end 164.55 105.3) (width 0.1) (layer "In2.Cu") (net 358))
  (segment (start 132.875 90.05) (end 138.009828 95.184828) (width 0.1) (layer "In2.Cu") (net 358))
  (segment (start 170.69 105.71) (end 172.15 104.25) (width 0.1) (layer "In2.Cu") (net 358))
  (segment (start 129.325 81.15) (end 123.957008 75.782008) (width 0.1) (layer "In2.Cu") (net 358))
  (segment (start 172.15 99.57368) (end 171.636328 99.060008) (width 0.1) (layer "In2.Cu") (net 358))
  (segment (start 172.15 104.25) (end 172.15 99.57368) (width 0.1) (layer "In2.Cu") (net 358))
  (segment (start 128.4 88.7) (end 129.75 90.05) (width 0.1) (layer "In2.Cu") (net 358))
  (segment (start 128.4 87.4) (end 129.325 86.475) (width 0.1) (layer "In2.Cu") (net 358))
  (segment (start 164.96 105.71) (end 170.69 105.71) (width 0.1) (layer "In2.Cu") (net 358))
  (segment (start 144.9 103.5) (end 145.7 104.3) (width 0.1) (layer "In2.Cu") (net 358))
  (segment (start 129.75 90.05) (end 132.875 90.05) (width 0.1) (layer "In2.Cu") (net 358))
  (segment (start 128.4 90.2) (end 128.4 88.1) (width 0.1) (layer "In9.Cu") (net 358))
  (segment (start 122 91.7) (end 122.3 92) (width 0.1) (layer "In9.Cu") (net 358))
  (segment (start 126.6 92) (end 128.4 90.2) (width 0.1) (layer "In9.Cu") (net 358))
  (segment (start 122.3 92) (end 126.6 92) (width 0.1) (layer "In9.Cu") (net 358))
  (segment (start 118.81 90.19) (end 118.5 90.5) (width 0.1) (layer "B.Cu") (net 358))
  (segment (start 121.35 91.9) (end 121.55 91.7) (width 0.1) (layer "B.Cu") (net 358))
  (segment (start 117.95 90.92603) (end 117.95 91.35) (width 0.1) (layer "B.Cu") (net 358))
  (segment (start 121.55 91.7) (end 122 91.7) (width 0.1) (layer "B.Cu") (net 358))
  (segment (start 118.5 90.5) (end 118.37603 90.5) (width 0.1) (layer "B.Cu") (net 358))
  (segment (start 127.55 88.85) (end 127.675 88.725) (width 0.1) (layer "B.Cu") (net 358))
  (segment (start 128.4 88.55) (end 128.4 88.1) (width 0.1) (layer "B.Cu") (net 358))
  (segment (start 127.675 88.725) (end 128.225 88.725) (width 0.1) (layer "B.Cu") (net 358))
  (segment (start 118.81 89.98) (end 118.81 90.19) (width 0.1) (layer "B.Cu") (net 358))
  (segment (start 118.37603 90.5) (end 117.95 90.92603) (width 0.1) (layer "B.Cu") (net 358))
  (segment (start 117.95 91.35) (end 118.5 91.9) (width 0.1) (layer "B.Cu") (net 358))
  (segment (start 128.225 88.725) (end 128.4 88.55) (width 0.1) (layer "B.Cu") (net 358))
  (segment (start 118.5 91.9) (end 121.35 91.9) (width 0.1) (layer "B.Cu") (net 358))
  (segment (start 127.55 89.3375) (end 127.55 88.85) (width 0.1) (layer "B.Cu") (net 358))
  (segment (start 201.9 114.185) (end 198.385 117.7) (width 0.2) (layer "F.Cu") (net 360))
  (segment (start 198.385 117.7) (end 194.1 117.7) (width 0.2) (layer "F.Cu") (net 360))
  (via (at 189 125.6) (size 0.5) (drill 0.2) (layers "F.Cu" "B.Cu") (free) (net 360))
  (via (at 177.2 126.2) (size 0.5) (drill 0.2) (layers "F.Cu" "B.Cu") (free) (net 360))
  (via (at 190.2 126.2) (size 0.5) (drill 0.2) (layers "F.Cu" "B.Cu") (free) (net 360))
  (via (at 178.4 126.2) (size 0.5) (drill 0.2) (layers "F.Cu" "B.Cu") (free) (net 360))
  (via (at 178.4 125.6) (size 0.5) (drill 0.2) (layers "F.Cu" "B.Cu") (free) (net 360))
  (via (at 177.2 125.6) (size 0.5) (drill 0.2) (layers "F.Cu" "B.Cu") (free) (net 360))
  (via (at 189 126.2) (size 0.5) (drill 0.2) (layers "F.Cu" "B.Cu") (free) (net 360))
  (via (at 190.2 125.6) (size 0.5) (drill 0.2) (layers "F.Cu" "B.Cu") (free) (net 360))
  (via (at 189.6 125.6) (size 0.5) (drill 0.2) (layers "F.Cu" "B.Cu") (free) (net 360))
  (via (at 177.8 126.2) (size 0.5) (drill 0.2) (layers "F.Cu" "B.Cu") (free) (net 360))
  (via (at 177.8 125.6) (size 0.5) (drill 0.2) (layers "F.Cu" "B.Cu") (free) (net 360))
  (via (at 194.1 117.7) (size 0.5) (drill 0.2) (layers "F.Cu" "B.Cu") (net 360))
  (via (at 189.6 126.2) (size 0.5) (drill 0.2) (layers "F.Cu" "B.Cu") (free) (net 360))
  (segment (start 175.765 127.105) (end 175.765 126.365) (width 0.2) (layer "B.Cu") (net 360))
  (segment (start 175.765 126.365) (end 175.93 126.2) (width 0.2) (layer "B.Cu") (net 360))
  (segment (start 192.5 120.05) (end 192.5 117.875) (width 0.15) (layer "B.Cu") (net 360))
  (segment (start 175.93 126.2) (end 177.2 126.2) (width 0.2) (layer "B.Cu") (net 360))
  (segment (start 175.765 129.105) (end 175.765 127.105) (width 0.2) (layer "B.Cu") (net 360))
  (segment (start 192.675 117.7) (end 194.1 117.7) (width 0.15) (layer "B.Cu") (net 360))
  (segment (start 192.5 117.875) (end 192.675 117.7) (width 0.15) (layer "B.Cu") (net 360))
  (segment (start 140.926328 90.690008) (end 141.896328 91.660008) (width 0.2) (layer "F.Cu") (net 370))
  (segment (start 186.2 129.835) (end 186.135 129.9) (width 0.2) (layer "B.Cu") (net 381))
  (segment (start 186.2 129.835) (end 186.2 125.5) (width 0.2) (layer "B.Cu") (net 381))
  (segment (start 250.112079 120.512079) (end 250.415 120.815) (width 0.122) (layer "F.Cu") (net 403))
  (segment (start 249.479343 120.4535) (end 249.970657 120.4535) (width 0.122) (layer "F.Cu") (net 403))
  (segment (start 249.04 120.81) (end 249.337922 120.512078) (width 0.122) (layer "F.Cu") (net 403))
  (arc (start 249.970657 120.4535) (mid 250.047194 120.468724) (end 250.112079 120.512079) (width 0.122) (layer "F.Cu") (net 403))
  (arc (start 249.479343 120.4535) (mid 249.402807 120.468724) (end 249.337922 120.512078) (width 0.122) (layer "F.Cu") (net 403))
  (segment (start 191.636328 96.05) (end 191.136328 95.55) (width 0.127) (layer "F.Cu") (net 404))
  (segment (start 247.311921 120.512079) (end 247.185 120.639) (width 0.122) (layer "F.Cu") (net 404))
  (segment (start 248.07 120.81) (end 247.772078 120.512078) (width 0.122) (layer "F.Cu") (net 404))
  (segment (start 247.630657 120.4535) (end 247.453343 120.4535) (width 0.122) (layer "F.Cu") (net 404))
  (via blind (at 191.636328 96.05) (size 0.5) (drill 0.2) (layers "F.Cu" "In2.Cu") (net 404))
  (via (at 247.185 120.664) (size 0.5) (drill 0.2) (layers "F.Cu" "B.Cu") (net 404))
  (arc (start 247.311921 120.512079) (mid 247.376806 120.468724) (end 247.453343 120.4535) (width 0.122) (layer "F.Cu") (net 404))
  (arc (start 247.772078 120.512078) (mid 247.707193 120.468724) (end 247.630657 120.4535) (width 0.122) (layer "F.Cu") (net 404))
  (segment (start 246.880326 120.485) (end 246.972089 120.485) (width 0.13) (layer "In2.Cu") (net 404))
  (segment (start 240.722 117.245483) (end 240.722 118.308368) (width 0.13) (layer "In2.Cu") (net 404))
  (segment (start 207.202041 103.764335) (end 208.966929 101.999447) (width 0.13) (layer "In2.Cu") (net 404))
  (segment (start 233.794996 106.511372) (end 235.200553 107.916929) (width 0.13) (layer "In2.Cu") (net 404))
  (segment (start 232.097 102.770483) (end 232.097 103.033368) (width 0.13) (layer "In2.Cu") (net 404))
  (segment (start 237.097 112.270483) (end 237.097 113.133368) (width 0.13) (layer "In2.Cu") (net 404))
  (segment (start 198.135771 103.962331) (end 206.724037 103.962331) (width 0.13) (layer "In2.Cu") (net 404))
  (segment (start 191.930294 96.05) (end 191.636328 96.05) (width 0.082) (layer "In2.Cu") (net 404))
  (segment (start 243.686372 119.680004) (end 244.39193 118.974446) (width 0.13) (layer "In2.Cu") (net 404))
  (segment (start 246.457128 120.217546) (end 246.614454 120.374872) (width 0.13) (layer "In2.Cu") (net 404))
  (segment (start 232.294996 103.511372) (end 233.450553 104.666929) (width 0.13) (layer "In2.Cu") (net 404))
  (segment (start 231.53307 101.999446) (end 231.950553 102.416929) (width 0.13) (layer "In2.Cu") (net 404))
  (segment (start 192.054 100.056888) (end 192.054 96.173706) (width 0.082) (layer "In2.Cu") (net 404))
  (segment (start 198.135771 103.962331) (end 198.126527 103.953087) (width 0.082) (layer "In2.Cu") (net 404))
  (segment (start 240.919996 118.786372) (end 241.813628 119.680004) (width 0.13) (layer "In2.Cu") (net 404))
  (segment (start 246.095202 118.886578) (end 246.288421 119.079797) (width 0.13) (layer "In2.Cu") (net 404))
  (segment (start 246.347 119.221219) (end 246.347 119.951674) (width 0.13) (layer "In2.Cu") (net 404))
  (segment (start 235.347 108.270483) (end 235.347 110.033368) (width 0.13) (layer "In2.Cu") (net 404))
  (segment (start 191.375077 103.721701) (end 191.207307 103.553931) (width 0.082) (layer "In2.Cu") (net 404))
  (segment (start 247.029978 120.508978) (end 247.185 120.664) (width 0.13) (layer "In2.Cu") (net 404))
  (segment (start 191.534534 100.441008) (end 191.66988 100.441008) (width 0.082) (layer "In2.Cu") (net 404))
  (segment (start 235.544996 110.511372) (end 236.950553 111.916929) (width 0.13) (layer "In2.Cu") (net 404))
  (segment (start 242.291632 119.878) (end 243.208368 119.878) (width 0.13) (layer "In2.Cu") (net 404))
  (segment (start 237.294996 113.611372) (end 240.575554 116.89193) (width 0.13) (layer "In2.Cu") (net 404))
  (segment (start 197.985105 103.894508) (end 191.79227 103.894508) (width 0.082) (layer "In2.Cu") (net 404))
  (segment (start 209.320483 101.853) (end 231.179517 101.853) (width 0.13) (layer "In2.Cu") (net 404))
  (segment (start 244.745483 118.828) (end 245.953781 118.828) (width 0.13) (layer "In2.Cu") (net 404))
  (segment (start 191.0345 103.136738) (end 191.0345 100.941042) (width 0.082) (layer "In2.Cu") (net 404))
  (segment (start 191.173917 100.604459) (end 191.197951 100.580425) (width 0.082) (layer "In2.Cu") (net 404))
  (segment (start 192.018853 96.088853) (end 192.015147 96.085147) (width 0.082) (layer "In2.Cu") (net 404))
  (segment (start 191.882012 100.35314) (end 191.966132 100.26902) (width 0.082) (layer "In2.Cu") (net 404))
  (segment (start 233.597 105.020483) (end 233.597 106.033368) (width 0.13) (layer "In2.Cu") (net 404))
  (arc (start 246.347 119.951674) (mid 246.375621 120.095563) (end 246.457128 120.217546) (width 0.13) (layer "In2.Cu") (net 404))
  (arc (start 237.097 113.133368) (mid 237.148457 113.392062) (end 237.294996 113.611372) (width 0.13) (layer "In2.Cu") (net 404))
  (arc (start 235.200553 107.916929) (mid 235.30894 108.079141) (end 235.347 108.270483) (width 0.13) (layer "In2.Cu") (net 404))
  (arc (start 243.208368 119.878) (mid 243.467062 119.826543) (end 243.686372 119.680004) (width 0.13) (layer "In2.Cu") (net 404))
  (arc (start 246.972089 120.485) (mid 247.003418 120.491232) (end 247.029978 120.508978) (width 0.13) (layer "In2.Cu") (net 404))
  (arc (start 231.179517 101.853) (mid 231.370858 101.89106) (end 231.53307 101.999446) (width 0.13) (layer "In2.Cu") (net 404))
  (arc (start 231.950553 102.416929) (mid 232.05894 102.579141) (end 232.097 102.770483) (width 0.13) (layer "In2.Cu") (net 404))
  (arc (start 241.813628 119.680004) (mid 242.032938 119.826543) (end 242.291632 119.878) (width 0.13) (layer "In2.Cu") (net 404))
  (arc (start 206.724037 103.962331) (mid 206.982731 103.910873) (end 207.202041 103.764335) (width 0.13) (layer "In2.Cu") (net 404))
  (arc (start 244.39193 118.974446) (mid 244.554142 118.86606) (end 244.745483 118.828) (width 0.13) (layer "In2.Cu") (net 404))
  (arc (start 240.575554 116.89193) (mid 240.68394 117.054142) (end 240.722 117.245483) (width 0.13) (layer "In2.Cu") (net 404))
  (arc (start 236.950553 111.916929) (mid 237.05894 112.079141) (end 237.097 112.270483) (width 0.13) (layer "In2.Cu") (net 404))
  (arc (start 191.66988 100.441008) (mid 191.784685 100.418172) (end 191.882012 100.35314) (width 0.082) (layer "In2.Cu") (net 404))
  (arc (start 245.953781 118.828) (mid 246.030317 118.843224) (end 246.095202 118.886578) (width 0.13) (layer "In2.Cu") (net 404))
  (arc (start 208.966929 101.999447) (mid 209.129141 101.89106) (end 209.320483 101.853) (width 0.13) (layer "In2.Cu") (net 404))
  (arc (start 232.097 103.033368) (mid 232.148458 103.292062) (end 232.294996 103.511372) (width 0.13) (layer "In2.Cu") (net 404))
  (arc (start 192.054 96.173706) (mid 192.044866 96.127784) (end 192.018853 96.088853) (width 0.082) (layer "In2.Cu") (net 404))
  (arc (start 198.126527 103.953087) (mid 198.061642 103.909732) (end 197.985105 103.894508) (width 0.082) (layer "In2.Cu") (net 404))
  (arc (start 191.0345 100.941042) (mid 191.070733 100.758885) (end 191.173917 100.604459) (width 0.082) (layer "In2.Cu") (net 404))
  (arc (start 246.288421 119.079797) (mid 246.331776 119.144682) (end 246.347 119.221219) (width 0.13) (layer "In2.Cu") (net 404))
  (arc (start 191.207307 103.553931) (mid 191.079411 103.362521) (end 191.0345 103.136738) (width 0.082) (layer "In2.Cu") (net 404))
  (arc (start 192.054 100.056888) (mid 192.031164 100.171693) (end 191.966132 100.26902) (width 0.082) (layer "In2.Cu") (net 404))
  (arc (start 191.930294 96.05) (mid 191.976216 96.059134) (end 192.015147 96.085147) (width 0.082) (layer "In2.Cu") (net 404))
  (arc (start 240.722 118.308368) (mid 240.773457 118.567062) (end 240.919996 118.786372) (width 0.13) (layer "In2.Cu") (net 404))
  (arc (start 233.597 106.033368) (mid 233.648457 106.292062) (end 233.794996 106.511372) (width 0.13) (layer "In2.Cu") (net 404))
  (arc (start 246.614454 120.374872) (mid 246.736437 120.456379) (end 246.880326 120.485) (width 0.13) (layer "In2.Cu") (net 404))
  (arc (start 233.450553 104.666929) (mid 233.55894 104.829141) (end 233.597 105.020483) (width 0.13) (layer "In2.Cu") (net 404))
  (arc (start 235.347 110.033368) (mid 235.398457 110.292062) (end 235.544996 110.511372) (width 0.13) (layer "In2.Cu") (net 404))
  (arc (start 191.534534 100.441008) (mid 191.352377 100.477241) (end 191.197951 100.580425) (width 0.082) (layer "In2.Cu") (net 404))
  (arc (start 191.79227 103.894508) (mid 191.566487 103.849597) (end 191.375077 103.721701) (width 0.082) (layer "In2.Cu") (net 404))
  (segment (start 249.725 123.875) (end 249.725 124.15) (width 0.3) (layer "F.Cu") (net 405))
  (segment (start 250.1508 123.4492) (end 249.725 123.875) (width 0.3) (layer "F.Cu") (net 405))
  (segment (start 250.675 123.4492) (end 250.1508 123.4492) (width 0.3) (layer "F.Cu") (net 405))
  (via (at 249.725 124.15) (size 0.5) (drill 0.2) (layers "F.Cu" "B.Cu") (net 405))
  (segment (start 250.34 124.765) (end 249.725 124.15) (width 0.127) (layer "B.Cu") (net 405))
  (segment (start 250.365 124.765) (end 250.34 124.765) (width 0.127) (layer "B.Cu") (net 405))
  (segment (start 180.136328 102.560008) (end 179.636328 103.060008) (width 0.1) (layer "F.Cu") (net 406))
  (via blind (at 179.636328 103.060008) (size 0.5) (drill 0.2) (layers "F.Cu" "In5.Cu") (net 406))
  (via (at 247.19 100.936) (size 0.5) (drill 0.2) (layers "F.Cu" "B.Cu") (net 406))
  (segment (start 180.221232 105.45) (end 180.14253 105.341676) (width 0.1) (layer "In5.Cu") (net 406))
  (segment (start 236.125 100.75) (end 235.775 100.4) (width 0.1) (layer "In5.Cu") (net 406))
  (segment (start 181.259571 104.776201) (end 181.225 104.775) (width 0.1) (layer "In5.Cu") (net 406))
  (segment (start 179.825 104.775) (end 179.762704 104.773182) (width 0.1) (layer "In5.Cu") (net 406))
  (segment (start 181.4 103.208943) (end 180.846057 102.655) (width 0.09) (layer "In5.Cu") (net 406))
  (segment (start 181.175 104.775) (end 181.141849 104.776278) (width 0.1) (layer "In5.Cu") (net 406))
  (segment (start 181.05 104.9) (end 181.05 105.05) (width 0.1) (layer "In5.Cu") (net 406))
  (segment (start 179.359065 104.482641) (end 179.326818 104.362296) (width 0.1) (layer "In5.Cu") (net 406))
  (segment (start 181.048846 105.051154) (end 181.048846 105.147386) (width 0.1) (layer "In5.Cu") (net 406))
  (segment (start 247.619867 101.117999) (end 247.75 100.987866) (width 0.1) (layer "In5.Cu") (net 406))
  (segment (start 179.509459 104.67864) (end 179.42136 104.590541) (width 0.1) (layer "In5.Cu") (net 406))
  (segment (start 181.4 103.65) (end 181.4 103.412134) (width 0.1) (layer "In5.Cu") (net 406))
  (segment (start 180.098846 105.147386) (end 180.098846 105.051154) (width 0.1) (layer "In5.Cu") (net 406))
  (segment (start 180.008151 104.776278) (end 179.975 104.775) (width 0.1) (layer "In5.Cu") (net 406))
  (segment (start 181.323449 104.80266) (end 181.259571 104.776201) (width 0.1) (layer "In5.Cu") (net 406))
  (segment (start 180.098722 104.866849) (end 180.065571 104.809429) (width 0.1) (layer "In5.Cu") (net 406))
  (segment (start 181.37234 103.748449) (end 181.398799 103.684571) (width 0.1) (layer "In5.Cu") (net 406))
  (segment (start 179.326818 104.237704) (end 179.359065 104.117359) (width 0.1) (layer "In5.Cu") (net 406))
  (segment (start 245.24 100.930436) (end 245.24 100.9) (width 0.1) (layer "In5.Cu") (net 406))
  (segment (start 210.062134 100.4) (end 202.412134 108.05) (width 0.1) (layer "In5.Cu") (net 406))
  (segment (start 179.737704 104.773182) (end 179.617359 104.740935) (width 0.1) (layer "In5.Cu") (net 406))
  (segment (start 180.92646 105.45) (end 180.818136 105.528702) (width 0.1) (layer "In5.Cu") (net 406))
  (segment (start 179.42136 104.590541) (end 179.359065 104.482641) (width 0.1) (layer "In5.Cu") (net 406))
  (segment (start 179.762704 103.826818) (end 179.825 103.825) (width 0.1) (layer "In5.Cu") (net 406))
  (segment (start 181.398799 104.915429) (end 181.37234 104.851551) (width 0.1) (layer "In5.Cu") (net 406))
  (segment (start 179.975 104.775) (end 179.825 104.775) (width 0.1) (layer "In5.Cu") (net 406))
  (segment (start 202.412134 108.05) (end 183.337866 108.05) (width 0.1) (layer "In5.Cu") (net 406))
  (segment (start 247.75 100.762134) (end 247.387866 100.4) (width 0.1) (layer "In5.Cu") (net 406))
  (segment (start 181.005162 105.341676) (end 180.92646 105.45) (width 0.1) (layer "In5.Cu") (net 406))
  (segment (start 181.4 104.95) (end 181.398799 104.915429) (width 0.1) (layer "In5.Cu") (net 406))
  (segment (start 245.05797 100.75) (end 244.82397 100.516) (width 0.1) (layer "In5.Cu") (net 406))
  (segment (start 180.14253 105.341676) (end 180.101154 105.214334) (width 0.1) (layer "In5.Cu") (net 406))
  (segment (start 247.19 100.936) (end 247.371999 101.117999) (width 0.1) (layer "In5.Cu") (net 406))
  (segment (start 180.1 105.05) (end 180.1 104.9) (width 0.1) (layer "In5.Cu") (net 406))
  (segment (start 179.617359 104.740935) (end 179.509459 104.67864) (width 0.1) (layer "In5.Cu") (net 406))
  (segment (start 179.359065 104.117359) (end 179.42136 104.009459) (width 0.1) (layer "In5.Cu") (net 406))
  (segment (start 179.325 104.3) (end 179.326818 104.237704) (width 0.1) (layer "In5.Cu") (net 406))
  (segment (start 245.54 100.9) (end 245.54 100.930436) (width 0.1) (layer "In5.Cu") (net 406))
  (segment (start 180.098846 105.051154) (end 180.1 105.05) (width 0.1) (layer "In5.Cu") (net 406))
  (segment (start 180.523846 105.572386) (end 180.456898 105.570078) (width 0.1) (layer "In5.Cu") (net 406))
  (segment (start 179.509459 103.92136) (end 179.617359 103.859065) (width 0.1) (layer "In5.Cu") (net 406))
  (segment (start 244.82397 100.516) (end 244.47603 100.516) (width 0.1) (layer "In5.Cu") (net 406))
  (segment (start 247.387866 100.4) (end 246.762134 100.4) (width 0.1) (layer "In5.Cu") (net 406))
  (segment (start 181.225 103.825) (end 181.259571 103.823799) (width 0.1) (layer "In5.Cu") (net 406))
  (segment (start 244.24203 100.75) (end 236.125 100.75) (width 0.1) (layer "In5.Cu") (net 406))
  (segment (start 180.065571 104.809429) (end 180.008151 104.776278) (width 0.1) (layer "In5.Cu") (net 406))
  (segment (start 180.690794 105.570078) (end 180.623846 105.572386) (width 0.1) (layer "In5.Cu") (net 406))
  (segment (start 235.775 100.4) (end 210.062134 100.4) (width 0.1) (layer "In5.Cu") (net 406))
  (segment (start 181.05 105.05) (end 181.048846 105.051154) (width 0.1) (layer "In5.Cu") (net 406))
  (segment (start 181.37234 104.851551) (end 181.323449 104.80266) (width 0.1) (layer "In5.Cu") (net 406))
  (segment (start 179.762704 104.773182) (end 179.737704 104.773182) (width 0.1) (layer "In5.Cu") (net 406))
  (segment (start 179.775 102.655) (end 179.636328 102.793672) (width 0.09) (layer "In5.Cu") (net 406))
  (segment (start 181.046538 105.214334) (end 181.005162 105.341676) (width 0.1) (layer "In5.Cu") (net 406))
  (segment (start 181.323449 103.79734) (end 181.37234 103.748449) (width 0.1) (layer "In5.Cu") (net 406))
  (segment (start 181.048846 105.147386) (end 181.046538 105.214334) (width 0.1) (layer "In5.Cu") (net 406))
  (segment (start 179.42136 104.009459) (end 179.509459 103.92136) (width 0.1) (layer "In5.Cu") (net 406))
  (segment (start 181.4 106.112134) (end 181.4 104.95) (width 0.1) (layer "In5.Cu") (net 406))
  (segment (start 180.329556 105.528702) (end 180.221232 105.45) (width 0.1) (layer "In5.Cu") (net 406))
  (segment (start 246.412134 100.75) (end 245.69 100.75) (width 0.1) (layer "In5.Cu") (net 406))
  (segment (start 246.762134 100.4) (end 246.412134 100.75) (width 0.1) (layer "In5.Cu") (net 406))
  (segment (start 245.09 100.75) (end 245.05797 100.75) (width 0.1) (layer "In5.Cu") (net 406))
  (segment (start 183.337866 108.05) (end 181.4 106.112134) (width 0.1) (layer "In5.Cu") (net 406))
  (segment (start 247.371999 101.117999) (end 247.619867 101.117999) (width 0.1) (layer "In5.Cu") (net 406))
  (segment (start 181.084429 104.809429) (end 181.051278 104.866849) (width 0.1) (layer "In5.Cu") (net 406))
  (segment (start 244.47603 100.516) (end 244.24203 100.75) (width 0.1) (layer "In5.Cu") (net 406))
  (segment (start 181.398799 103.684571) (end 181.4 103.65) (width 0.1) (layer "In5.Cu") (net 406))
  (segment (start 180.623846 105.572386) (end 180.523846 105.572386) (width 0.1) (layer "In5.Cu") (net 406))
  (segment (start 247.75 100.987866) (end 247.75 100.762134) (width 0.1) (layer "In5.Cu") (net 406))
  (segment (start 180.818136 105.528702) (end 180.690794 105.570078) (width 0.1) (layer "In5.Cu") (net 406))
  (segment (start 181.141849 104.776278) (end 181.084429 104.809429) (width 0.1) (layer "In5.Cu") (net 406))
  (segment (start 181.051278 104.866849) (end 181.05 104.9) (width 0.1) (layer "In5.Cu") (net 406))
  (segment (start 180.846057 102.655) (end 179.775 102.655) (width 0.09) (layer "In5.Cu") (net 406))
  (segment (start 179.636328 102.793672) (end 179.636328 103.060008) (width 0.09) (layer "In5.Cu") (net 406))
  (segment (start 179.737704 103.826818) (end 179.762704 103.826818) (width 0.1) (layer "In5.Cu") (net 406))
  (segment (start 179.326818 104.362296) (end 179.325 104.3) (width 0.1) (layer "In5.Cu") (net 406))
  (segment (start 180.456898 105.570078) (end 180.329556 105.528702) (width 0.1) (layer "In5.Cu") (net 406))
  (segment (start 181.259571 103.823799) (end 181.323449 103.79734) (width 0.1) (layer "In5.Cu") (net 406))
  (segment (start 180.1 104.9) (end 180.098722 104.866849) (width 0.1) (layer "In5.Cu") (net 406))
  (segment (start 179.617359 103.859065) (end 179.737704 103.826818) (width 0.1) (layer "In5.Cu") (net 406))
  (segment (start 181.4 103.412134) (end 181.4 103.208943) (width 0.09) (layer "In5.Cu") (net 406))
  (segment (start 181.225 104.775) (end 181.175 104.775) (width 0.1) (layer "In5.Cu") (net 406))
  (segment (start 179.825 103.825) (end 181.225 103.825) (width 0.1) (layer "In5.Cu") (net 406))
  (segment (start 180.101154 105.214334) (end 180.098846 105.147386) (width 0.1) (layer "In5.Cu") (net 406))
  (arc (start 245.39 101.080436) (mid 245.283934 101.036502) (end 245.24 100.930436) (width 0.1) (layer "In5.Cu") (net 406))
  (arc (start 245.69 100.75) (mid 245.583934 100.793934) (end 245.54 100.9) (width 0.1) (layer "In5.Cu") (net 406))
  (arc (start 245.54 100.930436) (mid 245.496066 101.036502) (end 245.39 101.080436) (width 0.1) (layer "In5.Cu") (net 406))
  (arc (start 245.24 100.9) (mid 245.196066 100.793934) (end 245.09 100.75) (width 0.1) (layer "In5.Cu") (net 406))
  (segment (start 247.19 100.936) (end 247.371999 101.117999) (width 0.1) (layer "B.Cu") (net 406))
  (segment (start 247.825 101.015) (end 247.825 100.635) (width 0.1) (layer "B.Cu") (net 406))
  (segment (start 247.371999 101.117999) (end 247.722001 101.117999) (width 0.1) (layer "B.Cu") (net 406))
  (segment (start 247.722001 101.117999) (end 247.825 101.015) (width 0.1) (layer "B.Cu") (net 406))
  (segment (start 179.136328 102.560008) (end 178.636328 103.060008) (width 0.1) (layer "F.Cu") (net 407))
  (via blind (at 178.636328 103.060008) (size 0.5) (drill 0.2) (layers "F.Cu" "In5.Cu") (net 407))
  (via (at 248.46 102.87) (size 0.5) (drill 0.2) (layers "F.Cu" "B.Cu") (net 407))
  (segment (start 248.152 103.4) (end 248.202 103.4) (width 0.1) (layer "In5.Cu") (net 407))
  (segment (start 235.062134 102.1) (end 242.962134 102.1) (width 0.1) (layer "In5.Cu") (net 407))
  (segment (start 178.339992 103.060008) (end 178.286329 103.113671) (width 0.1) (layer "In5.Cu") (net 407))
  (segment (start 249.05 102.862134) (end 248.875867 102.688001) (width 0.1) (layer "In5.Cu") (net 407))
  (segment (start 245.062134 102.95) (end 245.512134 103.4) (width 0.1) (layer "In5.Cu") (net 407))
  (segment (start 245.512134 103.4) (end 246.253 103.4) (width 0.1) (layer "In5.Cu") (net 407))
  (segment (start 243.812134 102.95) (end 245.062134 102.95) (width 0.1) (layer "In5.Cu") (net 407))
  (segment (start 247.153 103.4) (end 247.203 103.4) (width 0.1) (layer "In5.Cu") (net 407))
  (segment (start 248.737866 103.4) (end 249.05 103.087866) (width 0.1) (layer "In5.Cu") (net 407))
  (segment (start 247.203 103.4) (end 247.402 103.4) (width 0.1) (layer "In5.Cu") (net 407))
  (segment (start 248.641999 102.688001) (end 248.46 102.87) (width 0.1) (layer "In5.Cu") (net 407))
  (segment (start 178.636328 103.060008) (end 178.339992 103.060008) (width 0.1) (layer "In5.Cu") (net 407))
  (segment (start 234.337134 101.375) (end 235.062134 102.1) (width 0.1) (layer "In5.Cu") (net 407))
  (segment (start 203.537866 108.75) (end 210.912866 101.375) (width 0.1) (layer "In5.Cu") (net 407))
  (segment (start 246.478 103.175) (end 246.478 103.08244) (width 0.1) (layer "In5.Cu") (net 407))
  (segment (start 210.912866 101.375) (end 234.337134 101.375) (width 0.1) (layer "In5.Cu") (net 407))
  (segment (start 242.962134 102.1) (end 243.812134 102.95) (width 0.1) (layer "In5.Cu") (net 407))
  (segment (start 246.928 103.08244) (end 246.928 103.175) (width 0.1) (layer "In5.Cu") (net 407))
  (segment (start 248.875867 102.688001) (end 248.641999 102.688001) (width 0.1) (layer "In5.Cu") (net 407))
  (segment (start 182.937134 108.75) (end 203.537866 108.75) (width 0.1) (layer "In5.Cu") (net 407))
  (segment (start 178.286329 103.113671) (end 178.286329 104.099195) (width 0.1) (layer "In5.Cu") (net 407))
  (segment (start 247.752 103.05) (end 247.802 103.05) (width 0.1) (layer "In5.Cu") (net 407))
  (segment (start 178.286329 104.099195) (end 182.937134 108.75) (width 0.1) (layer "In5.Cu") (net 407))
  (segment (start 248.202 103.4) (end 248.737866 103.4) (width 0.1) (layer "In5.Cu") (net 407))
  (segment (start 249.05 103.087866) (end 249.05 102.862134) (width 0.1) (layer "In5.Cu") (net 407))
  (arc (start 246.253 103.4) (mid 246.412099 103.334099) (end 246.478 103.175) (width 0.1) (layer "In5.Cu") (net 407))
  (arc (start 247.977 103.225) (mid 248.028256 103.348744) (end 248.152 103.4) (width 0.1) (layer "In5.Cu") (net 407))
  (arc (start 247.402 103.4) (mid 247.525744 103.348744) (end 247.577 103.225) (width 0.1) (layer "In5.Cu") (net 407))
  (arc (start 246.703 102.85744) (mid 246.862099 102.923341) (end 246.928 103.08244) (width 0.1) (layer "In5.Cu") (net 407))
  (arc (start 247.802 103.05) (mid 247.925744 103.101256) (end 247.977 103.225) (width 0.1) (layer "In5.Cu") (net 407))
  (arc (start 246.928 103.175) (mid 246.993901 103.334099) (end 247.153 103.4) (width 0.1) (layer "In5.Cu") (net 407))
  (arc (start 246.478 103.08244) (mid 246.543901 102.923341) (end 246.703 102.85744) (width 0.1) (layer "In5.Cu") (net 407))
  (arc (start 247.577 103.225) (mid 247.628256 103.101256) (end 247.752 103.05) (width 0.1) (layer "In5.Cu") (net 407))
  (segment (start 248.641999 102.688001) (end 249.023001 102.688001) (width 0.1) (layer "B.Cu") (net 407))
  (segment (start 249.023001 102.688001) (end 249.095 102.76) (width 0.1) (layer "B.Cu") (net 407))
  (segment (start 248.46 102.87) (end 248.641999 102.688001) (width 0.1) (layer "B.Cu") (net 407))
  (segment (start 249.095 102.76) (end 249.095 103.175) (width 0.1) (layer "B.Cu") (net 407))
  (segment (start 249.04 119.81) (end 249.337922 120.107922) (width 0.122) (layer "F.Cu") (net 408))
  (segment (start 249.479343 120.1665) (end 249.980657 120.1665) (width 0.122) (layer "F.Cu") (net 408))
  (segment (start 250.122079 120.107921) (end 250.415 119.815) (width 0.122) (layer "F.Cu") (net 408))
  (arc (start 249.337922 120.107922) (mid 249.402807 120.151276) (end 249.479343 120.1665) (width 0.122) (layer "F.Cu") (net 408))
  (arc (start 249.980657 120.1665) (mid 250.057194 120.151276) (end 250.122079 120.107921) (width 0.122) (layer "F.Cu") (net 408))
  (segment (start 192.636328 96.05) (end 192.136328 95.55) (width 0.127) (layer "F.Cu") (net 409))
  (segment (start 247.630657 120.1665) (end 247.459343 120.1665) (width 0.122) (layer "F.Cu") (net 409))
  (segment (start 247.317921 120.107921) (end 247.185 119.975) (width 0.122) (layer "F.Cu") (net 409))
  (segment (start 248.07 119.81) (end 247.772078 120.107922) (width 0.122) (layer "F.Cu") (net 409))
  (via blind (at 192.636328 96.05) (size 0.5) (drill 0.2) (layers "F.Cu" "In2.Cu") (net 409))
  (via (at 247.185 120) (size 0.5) (drill 0.2) (layers "F.Cu" "B.Cu") (net 409))
  (arc (start 247.459343 120.1665) (mid 247.382806 120.151276) (end 247.317921 120.107921) (width 0.122) (layer "F.Cu") (net 409))
  (arc (start 247.630657 120.1665) (mid 247.707193 120.151276) (end 247.772078 120.107922) (width 0.122) (layer "F.Cu") (net 409))
  (segment (start 243.50807 119.425554) (end 244.213628 118.719996) (width 0.13) (layer "In2.Cu") (net 409))
  (segment (start 191.206481 103.10275) (end 191.206481 100.939407) (width 0.082) (layer "In2.Cu") (net 409))
  (segment (start 207.02374 103.509884) (end 208.788628 101.744996) (width 0.13) (layer "In2.Cu") (net 409))
  (segment (start 244.691632 118.522) (end 246.007632 118.522) (width 0.13) (layer "In2.Cu") (net 409))
  (segment (start 241.028 117.191632) (end 241.028 118.254517) (width 0.13) (layer "In2.Cu") (net 409))
  (segment (start 191.472686 103.576062) (end 191.352928 103.456304) (width 0.082) (layer "In2.Cu") (net 409))
  (segment (start 191.532899 100.612989) (end 191.668215 100.612989) (width 0.082) (layer "In2.Cu") (net 409))
  (segment (start 198.135771 103.656331) (end 206.670186 103.656331) (width 0.13) (layer "In2.Cu") (net 409))
  (segment (start 232.549447 103.333071) (end 233.705004 104.488628) (width 0.13) (layer "In2.Cu") (net 409))
  (segment (start 198.135771 103.656331) (end 198.128173 103.663929) (width 0.082) (layer "In2.Cu") (net 409))
  (segment (start 237.403 112.216218) (end 237.403 113.079517) (width 0.13) (layer "In2.Cu") (net 409))
  (segment (start 192.004798 100.473572) (end 192.086583 100.391787) (width 0.082) (layer "In2.Cu") (net 409))
  (segment (start 197.986751 103.722508) (end 192.482508 103.722508) (width 0.082) (layer "In2.Cu") (net 409))
  (segment (start 192.357508 103.597508) (end 192.357508 103.597258) (width 0.082) (layer "In2.Cu") (net 409))
  (segment (start 192.349706 96.05) (end 192.636328 96.05) (width 0.082) (layer "In2.Cu") (net 409))
  (segment (start 191.294349 100.727275) (end 191.320767 100.700857) (width 0.082) (layer "In2.Cu") (net 409))
  (segment (start 192.261147 96.088853) (end 192.264853 96.085147) (width 0.082) (layer "In2.Cu") (net 409))
  (segment (start 241.174447 118.608071) (end 241.99193 119.425554) (width 0.13) (layer "In2.Cu") (net 409))
  (segment (start 191.932508 103.722508) (end 191.826239 103.722508) (width 0.082) (layer "In2.Cu") (net 409))
  (segment (start 192.226 100.055204) (end 192.226 96.173706) (width 0.082) (layer "In2.Cu") (net 409))
  (segment (start 192.107508 103.597258) (end 192.107508 103.597508) (width 0.082) (layer "In2.Cu") (net 409))
  (segment (start 237.549447 113.433071) (end 240.830004 116.713628) (width 0.13) (layer "In2.Cu") (net 409))
  (segment (start 235.799447 110.333071) (end 237.205297 111.738921) (width 0.13) (layer "In2.Cu") (net 409))
  (segment (start 233.903 104.966632) (end 233.903 105.979517) (width 0.13) (layer "In2.Cu") (net 409))
  (segment (start 242.345483 119.572) (end 243.154517 119.572) (width 0.13) (layer "In2.Cu") (net 409))
  (segment (start 246.273504 118.632128) (end 246.542872 118.901496) (width 0.13) (layer "In2.Cu") (net 409))
  (segment (start 246.711579 120.039245) (end 246.822045 120.149711) (width 0.13) (layer "In2.Cu") (net 409))
  (segment (start 232.403 102.716632) (end 232.403 102.979517) (width 0.13) (layer "In2.Cu") (net 409))
  (segment (start 246.653 119.167368) (end 246.653 119.897823) (width 0.13) (layer "In2.Cu") (net 409))
  (segment (start 247.064545 120.120455) (end 247.185 120) (width 0.13) (layer "In2.Cu") (net 409))
  (segment (start 234.049447 106.333071) (end 235.455297 107.738921) (width 0.13) (layer "In2.Cu") (net 409))
  (segment (start 191.982508 103.722508) (end 191.932508 103.722508) (width 0.082) (layer "In2.Cu") (net 409))
  (segment (start 235.653 108.216218) (end 235.653 109.979517) (width 0.13) (layer "In2.Cu") (net 409))
  (segment (start 246.892755 120.179) (end 246.923157 120.179) (width 0.13) (layer "In2.Cu") (net 409))
  (segment (start 209.266632 101.547) (end 231.233368 101.547) (width 0.13) (layer "In2.Cu") (net 409))
  (segment (start 231.711372 101.744996) (end 232.205004 102.238628) (width 0.13) (layer "In2.Cu") (net 409))
  (arc (start 191.668215 100.612989) (mid 191.850372 100.576756) (end 192.004798 100.473572) (width 0.082) (layer "In2.Cu") (net 409))
  (arc (start 246.007632 118.522) (mid 246.151521 118.550621) (end 246.273504 118.632128) (width 0.13) (layer "In2.Cu") (net 409))
  (arc (start 191.206481 100.939407) (mid 191.229317 100.824602) (end 191.294349 100.727275) (width 0.082) (layer "In2.Cu") (net 409))
  (arc (start 233.705004 104.488628) (mid 233.851542 104.707938) (end 233.903 104.966632) (width 0.13) (layer "In2.Cu") (net 409))
  (arc (start 192.232508 103.472258) (mid 192.14412 103.50887) (end 192.107508 103.597258) (width 0.082) (layer "In2.Cu") (net 409))
  (arc (start 206.670186 103.656331) (mid 206.861528 103.618271) (end 207.02374 103.509884) (width 0.13) (layer "In2.Cu") (net 409))
  (arc (start 191.352928 103.456304) (mid 191.244541 103.294092) (end 191.206481 103.10275) (width 0.082) (layer "In2.Cu") (net 409))
  (arc (start 237.403 113.079517) (mid 237.44106 113.270859) (end 237.549447 113.433071) (width 0.13) (layer "In2.Cu") (net 409))
  (arc (start 246.822045 120.149711) (mid 246.854487 120.171388) (end 246.892755 120.179) (width 0.13) (layer "In2.Cu") (net 409))
  (arc (start 192.086583 100.391787) (mid 192.189767 100.237361) (end 192.226 100.055204) (width 0.082) (layer "In2.Cu") (net 409))
  (arc (start 246.653 119.897823) (mid 246.668224 119.97436) (end 246.711579 120.039245) (width 0.13) (layer "In2.Cu") (net 409))
  (arc (start 241.174447 118.608071) (mid 241.06606 118.445859) (end 241.028 118.254517) (width 0.13) (layer "In2.Cu") (net 409))
  (arc (start 192.357508 103.597258) (mid 192.320896 103.50887) (end 192.232508 103.472258) (width 0.082) (layer "In2.Cu") (net 409))
  (arc (start 192.482508 103.722508) (mid 192.39412 103.685896) (end 192.357508 103.597508) (width 0.082) (layer "In2.Cu") (net 409))
  (arc (start 235.653 109.979517) (mid 235.69106 110.170859) (end 235.799447 110.333071) (width 0.13) (layer "In2.Cu") (net 409))
  (arc (start 232.205004 102.238628) (mid 232.351542 102.457938) (end 232.403 102.716632) (width 0.13) (layer "In2.Cu") (net 409))
  (arc (start 244.213628 118.719996) (mid 244.432938 118.573458) (end 244.691632 118.522) (width 0.13) (layer "In2.Cu") (net 409))
  (arc (start 192.107508 103.597508) (mid 192.070896 103.685896) (end 191.982508 103.722508) (width 0.082) (layer "In2.Cu") (net 409))
  (arc (start 246.923157 120.179) (mid 246.999678 120.163792) (end 247.064545 120.120455) (width 0.13) (layer "In2.Cu") (net 409))
  (arc (start 233.903 105.979517) (mid 233.94106 106.170859) (end 234.049447 106.333071) (width 0.13) (layer "In2.Cu") (net 409))
  (arc (start 192.264853 96.085147) (mid 192.303784 96.059134) (end 192.349706 96.05) (width 0.082) (layer "In2.Cu") (net 409))
  (arc (start 231.233368 101.547) (mid 231.492062 101.598458) (end 231.711372 101.744996) (width 0.13) (layer "In2.Cu") (net 409))
  (arc (start 241.99193 119.425554) (mid 242.154142 119.53394) (end 242.345483 119.572) (width 0.13) (layer "In2.Cu") (net 409))
  (arc (start 208.788628 101.744996) (mid 209.007938 101.598457) (end 209.266632 101.547) (width 0.13) (layer "In2.Cu") (net 409))
  (arc (start 235.455297 107.738921) (mid 235.601619 107.957907) (end 235.653 108.216218) (width 0.13) (layer "In2.Cu") (net 409))
  (arc (start 232.403 102.979517) (mid 232.44106 103.170859) (end 232.549447 103.333071) (width 0.13) (layer "In2.Cu") (net 409))
  (arc (start 191.320767 100.700857) (mid 191.418094 100.635825) (end 191.532899 100.612989) (width 0.082) (layer "In2.Cu") (net 409))
  (arc (start 237.205297 111.738921) (mid 237.351619 111.957907) (end 237.403 112.216218) (width 0.13) (layer "In2.Cu") (net 409))
  (arc (start 243.154517 119.572) (mid 243.345858 119.53394) (end 243.50807 119.425554) (width 0.13) (layer "In2.Cu") (net 409))
  (arc (start 191.826239 103.722508) (mid 191.634898 103.684448) (end 191.472686 103.576062) (width 0.082) (layer "In2.Cu") (net 409))
  (arc (start 240.830004 116.713628) (mid 240.976542 116.932938) (end 241.028 117.191632) (width 0.13) (layer "In2.Cu") (net 409))
  (arc (start 192.226 96.173706) (mid 192.235134 96.127784) (end 192.261147 96.088853) (width 0.082) (layer "In2.Cu") (net 409))
  (arc (start 198.128173 103.663929) (mid 198.063288 103.707284) (end 197.986751 103.722508) (width 0.082) (layer "In2.Cu") (net 409))
  (arc (start 246.542872 118.901496) (mid 246.624379 119.023479) (end 246.653 119.167368) (width 0.13) (layer "In2.Cu") (net 409))
  (segment (start 253.69 119.86) (end 253.362789 120.187211) (width 0.122) (layer "F.Cu") (net 410))
  (segment (start 253.310079 123.0015) (end 253.083327 123.0015) (width 0.122) (layer "F.Cu") (net 410))
  (segment (start 252.895943 122.923883) (end 252.809116 122.837056) (width 0.122) (layer "F.Cu") (net 410))
  (segment (start 253.54 123.19) (end 253.380789 123.030789) (width 0.122) (layer "F.Cu") (net 410))
  (segment (start 252.7315 120.675327) (end 252.7315 122.649673) (width 0.122) (layer "F.Cu") (net 410))
  (segment (start 253.002943 120.294117) (end 252.809116 120.487944) (width 0.122) (layer "F.Cu") (net 410))
  (segment (start 253.292079 120.2165) (end 253.190327 120.2165) (width 0.122) (layer "F.Cu") (net 410))
  (via (at 253.54 123.19) (size 0.5) (drill 0.2) (layers "F.Cu" "B.Cu") (net 410))
  (arc (start 253.190327 120.2165) (mid 253.088916 120.236672) (end 253.002943 120.294117) (width 0.122) (layer "F.Cu") (net 410))
  (arc (start 252.7315 120.675327) (mid 252.751672 120.573916) (end 252.809116 120.487944) (width 0.122) (layer "F.Cu") (net 410))
  (arc (start 253.083327 123.0015) (mid 252.981916 122.981328) (end 252.895943 122.923883) (width 0.122) (layer "F.Cu") (net 410))
  (arc (start 253.380789 123.030789) (mid 253.348347 123.009112) (end 253.310079 123.0015) (width 0.122) (layer "F.Cu") (net 410))
  (arc (start 253.362789 120.187211) (mid 253.330347 120.208888) (end 253.292079 120.2165) (width 0.122) (layer "F.Cu") (net 410))
  (arc (start 252.7315 122.649673) (mid 252.751672 122.751084) (end 252.809116 122.837056) (width 0.122) (layer "F.Cu") (net 410))
  (segment (start 254.175 123.131421) (end 254.175 123.495) (width 0.122) (layer "B.Cu") (net 410))
  (segment (start 253.54 123.19) (end 253.669922 123.060078) (width 0.122) (layer "B.Cu") (net 410))
  (segment (start 254.145079 123.060079) (end 254.145711 123.060711) (width 0.122) (layer "B.Cu") (net 410))
  (segment (start 253.811343 123.0015) (end 254.003657 123.0015) (width 0.122) (layer "B.Cu") (net 410))
  (arc (start 253.811343 123.0015) (mid 253.734807 123.016724) (end 253.669922 123.060078) (width 0.122) (layer "B.Cu") (net 410))
  (arc (start 254.175 123.131421) (mid 254.167388 123.093153) (end 254.145711 123.060711) (width 0.122) (layer "B.Cu") (net 410))
  (arc (start 254.003657 123.0015) (mid 254.080194 123.016724) (end 254.145079 123.060079) (width 0.122) (layer "B.Cu") (net 410))
  (segment (start 255.3065 120.024139) (end 255.3065 118.8835) (width 0.122) (layer "F.Cu") (net 411))
  (segment (start 255.18485 120.18721) (end 255.277211 120.094849) (width 0.122) (layer "F.Cu") (net 411))
  (segment (start 193.596978 102.986346) (end 194.474996 103.864364) (width 0.1) (layer "F.Cu") (net 411))
  (segment (start 248.9565 108.133988) (end 248.9565 105.016547) (width 0.122) (layer "F.Cu") (net 411))
  (segment (start 238.811346 98.8935) (end 207.116547 98.8935) (width 0.122) (layer "F.Cu") (net 411))
  (segment (start 247.783453 103.8435) (end 244.451012 103.8435) (width 0.122) (layer "F.Cu") (net 411))
  (segment (start 255.057921 120.2165) (end 255.114139 120.2165) (width 0.122) (layer "F.Cu") (net 411))
  (segment (start 254.370086 112.930133) (end 253.752645 112.930133) (width 0.122) (layer "F.Cu") (net 411))
  (segment (start 198.139003 103.949303) (end 198.1632 103.9735) (width 0.1) (layer "F.Cu") (net 411))
  (segment (start 194.609346 103.920013) (end 198.068292 103.920013) (width 0.1) (layer "F.Cu") (net 411))
  (segment (start 253.282419 112.735359) (end 249.151274 108.604214) (width 0.122) (layer "F.Cu") (net 411))
  (segment (start 255.0065 118.5835) (end 255.0065 118.5335) (width 0.122) (layer "F.Cu") (net 411))
  (segment (start 248.810053 104.662993) (end 248.137006 103.989946) (width 0.122) (layer "F.Cu") (net 411))
  (segment (start 255.3065 117.4635) (end 255.3065 113.866547) (width 0.122) (layer "F.Cu") (net 411))
  (segment (start 206.762993 99.039947) (end 202.053504 103.749436) (width 0.122) (layer "F.Cu") (net 411))
  (segment (start 255.160053 113.512993) (end 254.723639 113.076579) (width 0.122) (layer "F.Cu") (net 411))
  (segment (start 255.3065 118.2335) (end 255.3065 118.1835) (width 0.122) (layer "F.Cu") (net 411))
  (segment (start 193.445282 102.589298) (end 193.512039 102.656055) (width 0.1) (layer "F.Cu") (net 411))
  (segment (start 255.1565 117.9135) (end 255.151539 117.9135) (width 0.122) (layer "F.Cu") (net 411))
  (segment (start 201.512567 103.9735) (end 198.1632 103.9735) (width 0.122) (layer "F.Cu") (net 411))
  (segment (start 243.980786 103.648726) (end 239.518453 99.186393) (width 0.122) (layer "F.Cu") (net 411))
  (segment (start 193.136328 102.560008) (end 193.374571 102.560008) (width 0.1) (layer "F.Cu") (net 411))
  (segment (start 255.151539 117.6135) (end 255.1565 117.6135) (width 0.122) (layer "F.Cu") (net 411))
  (segment (start 255.3065 118.1835) (end 255.3065 118.0635) (width 0.122) (layer "F.Cu") (net 411))
  (segment (start 193.541328 102.726765) (end 193.541328 102.851995) (width 0.1) (layer "F.Cu") (net 411))
  (segment (start 254.66 119.86) (end 254.987211 120.187211) (width 0.122) (layer "F.Cu") (net 411))
  (arc (start 255.114139 120.2165) (mid 255.152408 120.208888) (end 255.18485 120.18721) (width 0.122) (layer "F.Cu") (net 411))
  (arc (start 198.139003 103.949303) (mid 198.106561 103.927625) (end 198.068292 103.920013) (width 0.1) (layer "F.Cu") (net 411))
  (arc (start 207.116547 98.8935) (mid 206.925205 98.93156) (end 206.762993 99.039947) (width 0.122) (layer "F.Cu") (net 411))
  (arc (start 239.518453 99.186393) (mid 239.194029 98.96962) (end 238.811346 98.8935) (width 0.122) (layer "F.Cu") (net 411))
  (arc (start 255.3065 118.8835) (mid 255.262566 118.777434) (end 255.1565 118.7335) (width 0.122) (layer "F.Cu") (net 411))
  (arc (start 253.752645 112.930133) (mid 253.498161 112.879513) (end 253.282419 112.735359) (width 0.122) (layer "F.Cu") (net 411))
  (arc (start 255.277211 120.094849) (mid 255.298888 120.062407) (end 255.3065 120.024139) (width 0.122) (layer "F.Cu") (net 411))
  (arc (start 255.1565 118.7335) (mid 255.050434 118.689566) (end 255.0065 118.5835) (width 0.122) (layer "F.Cu") (net 411))
  (arc (start 193.596978 102.986346) (mid 193.555791 102.924705) (end 193.541328 102.851995) (width 0.1) (layer "F.Cu") (net 411))
  (arc (start 255.1565 117.6135) (mid 255.262566 117.569566) (end 255.3065 117.4635) (width 0.122) (layer "F.Cu") (net 411))
  (arc (start 255.0065 118.5335) (mid 255.050434 118.427434) (end 255.1565 118.3835) (width 0.122) (layer "F.Cu") (net 411))
  (arc (start 248.9565 105.016547) (mid 248.91844 104.825205) (end 248.810053 104.662993) (width 0.122) (layer "F.Cu") (net 411))
  (arc (start 194.474996 103.864364) (mid 194.536636 103.905551) (end 194.609346 103.920013) (width 0.1) (layer "F.Cu") (net 411))
  (arc (start 249.151274 108.604214) (mid 249.00712 108.388472) (end 248.9565 108.133988) (width 0.122) (layer "F.Cu") (net 411))
  (arc (start 248.137006 103.989946) (mid 247.974794 103.88156) (end 247.783453 103.8435) (width 0.122) (layer "F.Cu") (net 411))
  (arc (start 202.053504 103.749436) (mid 201.80532 103.915268) (end 201.512567 103.9735) (width 0.122) (layer "F.Cu") (net 411))
  (arc (start 193.445282 102.589298) (mid 193.41284 102.56762) (end 193.374571 102.560008) (width 0.1) (layer "F.Cu") (net 411))
  (arc (start 255.151539 117.9135) (mid 255.045473 117.869566) (end 255.001539 117.7635) (width 0.122) (layer "F.Cu") (net 411))
  (arc (start 255.3065 113.866547) (mid 255.26844 113.675205) (end 255.160053 113.512993) (width 0.122) (layer "F.Cu") (net 411))
  (arc (start 244.451012 103.8435) (mid 244.196528 103.79288) (end 243.980786 103.648726) (width 0.122) (layer "F.Cu") (net 411))
  (arc (start 255.3065 118.0635) (mid 255.262566 117.957434) (end 255.1565 117.9135) (width 0.122) (layer "F.Cu") (net 411))
  (arc (start 254.723639 113.076579) (mid 254.561427 112.968193) (end 254.370086 112.930133) (width 0.122) (layer "F.Cu") (net 411))
  (arc (start 255.1565 118.3835) (mid 255.262566 118.339566) (end 255.3065 118.2335) (width 0.122) (layer "F.Cu") (net 411))
  (arc (start 193.512039 102.656055) (mid 193.533716 102.688497) (end 193.541328 102.726765) (width 0.1) (layer "F.Cu") (net 411))
  (arc (start 254.987211 120.187211) (mid 255.019653 120.208888) (end 255.057921 120.2165) (width 0.122) (layer "F.Cu") (net 411))
  (arc (start 255.001539 117.7635) (mid 255.045473 117.657434) (end 255.151539 117.6135) (width 0.122) (layer "F.Cu") (net 411))
  (segment (start 253.292079 120.5035) (end 253.240861 120.5035) (width 0.122) (layer "F.Cu") (net 412))
  (segment (start 253.0185 120.725861) (end 253.0185 121.3565) (width 0.122) (layer "F.Cu") (net 412))
  (segment (start 253.69 120.86) (end 253.362789 120.532789) (width 0.122) (layer "F.Cu") (net 412))
  (segment (start 253.047789 122.669849) (end 253.06315 122.68521) (width 0.122) (layer "F.Cu") (net 412))
  (segment (start 253.17015 120.53279) (end 253.047789 120.655151) (width 0.122) (layer "F.Cu") (net 412))
  (segment (start 253.465268 121.8065) (end 253.1685 121.8065) (width 0.122) (layer "F.Cu") (net 412))
  (segment (start 253.0185 122.0065) (end 253.0185 122.599139) (width 0.122) (layer "F.Cu") (net 412))
  (segment (start 253.0185 121.9565) (end 253.0185 122.0065) (width 0.122) (layer "F.Cu") (net 412))
  (segment (start 253.1685 121.5065) (end 253.465268 121.5065) (width 0.122) (layer "F.Cu") (net 412))
  (segment (start 253.380789 122.685211) (end 253.54 122.526) (width 0.122) (layer "F.Cu") (net 412))
  (segment (start 253.133861 122.7145) (end 253.310079 122.7145) (width 0.122) (layer "F.Cu") (net 412))
  (via (at 253.54 122.526) (size 0.5) (drill 0.2) (layers "F.Cu" "B.Cu") (net 412))
  (arc (start 253.615268 121.6565) (mid 253.571334 121.762566) (end 253.465268 121.8065) (width 0.122) (layer "F.Cu") (net 412))
  (arc (start 253.0185 122.599139) (mid 253.026112 122.637407) (end 253.047789 122.669849) (width 0.122) (layer "F.Cu") (net 412))
  (arc (start 253.1685 121.8065) (mid 253.062434 121.850434) (end 253.0185 121.9565) (width 0.122) (layer "F.Cu") (net 412))
  (arc (start 253.0185 121.3565) (mid 253.062434 121.462566) (end 253.1685 121.5065) (width 0.122) (layer "F.Cu") (net 412))
  (arc (start 253.465268 121.5065) (mid 253.571334 121.550434) (end 253.615268 121.6565) (width 0.122) (layer "F.Cu") (net 412))
  (arc (start 253.06315 122.68521) (mid 253.095592 122.706888) (end 253.133861 122.7145) (width 0.122) (layer "F.Cu") (net 412))
  (arc (start 253.362789 120.532789) (mid 253.330347 120.511112) (end 253.292079 120.5035) (width 0.122) (layer "F.Cu") (net 412))
  (arc (start 253.240861 120.5035) (mid 253.202592 120.511112) (end 253.17015 120.53279) (width 0.122) (layer "F.Cu") (net 412))
  (arc (start 253.310079 122.7145) (mid 253.348347 122.706888) (end 253.380789 122.685211) (width 0.122) (layer "F.Cu") (net 412))
  (arc (start 253.047789 120.655151) (mid 253.026112 120.687593) (end 253.0185 120.725861) (width 0.122) (layer "F.Cu") (net 412))
  (segment (start 253.54 122.526) (end 253.669922 122.655922) (width 0.122) (layer "B.Cu") (net 412))
  (segment (start 254.129079 122.655921) (end 254.145711 122.639289) (width 0.122) (layer "B.Cu") (net 412))
  (segment (start 254.175 122.568579) (end 254.175 122.225) (width 0.122) (layer "B.Cu") (net 412))
  (segment (start 253.811343 122.7145) (end 253.987657 122.7145) (width 0.122) (layer "B.Cu") (net 412))
  (arc (start 254.145711 122.639289) (mid 254.167388 122.606847) (end 254.175 122.568579) (width 0.122) (layer "B.Cu") (net 412))
  (arc (start 253.811343 122.7145) (mid 253.734807 122.699276) (end 253.669922 122.655922) (width 0.122) (layer "B.Cu") (net 412))
  (arc (start 253.987657 122.7145) (mid 254.064194 122.699276) (end 254.129079 122.655921) (width 0.122) (layer "B.Cu") (net 412))
  (segment (start 178.136328 102.560008) (end 177.636328 103.060008) (width 0.1) (layer "F.Cu") (net 416))
  (via blind (at 177.636328 103.060008) (size 0.5) (drill 0.2) (layers "F.Cu" "In5.Cu") (net 416))
  (via (at 248.46 102.206) (size 0.5) (drill 0.2) (layers "F.Cu" "B.Cu") (net 416))
  (segment (start 177.986327 103.111327) (end 177.986327 104.223461) (width 0.1) (layer "In5.Cu") (net 416))
  (segment (start 243.687866 103.25) (end 244.937866 103.25) (width 0.1) (layer "In5.Cu") (net 416))
  (segment (start 244.937866 103.25) (end 245.387866 103.7) (width 0.1) (layer "In5.Cu") (net 416))
  (segment (start 211.037134 101.675) (end 234.212866 101.675) (width 0.1) (layer "In5.Cu") (net 416))
  (segment (start 249.35 102.737866) (end 249.000133 102.387999) (width 0.1) (layer "In5.Cu") (net 416))
  (segment (start 177.935008 103.060008) (end 177.986327 103.111327) (width 0.1) (layer "In5.Cu") (net 416))
  (segment (start 177.986327 104.223461) (end 182.812866 109.05) (width 0.1) (layer "In5.Cu") (net 416))
  (segment (start 234.212866 101.675) (end 234.937866 102.4) (width 0.1) (layer "In5.Cu") (net 416))
  (segment (start 249.35 103.212134) (end 249.35 102.737866) (width 0.1) (layer "In5.Cu") (net 416))
  (segment (start 248.641999 102.387999) (end 248.46 102.206) (width 0.1) (layer "In5.Cu") (net 416))
  (segment (start 245.387866 103.7) (end 248.862134 103.7) (width 0.1) (layer "In5.Cu") (net 416))
  (segment (start 248.862134 103.7) (end 249.35 103.212134) (width 0.1) (layer "In5.Cu") (net 416))
  (segment (start 242.837866 102.4) (end 243.687866 103.25) (width 0.1) (layer "In5.Cu") (net 416))
  (segment (start 203.662134 109.05) (end 211.037134 101.675) (width 0.1) (layer "In5.Cu") (net 416))
  (segment (start 234.937866 102.4) (end 242.837866 102.4) (width 0.1) (layer "In5.Cu") (net 416))
  (segment (start 249.000133 102.387999) (end 248.641999 102.387999) (width 0.1) (layer "In5.Cu") (net 416))
  (segment (start 182.812866 109.05) (end 203.662134 109.05) (width 0.1) (layer "In5.Cu") (net 416))
  (segment (start 177.636328 103.060008) (end 177.935008 103.060008) (width 0.1) (layer "In5.Cu") (net 416))
  (segment (start 248.641999 102.387999) (end 248.992001 102.387999) (width 0.1) (layer "B.Cu") (net 416))
  (segment (start 248.46 102.206) (end 248.641999 102.387999) (width 0.1) (layer "B.Cu") (net 416))
  (segment (start 249.095 102.285) (end 249.095 101.905) (width 0.1) (layer "B.Cu") (net 416))
  (segment (start 248.992001 102.387999) (end 249.095 102.285) (width 0.1) (layer "B.Cu") (net 416))
  (segment (start 181.136328 101.560008) (end 180.636328 102.060008) (width 0.1) (layer "F.Cu") (net 417))
  (via blind (at 180.636328 102.060008) (size 0.5) (drill 0.2) (layers "F.Cu" "In5.Cu") (net 417))
  (via (at 248.46 98.396) (size 0.5) (drill 0.2) (layers "F.Cu" "B.Cu") (net 417))
  (segment (start 244.517847 99.779981) (end 246.218226 99.779981) (width 0.1) (layer "In5.Cu") (net 417))
  (segment (start 183.361396 105.631066) (end 183.64424 105.348223) (width 0.1) (layer "In5.Cu") (net 417))
  (segment (start 209.062134 99.4) (end 236.75 99.4) (width 0.1) (layer "In5.Cu") (net 417))
  (segment (start 238.55 99.647909) (end 238.55 98.852091) (width 0.1) (layer "In5.Cu") (net 417))
  (segment (start 248.641999 98.577999) (end 248.46 98.396) (width 0.1) (layer "In5.Cu") (net 417))
  (segment (start 237.547909 98.852091) (end 237.547909 99.25) (width 0.1) (layer "In5.Cu") (net 417))
  (segment (start 237.55 99.25) (end 237.55 99.647909) (width 0.1) (layer "In5.Cu") (net 417))
  (segment (start 182.7 104) (end 182.9 104) (width 0.1) (layer "In5.Cu") (net 417))
  (segment (start 237.147909 99.002091) (end 237.147909 98.852091) (width 0.1) (layer "In5.Cu") (net 417))
  (segment (start 246.448208 99.55) (end 247.437866 99.55) (width 0.1) (layer "In5.Cu") (net 417))
  (segment (start 183.679593 106.691726) (end 184.037866 107.05) (width 0.1) (layer "In5.Cu") (net 417))
  (segment (start 247.737866 99.85) (end 248.912134 99.85) (width 0.1) (layer "In5.Cu") (net 417))
  (segment (start 237.947909 100.045818) (end 238.152091 100.045818) (width 0.1) (layer "In5.Cu") (net 417))
  (segment (start 246.218226 99.779981) (end 246.448208 99.55) (width 0.1) (layer "In5.Cu") (net 417))
  (segment (start 182.9 104.4) (end 182.7 104.4) (width 0.1) (layer "In5.Cu") (net 417))
  (segment (start 182.2 105.212134) (end 182.618932 105.631065) (width 0.1) (layer "In5.Cu") (net 417))
  (segment (start 180.636328 101.788672) (end 180.714991 101.710009) (width 0.1) (layer "In5.Cu") (net 417))
  (segment (start 249.3 98.887866) (end 248.990133 98.577999) (width 0.1) (layer "In5.Cu") (net 417))
  (segment (start 248.990133 98.577999) (end 248.641999 98.577999) (width 0.1) (layer "In5.Cu") (net 417))
  (segment (start 183.361398 105.631067) (end 183.361396 105.631066) (width 0.1) (layer "In5.Cu") (net 417))
  (segment (start 249.3 99.462134) (end 249.3 98.887866) (width 0.1) (layer "In5.Cu") (net 417))
  (segment (start 247.437866 99.55) (end 247.737866 99.85) (width 0.1) (layer "In5.Cu") (net 417))
  (segment (start 180.714991 101.710009) (end 180.922875 101.710009) (width 0.1) (layer "In5.Cu") (net 417))
  (segment (start 180.636328 102.060008) (end 180.636328 101.788672) (width 0.1) (layer "In5.Cu") (net 417))
  (segment (start 237.245818 98.754182) (end 237.45 98.754182) (width 0.1) (layer "In5.Cu") (net 417))
  (segment (start 182.2 104.9) (end 182.2 105.212134) (width 0.1) (layer "In5.Cu") (net 417))
  (segment (start 183.962435 105.666419) (end 183.962436 105.666418) (width 0.1) (layer "In5.Cu") (net 417))
  (segment (start 183.962436 105.348223) (end 183.962436 105.348222) (width 0.1) (layer "In5.Cu") (net 417))
  (segment (start 201.412134 107.05) (end 209.062134 99.4) (width 0.1) (layer "In5.Cu") (net 417))
  (segment (start 244.137866 99.4) (end 244.517847 99.779981) (width 0.1) (layer "In5.Cu") (net 417))
  (segment (start 238.95 98.852091) (end 238.95 99.002091) (width 0.1) (layer "In5.Cu") (net 417))
  (segment (start 180.922875 101.710009) (end 182.2 102.987134) (width 0.1) (layer "In5.Cu") (net 417))
  (segment (start 238.647909 98.754182) (end 238.852091 98.754182) (width 0.1) (layer "In5.Cu") (net 417))
  (segment (start 248.912134 99.85) (end 249.3 99.462134) (width 0.1) (layer "In5.Cu") (net 417))
  (segment (start 239.347909 99.4) (end 244.137866 99.4) (width 0.1) (layer "In5.Cu") (net 417))
  (segment (start 184.037866 107.05) (end 201.412134 107.05) (width 0.1) (layer "In5.Cu") (net 417))
  (segment (start 182.2 102.987134) (end 182.2 103.5) (width 0.1) (layer "In5.Cu") (net 417))
  (segment (start 183.962436 105.666418) (end 183.679593 105.949262) (width 0.1) (layer "In5.Cu") (net 417))
  (segment (start 237.547909 99.25) (end 237.55 99.25) (width 0.1) (layer "In5.Cu") (net 417))
  (arc (start 183.962436 105.348222) (mid 184.028337 105.507322) (end 183.962435 105.666419) (width 0.1) (layer "In5.Cu") (net 417))
  (arc (start 237.55 99.647909) (mid 237.666545 99.929273) (end 237.947909 100.045818) (width 0.1) (layer "In5.Cu") (net 417))
  (arc (start 238.55 98.852091) (mid 238.578677 98.782859) (end 238.647909 98.754182) (width 0.1) (layer "In5.Cu") (net 417))
  (arc (start 237.45 98.754182) (mid 237.519232 98.782859) (end 237.547909 98.852091) (width 0.1) (layer "In5.Cu") (net 417))
  (arc (start 182.2 103.5) (mid 182.346447 103.853553) (end 182.7 104) (width 0.1) (layer "In5.Cu") (net 417))
  (arc (start 182.7 104.4) (mid 182.346447 104.546447) (end 182.2 104.9) (width 0.1) (layer "In5.Cu") (net 417))
  (arc (start 238.152091 100.045818) (mid 238.433455 99.929273) (end 238.55 99.647909) (width 0.1) (layer "In5.Cu") (net 417))
  (arc (start 182.9 104) (mid 183.041421 104.058579) (end 183.1 104.2) (width 0.1) (layer "In5.Cu") (net 417))
  (arc (start 182.618932 105.631065) (mid 182.990165 105.784835) (end 183.361398 105.631067) (width 0.1) (layer "In5.Cu") (net 417))
  (arc (start 183.64424 105.348223) (mid 183.803337 105.282321) (end 183.962436 105.348223) (width 0.1) (layer "In5.Cu") (net 417))
  (arc (start 183.1 104.2) (mid 183.041421 104.341421) (end 182.9 104.4) (width 0.1) (layer "In5.Cu") (net 417))
  (arc (start 236.75 99.4) (mid 237.031364 99.283455) (end 237.147909 99.002091) (width 0.1) (layer "In5.Cu") (net 417))
  (arc (start 238.95 99.002091) (mid 239.066545 99.283455) (end 239.347909 99.4) (width 0.1) (layer "In5.Cu") (net 417))
  (arc (start 238.852091 98.754182) (mid 238.921323 98.782859) (end 238.95 98.852091) (width 0.1) (layer "In5.Cu") (net 417))
  (arc (start 183.679593 105.949262) (mid 183.525823 106.320493) (end 183.679593 106.691726) (width 0.1) (layer "In5.Cu") (net 417))
  (arc (start 237.147909 98.852091) (mid 237.176586 98.782859) (end 237.245818 98.754182) (width 0.1) (layer "In5.Cu") (net 417))
  (segment (start 248.992001 98.577999) (end 249.095 98.475) (width 0.1) (layer "B.Cu") (net 417))
  (segment (start 248.641999 98.577999) (end 248.992001 98.577999) (width 0.1) (layer "B.Cu") (net 417))
  (segment (start 248.46 98.396) (end 248.641999 98.577999) (width 0.1) (layer "B.Cu") (net 417))
  (segment (start 249.095 98.475) (end 249.095 98.095) (width 0.1) (layer "B.Cu") (net 417))
  (segment (start 201.503453 103.6865) (end 198.1632 103.6865) (width 0.122) (layer "F.Cu") (net 418))
  (segment (start 194.219825 103.200945) (end 194.219825 103.200946) (width 0.1) (layer "F.Cu") (net 418))
  (segment (start 193.760617 102.643399) (end 193.814718 102.589298) (width 0.1) (layer "F.Cu") (net 418))
  (segment (start 194.35158 103.337893) (end 194.354176 103.335296) (width 0.1) (layer "F.Cu") (net 418))
  (segment (start 194.351579 103.337893) (end 194.35158 103.337893) (width 0.1) (layer "F.Cu") (net 418))
  (segment (start 254.420621 112.643133) (end 253.80318 112.643133) (width 0.122) (layer "F.Cu") (net 418))
  (segment (start 255.5935 120.074673) (end 255.5935 113.816012) (width 0.122) (layer "F.Cu") (net 418))
  (segment (start 238.861881 98.6065) (end 207.066012 98.6065) (width 0.122) (layer "F.Cu") (net 418))
  (segment (start 198.078266 103.730013) (end 194.65077 103.730013) (width 0.1) (layer "F.Cu") (net 418))
  (segment (start 249.048726 104.495786) (end 248.304214 103.751274) (width 0.122) (layer "F.Cu") (net 418))
  (segment (start 194.082879 103.203543) (end 193.760618 102.881282) (width 0.1) (layer "F.Cu") (net 418))
  (segment (start 255.352057 120.425883) (end 255.515884 120.262056) (width 0.122) (layer "F.Cu") (net 418))
  (segment (start 193.731328 102.810571) (end 193.731328 102.714109) (width 0.1) (layer "F.Cu") (net 418))
  (segment (start 194.219825 103.200946) (end 194.217228 103.203542) (width 0.1) (layer "F.Cu") (net 418))
  (segment (start 255.398726 113.345786) (end 254.890847 112.837907) (width 0.122) (layer "F.Cu") (net 418))
  (segment (start 206.595786 98.801274) (end 201.857007 103.540053) (width 0.122) (layer "F.Cu") (net 418))
  (segment (start 198.1632 103.6865) (end 198.148977 103.700723) (width 0.1) (layer "F.Cu") (net 418))
  (segment (start 247.833988 103.5565) (end 244.501547 103.5565) (width 0.122) (layer "F.Cu") (net 418))
  (segment (start 244.147993 103.410053) (end 239.685661 98.947721) (width 0.122) (layer "F.Cu") (net 418))
  (segment (start 255.057921 120.5035) (end 255.164673 120.5035) (width 0.122) (layer "F.Cu") (net 418))
  (segment (start 194.58006 103.700724) (end 194.35158 103.472244) (width 0.1) (layer "F.Cu") (net 418))
  (segment (start 194.082878 103.203542) (end 194.082879 103.203543) (width 0.1) (layer "F.Cu") (net 418))
  (segment (start 249.2435 108.083453) (end 249.2435 104.966012) (width 0.122) (layer "F.Cu") (net 418))
  (segment (start 193.885429 102.560008) (end 194.136328 102.560008) (width 0.1) (layer "F.Cu") (net 418))
  (segment (start 253.449626 112.496686) (end 249.389946 108.437006) (width 0.122) (layer "F.Cu") (net 418))
  (segment (start 254.66 120.86) (end 254.987211 120.532789) (width 0.122) (layer "F.Cu") (net 418))
  (arc (start 194.65077 103.730013) (mid 194.612502 103.722401) (end 194.58006 103.700724) (width 0.1) (layer "F.Cu") (net 418))
  (arc (start 198.148977 103.700723) (mid 198.116535 103.722401) (end 198.078266 103.730013) (width 0.1) (layer "F.Cu") (net 418))
  (arc (start 194.354176 103.200946) (mid 194.287001 103.17312) (end 194.219825 103.200945) (width 0.1) (layer "F.Cu") (net 418))
  (arc (start 193.731328 102.714109) (mid 193.73894 102.675841) (end 193.760617 102.643399) (width 0.1) (layer "F.Cu") (net 418))
  (arc (start 207.066012 98.6065) (mid 206.811528 98.65712) (end 206.595786 98.801274) (width 0.122) (layer "F.Cu") (net 418))
  (arc (start 201.857007 103.540053) (mid 201.694795 103.64844) (end 201.503453 103.6865) (width 0.122) (layer "F.Cu") (net 418))
  (arc (start 194.35158 103.472244) (mid 194.323754 103.405069) (end 194.351579 103.337893) (width 0.1) (layer "F.Cu") (net 418))
  (arc (start 248.304214 103.751274) (mid 248.088472 103.60712) (end 247.833988 103.5565) (width 0.122) (layer "F.Cu") (net 418))
  (arc (start 194.217228 103.203542) (mid 194.150053 103.231367) (end 194.082878 103.203542) (width 0.1) (layer "F.Cu") (net 418))
  (arc (start 249.2435 108.083453) (mid 249.28156 108.274794) (end 249.389946 108.437006) (width 0.122) (layer "F.Cu") (net 418))
  (arc (start 239.685661 98.947721) (mid 239.307708 98.69518) (end 238.861881 98.6065) (width 0.122) (layer "F.Cu") (net 418))
  (arc (start 244.501547 103.5565) (mid 244.310205 103.51844) (end 244.147993 103.410053) (width 0.122) (layer "F.Cu") (net 418))
  (arc (start 253.80318 112.643133) (mid 253.611838 112.605073) (end 253.449626 112.496686) (width 0.122) (layer "F.Cu") (net 418))
  (arc (start 255.5935 120.074673) (mid 255.573328 120.176084) (end 255.515884 120.262056) (width 0.122) (layer "F.Cu") (net 418))
  (arc (start 249.048726 104.495786) (mid 249.19288 104.711528) (end 249.2435 104.966012) (width 0.122) (layer "F.Cu") (net 418))
  (arc (start 255.5935 113.816012) (mid 255.54288 113.561528) (end 255.398726 113.345786) (width 0.122) (layer "F.Cu") (net 418))
  (arc (start 254.420621 112.643133) (mid 254.675105 112.693753) (end 254.890847 112.837907) (width 0.122) (layer "F.Cu") (net 418))
  (arc (start 194.354176 103.335296) (mid 194.382001 103.268121) (end 194.354176 103.200946) (width 0.1) (layer "F.Cu") (net 418))
  (arc (start 193.814718 102.589298) (mid 193.84716 102.56762) (end 193.885429 102.560008) (width 0.1) (layer "F.Cu") (net 418))
  (arc (start 255.057921 120.5035) (mid 255.019653 120.511112) (end 254.987211 120.532789) (width 0.122) (layer "F.Cu") (net 418))
  (arc (start 255.352057 120.425883) (mid 255.266085 120.483328) (end 255.164673 120.5035) (width 0.122) (layer "F.Cu") (net 418))
  (arc (start 193.760618 102.881282) (mid 193.73894 102.84884) (end 193.731328 102.810571) (width 0.1) (layer "F.Cu") (net 418))
  (segment (start 255.195 97.98) (end 255.492922 97.682078) (width 0.122) (layer "F.Cu") (net 419))
  (segment (start 255.634343 97.6235) (end 255.805657 97.6235) (width 0.122) (layer "F.Cu") (net 419))
  (segment (start 255.947079 97.682079) (end 256.08 97.815) (width 0.122) (layer "F.Cu") (net 419))
  (via (at 256.08 97.79) (size 0.5) (drill 0.2) (layers "F.Cu" "B.Cu") (net 419))
  (arc (start 255.492922 97.682078) (mid 255.557807 97.638724) (end 255.634343 97.6235) (width 0.122) (layer "F.Cu") (net 419))
  (arc (start 255.805657 97.6235) (mid 255.882194 97.638724) (end 255.947079 97.682079) (width 0.122) (layer "F.Cu") (net 419))
  (segment (start 256.08 97.79) (end 256.209922 97.660078) (width 0.122) (layer "B.Cu") (net 419))
  (segment (start 256.351343 97.6015) (end 256.543657 97.6015) (width 0.122) (layer "B.Cu") (net 419))
  (segment (start 256.685079 97.660079) (end 256.685711 97.660711) (width 0.122) (layer "B.Cu") (net 419))
  (segment (start 256.715 97.731421) (end 256.715 98.095) (width 0.122) (layer "B.Cu") (net 419))
  (arc (start 256.543657 97.6015) (mid 256.620194 97.616724) (end 256.685079 97.660079) (width 0.122) (layer "B.Cu") (net 419))
  (arc (start 256.351343 97.6015) (mid 256.274807 97.616724) (end 256.209922 97.660078) (width 0.122) (layer "B.Cu") (net 419))
  (arc (start 256.715 97.731421) (mid 256.707388 97.693153) (end 256.685711 97.660711) (width 0.122) (layer "B.Cu") (net 419))
  (segment (start 195.847349 102.158016) (end 198.043095 102.158016) (width 0.1) (layer "F.Cu") (net 420))
  (segment (start 205.382994 97.769946) (end 201.163504 101.989436) (width 0.122) (layer "F.Cu") (net 420))
  (segment (start 254.225 97.955) (end 253.927079 97.657079) (width 0.122) (layer "F.Cu") (net 420))
  (segment (start 195.541328 101.726765) (end 195.541328 101.851995) (width 0.1) (layer "F.Cu") (net 420))
  (segment (start 195.445282 101.589298) (end 195.512039 101.656055) (width 0.1) (layer "F.Cu") (net 420))
  (segment (start 200.622567 102.2135) (end 198.14 102.2135) (width 0.122) (layer "F.Cu") (net 420))
  (segment (start 195.596978 101.986346) (end 195.712999 102.102367) (width 0.1) (layer "F.Cu") (net 420))
  (segment (start 241.441346 97.6235) (end 205.736547 97.6235) (width 0.122) (layer "F.Cu") (net 420))
  (segment (start 252.357993 97.744947) (end 250.169214 99.933726) (width 0.122) (layer "F.Cu") (net 420))
  (segment (start 195.136328 101.560008) (end 195.374571 101.560008) (width 0.1) (layer "F.Cu") (net 420))
  (segment (start 249.698988 100.1285) (end 244.511748 100.1285) (width 0.122) (layer "F.Cu") (net 420))
  (segment (start 252.711547 97.5985) (end 253.785657 97.5985) (width 0.122) (layer "F.Cu") (net 420))
  (segment (start 198.113806 102.187306) (end 198.14 102.2135) (width 0.1) (layer "F.Cu") (net 420))
  (segment (start 244.253654 100.021594) (end 242.148453 97.916393) (width 0.122) (layer "F.Cu") (net 420))
  (arc (start 201.163504 101.989436) (mid 200.91532 102.155268) (end 200.622567 102.2135) (width 0.122) (layer "F.Cu") (net 420))
  (arc (start 250.169214 99.933726) (mid 249.953472 100.07788) (end 249.698988 100.1285) (width 0.122) (layer "F.Cu") (net 420))
  (arc (start 195.596978 101.986346) (mid 195.555791 101.924705) (end 195.541328 101.851995) (width 0.1) (layer "F.Cu") (net 420))
  (arc (start 195.512039 101.656055) (mid 195.533716 101.688497) (end 195.541328 101.726765) (width 0.1) (layer "F.Cu") (net 420))
  (arc (start 195.847349 102.158016) (mid 195.774639 102.143553) (end 195.712999 102.102367) (width 0.1) (layer "F.Cu") (net 420))
  (arc (start 205.736547 97.6235) (mid 205.545206 97.66156) (end 205.382994 97.769946) (width 0.122) (layer "F.Cu") (net 420))
  (arc (start 252.357993 97.744947) (mid 252.520205 97.63656) (end 252.711547 97.5985) (width 0.122) (layer "F.Cu") (net 420))
  (arc (start 198.113806 102.187306) (mid 198.081364 102.165628) (end 198.043095 102.158016) (width 0.1) (layer "F.Cu") (net 420))
  (arc (start 244.511748 100.1285) (mid 244.372069 100.100716) (end 244.253654 100.021594) (width 0.122) (layer "F.Cu") (net 420))
  (arc (start 242.148453 97.916393) (mid 241.82403 97.69962) (end 241.441346 97.6235) (width 0.122) (layer "F.Cu") (net 420))
  (arc (start 195.445282 101.589298) (mid 195.41284 101.56762) (end 195.374571 101.560008) (width 0.1) (layer "F.Cu") (net 420))
  (arc (start 253.927079 97.657079) (mid 253.862194 97.613724) (end 253.785657 97.5985) (width 0.122) (layer "F.Cu") (net 420))
  (segment (start 255.195 96.98) (end 255.492922 97.277922) (width 0.122) (layer "F.Cu") (net 421))
  (segment (start 255.634343 97.3365) (end 255.811657 97.3365) (width 0.122) (layer "F.Cu") (net 421))
  (segment (start 255.953079 97.277921) (end 256.08 97.151) (width 0.122) (layer "F.Cu") (net 421))
  (via (at 256.08 97.126) (size 0.5) (drill 0.2) (layers "F.Cu" "B.Cu") (net 421))
  (arc (start 255.492922 97.277922) (mid 255.557807 97.321276) (end 255.634343 97.3365) (width 0.122) (layer "F.Cu") (net 421))
  (arc (start 255.811657 97.3365) (mid 255.888194 97.321276) (end 255.953079 97.277921) (width 0.122) (layer "F.Cu") (net 421))
  (segment (start 256.715 97.168579) (end 256.715 96.825) (width 0.122) (layer "B.Cu") (net 421))
  (segment (start 256.669079 97.255921) (end 256.685711 97.239289) (width 0.122) (layer "B.Cu") (net 421))
  (segment (start 256.351343 97.3145) (end 256.527657 97.3145) (width 0.122) (layer "B.Cu") (net 421))
  (segment (start 256.08 97.126) (end 256.209922 97.255922) (width 0.122) (layer "B.Cu") (net 421))
  (arc (start 256.351343 97.3145) (mid 256.274807 97.299276) (end 256.209922 97.255922) (width 0.122) (layer "B.Cu") (net 421))
  (arc (start 256.685711 97.239289) (mid 256.707388 97.206847) (end 256.715 97.168579) (width 0.122) (layer "B.Cu") (net 421))
  (arc (start 256.527657 97.3145) (mid 256.604194 97.299276) (end 256.669079 97.255921) (width 0.122) (layer "B.Cu") (net 421))
  (segment (start 180.136328 101.560008) (end 179.636328 102.060008) (width 0.1) (layer "F.Cu") (net 425))
  (via blind (at 179.636328 102.060008) (size 0.5) (drill 0.2) (layers "F.Cu" "In5.Cu") (net 425))
  (via (at 247.19 101.6) (size 0.5) (drill 0.2) (layers "F.Cu" "B.Cu") (net 425))
  (segment (start 248.05 101.112134) (end 248.05 100.637866) (width 0.1) (layer "In5.Cu") (net 425))
  (segment (start 179.975 104.475) (end 179.8 104.475) (width 0.1) (layer "In5.Cu") (net 425))
  (segment (start 180.75 105.05) (end 180.748846 105.051154) (width 0.1) (layer "In5.Cu") (net 425))
  (segment (start 247.19 101.6) (end 247.371999 101.418001) (width 0.1) (layer "In5.Cu") (net 425))
  (segment (start 180.398846 105.147386) (end 180.398846 105.051154) (width 0.1) (layer "In5.Cu") (net 425))
  (segment (start 247.371999 101.418001) (end 247.744133 101.418001) (width 0.1) (layer "In5.Cu") (net 425))
  (segment (start 180.4 105.05) (end 180.4 104.9) (width 0.1) (layer "In5.Cu") (net 425))
  (segment (start 244.117792 100.45) (end 236.3 100.45) (width 0.1) (layer "In5.Cu") (net 425))
  (segment (start 183.462134 107.75) (end 181.7 105.987866) (width 0.1) (layer "In5.Cu") (net 425))
  (segment (start 209.937866 100.1) (end 202.287866 107.75) (width 0.1) (layer "In5.Cu") (net 425))
  (segment (start 244.948227 100.216019) (end 244.351774 100.216019) (width 0.1) (layer "In5.Cu") (net 425))
  (segment (start 180.75 104.9) (end 180.75 105.05) (width 0.1) (layer "In5.Cu") (net 425))
  (segment (start 180.398846 105.051154) (end 180.4 105.05) (width 0.1) (layer "In5.Cu") (net 425))
  (segment (start 180.748846 105.051154) (end 180.748846 105.147386) (width 0.1) (layer "In5.Cu") (net 425))
  (segment (start 247.744133 101.418001) (end 248.05 101.112134) (width 0.1) (layer "In5.Cu") (net 425))
  (segment (start 246.287866 100.45) (end 245.182208 100.45) (width 0.1) (layer "In5.Cu") (net 425))
  (segment (start 180.623846 105.272386) (end 180.523846 105.272386) (width 0.1) (layer "In5.Cu") (net 425))
  (segment (start 179.765 102.455) (end 179.636328 102.326328) (width 0.09) (layer "In5.Cu") (net 425))
  (segment (start 236.3 100.45) (end 235.95 100.1) (width 0.1) (layer "In5.Cu") (net 425))
  (segment (start 181.7 105.987866) (end 181.7 104.95) (width 0.1) (layer "In5.Cu") (net 425))
  (segment (start 181.698182 103.208943) (end 180.944239 102.455) (width 0.09) (layer "In5.Cu") (net 425))
  (segment (start 179.8 104.125) (end 181.225 104.125) (width 0.1) (layer "In5.Cu") (net 425))
  (segment (start 235.95 100.1) (end 209.937866 100.1) (width 0.1) (layer "In5.Cu") (net 425))
  (segment (start 179.636328 102.326328) (end 179.636328 102.060008) (width 0.09) (layer "In5.Cu") (net 425))
  (segment (start 181.698182 103.712296) (end 181.698182 103.408818) (width 0.1) (layer "In5.Cu") (net 425))
  (segment (start 181.698182 103.408818) (end 181.698182 103.208943) (width 0.09) (layer "In5.Cu") (net 425))
  (segment (start 244.351774 100.216019) (end 244.117792 100.45) (width 0.1) (layer "In5.Cu") (net 425))
  (segment (start 180.944239 102.455) (end 179.765 102.455) (width 0.09) (layer "In5.Cu") (net 425))
  (segment (start 245.182208 100.45) (end 244.948227 100.216019) (width 0.1) (layer "In5.Cu") (net 425))
  (segment (start 202.287866 107.75) (end 183.462134 107.75) (width 0.1) (layer "In5.Cu") (net 425))
  (segment (start 246.637866 100.1) (end 246.287866 100.45) (width 0.1) (layer "In5.Cu") (net 425))
  (segment (start 181.225 104.475) (end 181.175 104.475) (width 0.1) (layer "In5.Cu") (net 425))
  (segment (start 248.05 100.637866) (end 247.512134 100.1) (width 0.1) (layer "In5.Cu") (net 425))
  (segment (start 247.512134 100.1) (end 246.637866 100.1) (width 0.1) (layer "In5.Cu") (net 425))
  (arc (start 179.8 104.475) (mid 179.676256 104.423744) (end 179.625 104.3) (width 0.1) (layer "In5.Cu") (net 425))
  (arc (start 180.748846 105.147386) (mid 180.712234 105.235774) (end 180.623846 105.272386) (width 0.1) (layer "In5.Cu") (net 425))
  (arc (start 181.7 104.95) (mid 181.560876 104.614124) (end 181.225 104.475) (width 0.1) (layer "In5.Cu") (net 425))
  (arc (start 179.625 104.3) (mid 179.676256 104.176256) (end 179.8 104.125) (width 0.1) (layer "In5.Cu") (net 425))
  (arc (start 180.523846 105.272386) (mid 180.435458 105.235774) (end 180.398846 105.147386) (width 0.1) (layer "In5.Cu") (net 425))
  (arc (start 181.175 104.475) (mid 180.87448 104.59948) (end 180.75 104.9) (width 0.1) (layer "In5.Cu") (net 425))
  (arc (start 180.4 104.9) (mid 180.27552 104.59948) (end 179.975 104.475) (width 0.1) (layer "In5.Cu") (net 425))
  (arc (start 181.225 104.125) (mid 181.538189 104.007124) (end 181.698182 103.712296) (width 0.1) (layer "In5.Cu") (net 425))
  (segment (start 247.753001 101.418001) (end 247.825 101.49) (width 0.1) (layer "B.Cu") (net 425))
  (segment (start 247.825 101.49) (end 247.825 101.905) (width 0.1) (layer "B.Cu") (net 425))
  (segment (start 247.19 101.6) (end 247.371999 101.418001) (width 0.1) (layer "B.Cu") (net 425))
  (segment (start 247.371999 101.418001) (end 247.753001 101.418001) (width 0.1) (layer "B.Cu") (net 425))
  (segment (start 177.636328 102.060008) (end 178.136328 101.560008) (width 0.1) (layer "F.Cu") (net 426))
  (via blind (at 177.636328 102.060008) (size 0.5) (drill 0.2) (layers "F.Cu" "In5.Cu") (net 426))
  (via (at 247.19 104.746) (size 0.5) (drill 0.2) (layers "F.Cu" "B.Cu") (net 426))
  (segment (start 246.312134 104.35) (end 245.272208 104.35) (width 0.1) (layer "In5.Cu") (net 426))
  (segment (start 247.008001 104.927999) (end 246.890133 104.927999) (width 0.1) (layer "In5.Cu") (net 426))
  (segment (start 204.887866 109.65) (end 182.061134 109.65) (width 0.1) (layer "In5.Cu") (net 426))
  (segment (start 244.948227 104.026019) (end 244.351774 104.026019) (width 0.1) (layer "In5.Cu") (net 426))
  (segment (start 176.342414 101.660008) (end 177.540008 101.660008) (width 0.09) (layer "In5.Cu") (net 426))
  (segment (start 245.272208 104.35) (end 244.948227 104.026019) (width 0.1) (layer "In5.Cu") (net 426))
  (segment (start 232.062134 102.85) (end 211.687866 102.85) (width 0.1) (layer "In5.Cu") (net 426))
  (segment (start 176.223988 104.102566) (end 176.039445 103.918023) (width 0.09) (layer "In5.Cu") (net 426))
  (segment (start 176.234 103.467422) (end 176.234 101.768422) (width 0.09) (layer "In5.Cu") (net 426))
  (segment (start 176.234 101.768422) (end 176.342414 101.660008) (width 0.09) (layer "In5.Cu") (net 426))
  (segment (start 247.19 104.746) (end 247.008001 104.927999) (width 0.1) (layer "In5.Cu") (net 426))
  (segment (start 242.832134 104.37) (end 242.312134 103.85) (width 0.1) (layer "In5.Cu") (net 426))
  (segment (start 182.061134 109.65) (end 176.810298 104.399164) (width 0.1) (layer "In5.Cu") (net 426))
  (segment (start 211.687866 102.85) (end 204.887866 109.65) (width 0.1) (layer "In5.Cu") (net 426))
  (segment (start 176.6951 104.35523) (end 176.442436 104.102566) (width 0.09) (layer "In5.Cu") (net 426))
  (segment (start 177.636328 101.756328) (end 177.636328 102.060008) (width 0.09) (layer "In5.Cu") (net 426))
  (segment (start 246.890133 104.927999) (end 246.312134 104.35) (width 0.1) (layer "In5.Cu") (net 426))
  (segment (start 242.312134 103.85) (end 233.062134 103.85) (width 0.1) (layer "In5.Cu") (net 426))
  (segment (start 244.007793 104.37) (end 242.832134 104.37) (width 0.1) (layer "In5.Cu") (net 426))
  (segment (start 176.442436 104.102566) (end 176.223988 104.102566) (width 0.09) (layer "In5.Cu") (net 426))
  (segment (start 244.351774 104.026019) (end 244.007793 104.37) (width 0.1) (layer "In5.Cu") (net 426))
  (segment (start 177.540008 101.660008) (end 177.636328 101.756328) (width 0.09) (layer "In5.Cu") (net 426))
  (segment (start 176.039445 103.918023) (end 176.039445 103.661977) (width 0.09) (layer "In5.Cu") (net 426))
  (segment (start 176.810298 104.399164) (end 176.801166 104.399164) (width 0.09) (layer "In5.Cu") (net 426))
  (segment (start 176.039445 103.661977) (end 176.234 103.467422) (width 0.09) (layer "In5.Cu") (net 426))
  (segment (start 233.062134 103.85) (end 232.062134 102.85) (width 0.1) (layer "In5.Cu") (net 426))
  (arc (start 176.801166 104.399164) (mid 176.743763 104.387746) (end 176.6951 104.35523) (width 0.09) (layer "In5.Cu") (net 426))
  (segment (start 247.722001 104.927999) (end 247.825 104.825) (width 0.1) (layer "B.Cu") (net 426))
  (segment (start 247.371999 104.927999) (end 247.722001 104.927999) (width 0.1) (layer "B.Cu") (net 426))
  (segment (start 247.19 104.746) (end 247.371999 104.927999) (width 0.1) (layer "B.Cu") (net 426))
  (segment (start 247.825 104.825) (end 247.825 104.445) (width 0.1) (layer "B.Cu") (net 426))
  (segment (start 181.136328 100.560008) (end 180.636328 101.060008) (width 0.1) (layer "F.Cu") (net 427))
  (via blind (at 180.636328 101.060008) (size 0.5) (drill 0.2) (layers "F.Cu" "In5.Cu") (net 427))
  (via (at 248.46 99.06) (size 0.5) (drill 0.2) (layers "F.Cu" "B.Cu") (net 427))
  (segment (start 249 99.337866) (end 248.787866 99.55) (width 0.1) (layer "In5.Cu") (net 427))
  (segment (start 237.85 99.25) (end 237.847909 99.25) (width 0.1) (layer "In5.Cu") (net 427))
  (segment (start 248.865867 98.878001) (end 249 99.012134) (width 0.1) (layer "In5.Cu") (net 427))
  (segment (start 247.862134 99.55) (end 247.562134 99.25) (width 0.1) (layer "In5.Cu") (net 427))
  (segment (start 180.710007 101.410007) (end 180.636328 101.336328) (width 0.1) (layer "In5.Cu") (net 427))
  (segment (start 246.4 99.25) (end 246.32397 99.25) (width 0.1) (layer "In5.Cu") (net 427))
  (segment (start 248.641999 98.878001) (end 248.865867 98.878001) (width 0.1) (layer "In5.Cu") (net 427))
  (segment (start 243.325 98.925) (end 243.325 98.606721) (width 0.1) (layer "In5.Cu") (net 427))
  (segment (start 237.85 99.647909) (end 237.85 99.25) (width 0.1) (layer "In5.Cu") (net 427))
  (segment (start 246.09397 99.48) (end 245.57 99.48) (width 0.1) (layer "In5.Cu") (net 427))
  (segment (start 183.432107 105.13609) (end 183.149263 105.418933) (width 0.1) (layer "In5.Cu") (net 427))
  (segment (start 237.45 98.454182) (end 237.245818 98.454182) (width 0.1) (layer "In5.Cu") (net 427))
  (segment (start 244.97 99.08) (end 244.97 99.28) (width 0.1) (layer "In5.Cu") (net 427))
  (segment (start 182.7 104.7) (end 182.9 104.7) (width 0.1) (layer "In5.Cu") (net 427))
  (segment (start 181.047141 101.410007) (end 180.710007 101.410007) (width 0.1) (layer "In5.Cu") (net 427))
  (segment (start 242.975 98.606721) (end 242.975 98.925) (width 0.1) (layer "In5.Cu") (net 427))
  (segment (start 182.5 105.087866) (end 182.5 104.9) (width 0.1) (layer "In5.Cu") (net 427))
  (segment (start 184.162134 106.75) (end 183.891725 106.479591) (width 0.1) (layer "In5.Cu") (net 427))
  (segment (start 247.562134 99.25) (end 247.05 99.25) (width 0.1) (layer "In5.Cu") (net 427))
  (segment (start 238.25 98.852091) (end 238.25 99.647909) (width 0.1) (layer "In5.Cu") (net 427))
  (segment (start 236.847909 98.852091) (end 236.847909 99.002091) (width 0.1) (layer "In5.Cu") (net 427))
  (segment (start 246.75 98.95) (end 246.7 98.95) (width 0.1) (layer "In5.Cu") (net 427))
  (segment (start 239.347909 99.1) (end 242.8 99.1) (width 0.1) (layer "In5.Cu") (net 427))
  (segment (start 208.937866 99.1) (end 201.287866 106.75) (width 0.1) (layer "In5.Cu") (net 427))
  (segment (start 244.262134 99.1) (end 243.5 99.1) (width 0.1) (layer "In5.Cu") (net 427))
  (segment (start 248.787866 99.55) (end 247.862134 99.55) (width 0.1) (layer "In5.Cu") (net 427))
  (segment (start 184.325 106.75) (end 184.162134 106.75) (width 0.1) (layer "In5.Cu") (net 427))
  (segment (start 201.287866 106.75) (end 185.325 106.75) (width 0.1) (layer "In5.Cu") (net 427))
  (segment (start 245.37 99.28) (end 245.37 99.08) (width 0.1) (layer "In5.Cu") (net 427))
  (segment (start 244.642134 99.48) (end 244.262134 99.1) (width 0.1) (layer "In5.Cu") (net 427))
  (segment (start 246.32397 99.25) (end 246.09397 99.48) (width 0.1) (layer "In5.Cu") (net 427))
  (segment (start 237.847909 99.25) (end 237.847909 98.852091) (width 0.1) (layer "In5.Cu") (net 427))
  (segment (start 238.152091 99.745818) (end 237.947909 99.745818) (width 0.1) (layer "In5.Cu") (net 427))
  (segment (start 183.149263 105.418933) (end 183.149265 105.418934) (width 0.1) (layer "In5.Cu") (net 427))
  (segment (start 182.5 103.5) (end 182.5 102.862866) (width 0.1) (layer "In5.Cu") (net 427))
  (segment (start 182.831065 105.418932) (end 182.5 105.087866) (width 0.1) (layer "In5.Cu") (net 427))
  (segment (start 238.852091 98.454182) (end 238.647909 98.454182) (width 0.1) (layer "In5.Cu") (net 427))
  (segment (start 182.9 103.7) (end 182.7 103.7) (width 0.1) (layer "In5.Cu") (net 427))
  (segment (start 249 99.012134) (end 249 99.337866) (width 0.1) (layer "In5.Cu") (net 427))
  (segment (start 184.174569 105.136089) (end 184.174571 105.13609) (width 0.1) (layer "In5.Cu") (net 427))
  (segment (start 184.17457 105.878553) (end 184.174568 105.878552) (width 0.1) (layer "In5.Cu") (net 427))
  (segment (start 239.25 99.002091) (end 239.25 98.852091) (width 0.1) (layer "In5.Cu") (net 427))
  (segment (start 183.891725 106.161395) (end 184.17457 105.878553) (width 0.1) (layer "In5.Cu") (net 427))
  (segment (start 182.5 102.862866) (end 181.047141 101.410007) (width 0.1) (layer "In5.Cu") (net 427))
  (segment (start 248.46 99.06) (end 248.641999 98.878001) (width 0.1) (layer "In5.Cu") (net 427))
  (segment (start 244.77 99.48) (end 244.642134 99.48) (width 0.1) (layer "In5.Cu") (net 427))
  (segment (start 180.636328 101.336328) (end 180.636328 101.060008) (width 0.1) (layer "In5.Cu") (net 427))
  (segment (start 236.75 99.1) (end 208.937866 99.1) (width 0.1) (layer "In5.Cu") (net 427))
  (arc (start 185.325 106.75) (mid 185.148223 106.676777) (end 185.075 106.5) (width 0.1) (layer "In5.Cu") (net 427))
  (arc (start 246.55 99.1) (mid 246.506066 99.206066) (end 246.4 99.25) (width 0.1) (layer "In5.Cu") (net 427))
  (arc (start 242.975 98.925) (mid 242.923744 99.048744) (end 242.8 99.1) (width 0.1) (layer "In5.Cu") (net 427))
  (arc (start 238.25 99.647909) (mid 238.221323 99.717141) (end 238.152091 99.745818) (width 0.1) (layer "In5.Cu") (net 427))
  (arc (start 238.647909 98.454182) (mid 238.366545 98.570727) (end 238.25 98.852091) (width 0.1) (layer "In5.Cu") (net 427))
  (arc (start 245.17 98.88) (mid 245.028579 98.938579) (end 244.97 99.08) (width 0.1) (layer "In5.Cu") (net 427))
  (arc (start 182.5 104.9) (mid 182.558579 104.758579) (end 182.7 104.7) (width 0.1) (layer "In5.Cu") (net 427))
  (arc (start 246.9 99.1) (mid 246.856066 98.993934) (end 246.75 98.95) (width 0.1) (layer "In5.Cu") (net 427))
  (arc (start 182.7 103.7) (mid 182.558579 103.641421) (end 182.5 103.5) (width 0.1) (layer "In5.Cu") (net 427))
  (arc (start 239.25 98.852091) (mid 239.133455 98.570727) (end 238.852091 98.454182) (width 0.1) (layer "In5.Cu") (net 427))
  (arc (start 184.174568 105.878552) (mid 184.328339 105.507322) (end 184.174569 105.136089) (width 0.1) (layer "In5.Cu") (net 427))
  (arc (start 183.891725 106.479591) (mid 183.825825 106.320494) (end 183.891725 106.161395) (width 0.1) (layer "In5.Cu") (net 427))
  (arc (start 243.5 99.1) (mid 243.376256 99.048744) (end 243.325 98.925) (width 0.1) (layer "In5.Cu") (net 427))
  (arc (start 183.4 104.2) (mid 183.253553 103.846447) (end 182.9 103.7) (width 0.1) (layer "In5.Cu") (net 427))
  (arc (start 245.57 99.48) (mid 245.428579 99.421421) (end 245.37 99.28) (width 0.1) (layer "In5.Cu") (net 427))
  (arc (start 184.825 106.25) (mid 184.648223 106.323223) (end 184.575 106.5) (width 0.1) (layer "In5.Cu") (net 427))
  (arc (start 239.347909 99.1) (mid 239.278677 99.071323) (end 239.25 99.002091) (width 0.1) (layer "In5.Cu") (net 427))
  (arc (start 184.174571 105.13609) (mid 183.803338 104.98232) (end 183.432107 105.13609) (width 0.1) (layer "In5.Cu") (net 427))
  (arc (start 236.847909 99.002091) (mid 236.819232 99.071323) (end 236.75 99.1) (width 0.1) (layer "In5.Cu") (net 427))
  (arc (start 185.075 106.5) (mid 185.001777 106.323223) (end 184.825 106.25) (width 0.1) (layer "In5.Cu") (net 427))
  (arc (start 245.37 99.08) (mid 245.311421 98.938579) (end 245.17 98.88) (width 0.1) (layer "In5.Cu") (net 427))
  (arc (start 183.149265 105.418934) (mid 182.990166 105.484835) (end 182.831065 105.418932) (width 0.1) (layer "In5.Cu") (net 427))
  (arc (start 237.847909 98.852091) (mid 237.731364 98.570727) (end 237.45 98.454182) (width 0.1) (layer "In5.Cu") (net 427))
  (arc (start 237.947909 99.745818) (mid 237.878677 99.717141) (end 237.85 99.647909) (width 0.1) (layer "In5.Cu") (net 427))
  (arc (start 243.15 98.431721) (mid 243.026256 98.482977) (end 242.975 98.606721) (width 0.1) (layer "In5.Cu") (net 427))
  (arc (start 243.325 98.606721) (mid 243.273744 98.482977) (end 243.15 98.431721) (width 0.1) (layer "In5.Cu") (net 427))
  (arc (start 237.245818 98.454182) (mid 236.964454 98.570727) (end 236.847909 98.852091) (width 0.1) (layer "In5.Cu") (net 427))
  (arc (start 247.05 99.25) (mid 246.943934 99.206066) (end 246.9 99.1) (width 0.1) (layer "In5.Cu") (net 427))
  (arc (start 182.9 104.7) (mid 183.253553 104.553553) (end 183.4 104.2) (width 0.1) (layer "In5.Cu") (net 427))
  (arc (start 246.7 98.95) (mid 246.593934 98.993934) (end 246.55 99.1) (width 0.1) (layer "In5.Cu") (net 427))
  (arc (start 244.97 99.28) (mid 244.911421 99.421421) (end 244.77 99.48) (width 0.1) (layer "In5.Cu") (net 427))
  (arc (start 184.575 106.5) (mid 184.501777 106.676777) (end 184.325 106.75) (width 0.1) (layer "In5.Cu") (net 427))
  (segment (start 248.641999 98.878001) (end 249.023001 98.878001) (width 0.1) (layer "B.Cu") (net 427))
  (segment (start 248.46 99.06) (end 248.641999 98.878001) (width 0.1) (layer "B.Cu") (net 427))
  (segment (start 249.095 98.95) (end 249.095 99.365) (width 0.1) (layer "B.Cu") (net 427))
  (segment (start 249.023001 98.878001) (end 249.095 98.95) (width 0.1) (layer "B.Cu") (net 427))
  (segment (start 180.136328 100.560008) (end 179.636328 101.060008) (width 0.1) (layer "F.Cu") (net 428))
  (via (at 245.92 102.87) (size 0.5) (drill 0.2) (layers "F.Cu" "B.Cu") (net 428))
  (via (at 179.636328 101.060008) (size 0.5) (drill 0.2) (layers "F.Cu" "B.Cu") (net 428))
  (segment (start 245.861371 103.649237) (end 246.350917 103.649237) (width 0.1) (layer "In7.Cu") (net 428))
  (segment (start 243.003834 102.458627) (end 243.003834 102.458626) (width 0.1) (layer "In7.Cu") (net 428))
  (segment (start 181.334619 102.472485) (end 181.375 102.512866) (width 0.1) (layer "In7.Cu") (net 428))
  (segment (start 179.887134 102.075) (end 180.045 102.075) (width 0.1) (layer "In7.Cu") (net 428))
  (segment (start 244.05 102.65) (end 244.05 102.7) (width 0.1) (layer "In7.Cu") (net 428))
  (segment (start 181.369975 102.260353) (end 181.33462 102.295709) (width 0.1) (layer "In7.Cu") (net 428))
  (segment (start 246.101999 102.688001) (end 245.92 102.87) (width 0.1) (layer "In7.Cu") (net 428))
  (segment (start 244.3 102.95) (end 244.35 102.95) (width 0.1) (layer "In7.Cu") (net 428))
  (segment (start 179.286329 101.474195) (end 179.416067 101.603933) (width 0.1) (layer "In7.Cu") (net 428))
  (segment (start 181.334621 102.472486) (end 181.334619 102.472485) (width 0.1) (layer "In7.Cu") (net 428))
  (segment (start 181.369976 102.083579) (end 181.369975 102.083577) (width 0.1) (layer "In7.Cu") (net 428))
  (segment (start 181.157844 102.118932) (end 181.157843 102.118933) (width 0.1) (layer "In7.Cu") (net 428))
  (segment (start 181.375 102.512866) (end 181.375 104.137866) (width 0.1) (layer "In7.Cu") (net 428))
  (segment (start 192.512134 104.9) (end 193.262134 105.65) (width 0.1) (layer "In7.Cu") (net 428))
  (segment (start 180.845 102.075) (end 180.937134 102.075) (width 0.1) (layer "In7.Cu") (net 428))
  (segment (start 246.65918 103.031314) (end 246.315867 102.688001) (width 0.1) (layer "In7.Cu") (net 428))
  (segment (start 246.65918 103.340974) (end 246.65918 103.031314) (width 0.1) (layer "In7.Cu") (net 428))
  (segment (start 182.137134 104.9) (end 192.512134 104.9) (width 0.1) (layer "In7.Cu") (net 428))
  (segment (start 242.961041 102.748908) (end 242.96104 102.748906) (width 0.1) (layer "In7.Cu") (net 428))
  (segment (start 198.737866 105.65) (end 199.575594 104.812272) (width 0.1) (layer "In7.Cu") (net 428))
  (segment (start 243.162134 102.95) (end 243.3 102.95) (width 0.1) (layer "In7.Cu") (net 428))
  (segment (start 179.286329 101.410007) (end 179.286329 101.474195) (width 0.1) (layer "In7.Cu") (net 428))
  (segment (start 234.062134 101.65) (end 234.562134 102.15) (width 0.1) (layer "In7.Cu") (net 428))
  (segment (start 181.375 104.137866) (end 182.137134 104.9) (width 0.1) (layer "In7.Cu") (net 428))
  (segment (start 246.315867 102.688001) (end 246.101999 102.688001) (width 0.1) (layer "In7.Cu") (net 428))
  (segment (start 180.245 101.875) (end 180.245 101.475) (width 0.1) (layer "In7.Cu") (net 428))
  (segment (start 245.162134 102.95) (end 245.861371 103.649237) (width 0.1) (layer "In7.Cu") (net 428))
  (segment (start 243.003834 102.458626) (end 242.961041 102.50142) (width 0.1) (layer "In7.Cu") (net 428))
  (segment (start 181.157843 102.118933) (end 181.193199 102.083578) (width 0.1) (layer "In7.Cu") (net 428))
  (segment (start 242.362134 102.15) (end 242.466067 102.253933) (width 0.1) (layer "In7.Cu") (net 428))
  (segment (start 242.713554 102.253932) (end 242.713555 102.253934) (width 0.1) (layer "In7.Cu") (net 428))
  (segment (start 193.262134 105.65) (end 198.737866 105.65) (width 0.1) (layer "In7.Cu") (net 428))
  (segment (start 180.645 101.475) (end 180.645 101.875) (width 0.1) (layer "In7.Cu") (net 428))
  (segment (start 234.562134 102.15) (end 242.362134 102.15) (width 0.1) (layer "In7.Cu") (net 428))
  (segment locked (start 234.062134 101.65) (end 207.387866 101.65) (width 0.1) (layer "In7.Cu") (net 428))
  (segment (start 243.55 102.7) (end 243.55 102.65) (width 0.1) (layer "In7.Cu") (net 428))
  (segment (start 204.225594 104.812272) (end 207.387866 101.65) (width 0.1) (layer "In7.Cu") (net 428))
  (segment (start 179.636328 101.060008) (end 179.286329 101.410007) (width 0.1) (layer "In7.Cu") (net 428))
  (segment (start 181.369974 102.260354) (end 181.369975 102.260353) (width 0.1) (layer "In7.Cu") (net 428))
  (segment (start 179.840331 102.028197) (end 179.887134 102.075) (width 0.1) (layer "In7.Cu") (net 428))
  (segment (start 180.937134 102.075) (end 180.981067 102.118933) (width 0.1) (layer "In7.Cu") (net 428))
  (segment (start 242.713555 102.253934) (end 242.756347 102.211139) (width 0.1) (layer "In7.Cu") (net 428))
  (segment (start 199.575594 104.812272) (end 204.225594 104.812272) (width 0.1) (layer "In7.Cu") (net 428))
  (segment (start 244.35 102.95) (end 245.162134 102.95) (width 0.1) (layer "In7.Cu") (net 428))
  (segment (start 243.003835 102.211139) (end 243.003835 102.21114) (width 0.1) (layer "In7.Cu") (net 428))
  (segment (start 179.84033 101.816066) (end 179.840331 101.816065) (width 0.1) (layer "In7.Cu") (net 428))
  (segment (start 246.350917 103.649237) (end 246.65918 103.340974) (width 0.1) (layer "In7.Cu") (net 428))
  (segment (start 179.6282 101.603932) (end 179.628199 101.603933) (width 0.1) (layer "In7.Cu") (net 428))
  (segment (start 242.96104 102.748906) (end 243.162134 102.95) (width 0.1) (layer "In7.Cu") (net 428))
  (arc (start 243.8 102.4) (mid 243.976777 102.473223) (end 244.05 102.65) (width 0.1) (layer "In7.Cu") (net 428))
  (arc (start 243.3 102.95) (mid 243.476777 102.876777) (end 243.55 102.7) (width 0.1) (layer "In7.Cu") (net 428))
  (arc (start 244.05 102.7) (mid 244.123223 102.876777) (end 244.3 102.95) (width 0.1) (layer "In7.Cu") (net 428))
  (arc (start 179.416067 101.603933) (mid 179.522135 101.647868) (end 179.6282 101.603932) (width 0.1) (layer "In7.Cu") (net 428))
  (arc (start 179.840331 101.816065) (mid 179.796397 101.922131) (end 179.840331 102.028197) (width 0.1) (layer "In7.Cu") (net 428))
  (arc (start 180.045 102.075) (mid 180.186421 102.016421) (end 180.245 101.875) (width 0.1) (layer "In7.Cu") (net 428))
  (arc (start 180.445 101.275) (mid 180.586421 101.333579) (end 180.645 101.475) (width 0.1) (layer "In7.Cu") (net 428))
  (arc (start 180.981067 102.118933) (mid 181.069456 102.155544) (end 181.157844 102.118932) (width 0.1) (layer "In7.Cu") (net 428))
  (arc (start 180.245 101.475) (mid 180.303579 101.333579) (end 180.445 101.275) (width 0.1) (layer "In7.Cu") (net 428))
  (arc (start 242.961041 102.50142) (mid 242.909785 102.625164) (end 242.961041 102.748908) (width 0.1) (layer "In7.Cu") (net 428))
  (arc (start 181.369975 102.083577) (mid 181.406586 102.171966) (end 181.369974 102.260354) (width 0.1) (layer "In7.Cu") (net 428))
  (arc (start 242.756347 102.211139) (mid 242.880091 102.159883) (end 243.003835 102.211139) (width 0.1) (layer "In7.Cu") (net 428))
  (arc (start 242.466067 102.253933) (mid 242.589811 102.305189) (end 242.713554 102.253932) (width 0.1) (layer "In7.Cu") (net 428))
  (arc (start 180.645 101.875) (mid 180.703579 102.016421) (end 180.845 102.075) (width 0.1) (layer "In7.Cu") (net 428))
  (arc (start 243.003835 102.21114) (mid 243.055091 102.334884) (end 243.003834 102.458627) (width 0.1) (layer "In7.Cu") (net 428))
  (arc (start 243.55 102.65) (mid 243.623223 102.473223) (end 243.8 102.4) (width 0.1) (layer "In7.Cu") (net 428))
  (arc (start 179.628199 101.603933) (mid 179.734265 101.559999) (end 179.840331 101.603933) (width 0.1) (layer "In7.Cu") (net 428))
  (arc (start 181.33462 102.295709) (mid 181.298009 102.384098) (end 181.334621 102.472486) (width 0.1) (layer "In7.Cu") (net 428))
  (arc (start 181.193199 102.083578) (mid 181.281588 102.046967) (end 181.369976 102.083579) (width 0.1) (layer "In7.Cu") (net 428))
  (arc (start 179.840331 101.603933) (mid 179.884266 101.710001) (end 179.84033 101.816066) (width 0.1) (layer "In7.Cu") (net 428))
  (segment (start 246.101999 102.688001) (end 246.483001 102.688001) (width 0.1) (layer "B.Cu") (net 428))
  (segment (start 246.483001 102.688001) (end 246.555 102.76) (width 0.1) (layer "B.Cu") (net 428))
  (segment (start 246.555 103.175) (end 246.555 102.76) (width 0.1) (layer "B.Cu") (net 428))
  (segment (start 246.101999 102.688001) (end 245.92 102.87) (width 0.1) (layer "B.Cu") (net 428))
  (segment (start 195.760618 101.881282) (end 195.818063 101.938727) (width 0.1) (layer "F.Cu") (net 429))
  (segment (start 198.008014 101.968016) (end 198.057063 101.968016) (width 0.1) (layer "F.Cu") (net 429))
  (segment (start 196.926984 101.873016) (end 196.926984 101.868955) (width 0.1) (layer "F.Cu") (net 429))
  (segment (start 198.127774 101.938726) (end 198.14 101.9265) (width 0.1) (layer "F.Cu") (net 429))
  (segment (start 196.136328 101.560008) (end 195.885429 101.560008) (width 0.1) (layer "F.Cu") (net 429))
  (segment (start 252.190786 97.506274) (end 250.002006 99.695054) (width 0.122) (layer "F.Cu") (net 429))
  (segment (start 196.736984 101.868955) (end 196.736984 101.873016) (width 0.1) (layer "F.Cu") (net 429))
  (segment (start 196.546984 101.873016) (end 196.546984 101.868955) (width 0.1) (layer "F.Cu") (net 429))
  (segment (start 252.661012 97.3115) (end 253.785657 97.3115) (width 0.122) (layer "F.Cu") (net 429))
  (segment (start 195.888773 101.968016) (end 196.451984 101.968016) (width 0.1) (layer "F.Cu") (net 429))
  (segment (start 200.613453 101.9265) (end 198.14 101.9265) (width 0.122) (layer "F.Cu") (net 429))
  (segment (start 197.211984 101.968016) (end 198.008014 101.968016) (width 0.1) (layer "F.Cu") (net 429))
  (segment (start 197.116984 101.868955) (end 197.116984 101.873016) (width 0.1) (layer "F.Cu") (net 429))
  (segment (start 244.420862 99.782922) (end 242.315661 97.677721) (width 0.122) (layer "F.Cu") (net 429))
  (segment (start 195.814718 101.589298) (end 195.760617 101.643399) (width 0.1) (layer "F.Cu") (net 429))
  (segment (start 249.648453 99.8415) (end 244.562283 99.8415) (width 0.122) (layer "F.Cu") (net 429))
  (segment (start 205.215786 97.531274) (end 200.967007 101.780053) (width 0.122) (layer "F.Cu") (net 429))
  (segment (start 195.731328 101.714109) (end 195.731328 101.810571) (width 0.1) (layer "F.Cu") (net 429))
  (segment (start 254.225 96.955) (end 253.927079 97.252921) (width 0.122) (layer "F.Cu") (net 429))
  (segment (start 241.491881 97.3365) (end 205.686012 97.3365) (width 0.122) (layer "F.Cu") (net 429))
  (arc (start 196.546984 101.868955) (mid 196.574809 101.80178) (end 196.641984 101.773955) (width 0.1) (layer "F.Cu") (net 429))
  (arc (start 195.731328 101.810571) (mid 195.73894 101.84884) (end 195.760618 101.881282) (width 0.1) (layer "F.Cu") (net 429))
  (arc (start 195.885429 101.560008) (mid 195.84716 101.56762) (end 195.814718 101.589298) (width 0.1) (layer "F.Cu") (net 429))
  (arc (start 196.926984 101.868955) (mid 196.954809 101.80178) (end 197.021984 101.773955) (width 0.1) (layer "F.Cu") (net 429))
  (arc (start 195.760617 101.643399) (mid 195.73894 101.675841) (end 195.731328 101.714109) (width 0.1) (layer "F.Cu") (net 429))
  (arc (start 205.686012 97.3365) (mid 205.431528 97.38712) (end 205.215786 97.531274) (width 0.122) (layer "F.Cu") (net 429))
  (arc (start 196.641984 101.773955) (mid 196.709159 101.80178) (end 196.736984 101.868955) (width 0.1) (layer "F.Cu") (net 429))
  (arc (start 253.927079 97.252921) (mid 253.862194 97.296276) (end 253.785657 97.3115) (width 0.122) (layer "F.Cu") (net 429))
  (arc (start 200.967007 101.780053) (mid 200.804795 101.88844) (end 200.613453 101.9265) (width 0.122) (layer "F.Cu") (net 429))
  (arc (start 198.057063 101.968016) (mid 198.095332 101.960404) (end 198.127774 101.938726) (width 0.1) (layer "F.Cu") (net 429))
  (arc (start 242.315661 97.677721) (mid 241.937708 97.42518) (end 241.491881 97.3365) (width 0.122) (layer "F.Cu") (net 429))
  (arc (start 244.562283 99.8415) (mid 244.485747 99.826276) (end 244.420862 99.782922) (width 0.122) (layer "F.Cu") (net 429))
  (arc (start 197.021984 101.773955) (mid 197.089159 101.80178) (end 197.116984 101.868955) (width 0.1) (layer "F.Cu") (net 429))
  (arc (start 252.190786 97.506274) (mid 252.406528 97.36212) (end 252.661012 97.3115) (width 0.122) (layer "F.Cu") (net 429))
  (arc (start 197.116984 101.873016) (mid 197.144809 101.940191) (end 197.211984 101.968016) (width 0.1) (layer "F.Cu") (net 429))
  (arc (start 196.831984 101.968016) (mid 196.899159 101.940191) (end 196.926984 101.873016) (width 0.1) (layer "F.Cu") (net 429))
  (arc (start 196.736984 101.873016) (mid 196.764809 101.940191) (end 196.831984 101.968016) (width 0.1) (layer "F.Cu") (net 429))
  (arc (start 196.451984 101.968016) (mid 196.519159 101.940191) (end 196.546984 101.873016) (width 0.1) (layer "F.Cu") (net 429))
  (arc (start 250.002006 99.695054) (mid 249.839794 99.80344) (end 249.648453 99.8415) (width 0.122) (layer "F.Cu") (net 429))
  (arc (start 195.818063 101.938727) (mid 195.850505 101.960404) (end 195.888773 101.968016) (width 0.1) (layer "F.Cu") (net 429))
  (segment (start 255.634343 92.5185) (end 255.805657 92.5185) (width 0.122) (layer "F.Cu") (net 430))
  (segment (start 255.947079 92.577079) (end 256.08 92.71) (width 0.122) (layer "F.Cu") (net 430))
  (segment (start 255.195 92.875) (end 255.492922 92.577078) (width 0.122) (layer "F.Cu") (net 430))
  (via (at 256.08 92.71) (size 0.5) (drill 0.2) (layers "F.Cu" "B.Cu") (net 430))
  (arc (start 255.805657 92.5185) (mid 255.882194 92.533724) (end 255.947079 92.577079) (width 0.122) (layer "F.Cu") (net 430))
  (arc (start 255.634343 92.5185) (mid 255.557807 92.533724) (end 255.492922 92.577078) (width 0.122) (layer "F.Cu") (net 430))
  (segment (start 256.08 92.71) (end 256.209922 92.580078) (width 0.122) (layer "B.Cu") (net 430))
  (segment (start 256.715 92.651421) (end 256.715 93.015) (width 0.122) (layer "B.Cu") (net 430))
  (segment (start 256.351343 92.5215) (end 256.543657 92.5215) (width 0.122) (layer "B.Cu") (net 430))
  (segment (start 256.685079 92.580079) (end 256.685711 92.580711) (width 0.122) (layer "B.Cu") (net 430))
  (arc (start 256.543657 92.5215) (mid 256.620194 92.536724) (end 256.685079 92.580079) (width 0.122) (layer "B.Cu") (net 430))
  (arc (start 256.715 92.651421) (mid 256.707388 92.613153) (end 256.685711 92.580711) (width 0.122) (layer "B.Cu") (net 430))
  (arc (start 256.351343 92.5215) (mid 256.274807 92.536724) (end 256.209922 92.580078) (width 0.122) (layer "B.Cu") (net 430))
  (segment (start 195.445282 99.589298) (end 195.512039 99.656055) (width 0.1) (layer "F.Cu") (net 431))
  (segment (start 195.596978 99.986346) (end 195.712999 100.102367) (width 0.1) (layer "F.Cu") (net 431))
  (segment (start 250.635861 92.577079) (end 249.272078 93.940862) (width 0.122) (layer "F.Cu") (net 431))
  (segment (start 195.136328 99.560008) (end 195.374571 99.560008) (width 0.1) (layer "F.Cu") (net 431))
  (segment (start 254.225 92.875) (end 253.927078 92.577078) (width 0.122) (layer "F.Cu") (net 431))
  (segment (start 195.541328 99.726765) (end 195.541328 99.851995) (width 0.1) (layer "F.Cu") (net 431))
  (segment (start 195.847349 100.158016) (end 198.053095 100.158016) (width 0.1) (layer "F.Cu") (net 431))
  (segment (start 204.222993 96.499947) (end 200.733503 99.989437) (width 0.122) (layer "F.Cu") (net 431))
  (segment (start 249.106594 95.726346) (end 248.586346 96.246594) (width 0.122) (layer "F.Cu") (net 431))
  (segment (start 198.123806 100.187306) (end 198.15 100.2135) (width 0.1) (layer "F.Cu") (net 431))
  (segment (start 248.328252 96.3535) (end 204.576547 96.3535) (width 0.122) (layer "F.Cu") (net 431))
  (segment (start 253.785657 92.5185) (end 250.777283 92.5185) (width 0.122) (layer "F.Cu") (net 431))
  (segment (start 249.2135 94.082283) (end 249.2135 95.468252) (width 0.122) (layer "F.Cu") (net 431))
  (segment (start 200.192567 100.2135) (end 198.15 100.2135) (width 0.122) (layer "F.Cu") (net 431))
  (arc (start 250.635861 92.577079) (mid 250.700746 92.533724) (end 250.777283 92.5185) (width 0.122) (layer "F.Cu") (net 431))
  (arc (start 204.222993 96.499947) (mid 204.385205 96.39156) (end 204.576547 96.3535) (width 0.122) (layer "F.Cu") (net 431))
  (arc (start 248.586346 96.246594) (mid 248.467931 96.325716) (end 248.328252 96.3535) (width 0.122) (layer "F.Cu") (net 431))
  (arc (start 198.053095 100.158016) (mid 198.091364 100.165628) (end 198.123806 100.187306) (width 0.1) (layer "F.Cu") (net 431))
  (arc (start 195.445282 99.589298) (mid 195.41284 99.56762) (end 195.374571 99.560008) (width 0.1) (layer "F.Cu") (net 431))
  (arc (start 195.712999 100.102367) (mid 195.774639 100.143554) (end 195.847349 100.158016) (width 0.1) (layer "F.Cu") (net 431))
  (arc (start 195.596978 99.986346) (mid 195.555791 99.924705) (end 195.541328 99.851995) (width 0.1) (layer "F.Cu") (net 431))
  (arc (start 253.927078 92.577078) (mid 253.862193 92.533724) (end 253.785657 92.5185) (width 0.122) (layer "F.Cu") (net 431))
  (arc (start 200.733503 99.989437) (mid 200.485319 100.155268) (end 200.192567 100.2135) (width 0.122) (layer "F.Cu") (net 431))
  (arc (start 195.512039 99.656055) (mid 195.533716 99.688497) (end 195.541328 99.726765) (width 0.1) (layer "F.Cu") (net 431))
  (arc (start 249.272078 93.940862) (mid 249.228724 94.005747) (end 249.2135 94.082283) (width 0.122) (layer "F.Cu") (net 431))
  (arc (start 249.106594 95.726346) (mid 249.185716 95.607931) (end 249.2135 95.468252) (width 0.122) (layer "F.Cu") (net 431))
  (segment (start 179.136328 100.560008) (end 178.636328 101.060008) (width 0.1) (layer "F.Cu") (net 435))
  (via (at 178.636328 101.060008) (size 0.5) (drill 0.2) (layers "F.Cu" "B.Cu") (net 435))
  (via (at 245.92 102.206) (size 0.5) (drill 0.2) (layers "F.Cu" "B.Cu") (net 435))
  (segment (start 193.137866 105.95) (end 198.862134 105.95) (width 0.1) (layer "In7.Cu") (net 435))
  (segment (start 246.475185 103.949237) (end 246.95918 103.465242) (width 0.1) (layer "In7.Cu") (net 435))
  (segment (start 180.812866 102.375) (end 181.075 102.637134) (width 0.1) (layer "In7.Cu") (net 435))
  (segment (start 192.387866 105.2) (end 193.137866 105.95) (width 0.1) (layer "In7.Cu") (net 435))
  (segment (start 204.349862 105.112272) (end 207.512134 101.95) (width 0.1) (layer "In7.Cu") (net 435))
  (segment (start 178.986327 101.598461) (end 179.762866 102.375) (width 0.1) (layer "In7.Cu") (net 435))
  (segment (start 198.862134 105.95) (end 199.699862 105.112272) (width 0.1) (layer "In7.Cu") (net 435))
  (segment (start 178.636328 101.060008) (end 178.986327 101.410007) (width 0.1) (layer "In7.Cu") (net 435))
  (segment (start 245.037866 103.25) (end 245.737103 103.949237) (width 0.1) (layer "In7.Cu") (net 435))
  (segment (start 233.937866 101.95) (end 234.437866 102.45) (width 0.1) (layer "In7.Cu") (net 435))
  (segment (start 246.440133 102.387999) (end 246.101999 102.387999) (width 0.1) (layer "In7.Cu") (net 435))
  (segment (start 246.101999 102.387999) (end 245.92 102.206) (width 0.1) (layer "In7.Cu") (net 435))
  (segment (start 246.95918 103.465242) (end 246.95918 102.907046) (width 0.1) (layer "In7.Cu") (net 435))
  (segment (start 242.237866 102.45) (end 243.037866 103.25) (width 0.1) (layer "In7.Cu") (net 435))
  (segment (start 181.075 104.262134) (end 182.012866 105.2) (width 0.1) (layer "In7.Cu") (net 435))
  (segment (start 199.699862 105.112272) (end 204.349862 105.112272) (width 0.1) (layer "In7.Cu") (net 435))
  (segment (start 245.737103 103.949237) (end 246.475185 103.949237) (width 0.1) (layer "In7.Cu") (net 435))
  (segment (start 234.437866 102.45) (end 242.237866 102.45) (width 0.1) (layer "In7.Cu") (net 435))
  (segment (start 243.037866 103.25) (end 245.037866 103.25) (width 0.1) (layer "In7.Cu") (net 435))
  (segment (start 181.075 102.637134) (end 181.075 104.262134) (width 0.1) (layer "In7.Cu") (net 435))
  (segment locked (start 207.512134 101.95) (end 233.937866 101.95) (width 0.1) (layer "In7.Cu") (net 435))
  (segment (start 179.762866 102.375) (end 180.812866 102.375) (width 0.1) (layer "In7.Cu") (net 435))
  (segment (start 246.95918 102.907046) (end 246.440133 102.387999) (width 0.1) (layer "In7.Cu") (net 435))
  (segment (start 182.012866 105.2) (end 192.387866 105.2) (width 0.1) (layer "In7.Cu") (net 435))
  (segment (start 178.986327 101.410007) (end 178.986327 101.598461) (width 0.1) (layer "In7.Cu") (net 435))
  (segment (start 245.92 102.206) (end 246.101999 102.387999) (width 0.1) (layer "B.Cu") (net 435))
  (segment (start 246.555 101.905) (end 246.555 102.285) (width 0.1) (layer "B.Cu") (net 435))
  (segment (start 246.101999 102.387999) (end 246.452001 102.387999) (width 0.1) (layer "B.Cu") (net 435))
  (segment (start 246.452001 102.387999) (end 246.555 102.285) (width 0.1) (layer "B.Cu") (net 435))
  (segment (start 177.636328 101.060008) (end 178.136328 100.560008) (width 0.1) (layer "F.Cu") (net 436))
  (via blind (at 177.636328 101.060008) (size 0.5) (drill 0.2) (layers "F.Cu" "In5.Cu") (net 436))
  (via (at 247.19 105.41) (size 0.5) (drill 0.2) (layers "F.Cu" "B.Cu") (net 436))
  (segment (start 177.068202 105.100326) (end 181.917876 109.95) (width 0.1) (layer "In5.Cu") (net 436))
  (segment (start 176.034 102.886) (end 176.034 103.384578) (width 0.09) (layer "In5.Cu") (net 436))
  (segment (start 175.839445 103.579133) (end 175.839445 104.000867) (width 0.09) (layer "In5.Cu") (net 436))
  (segment (start 211.812134 103.15) (end 231.937866 103.15) (width 0.1) (layer "In5.Cu") (net 436))
  (segment (start 247.008001 105.228001) (end 247.19 105.41) (width 0.1) (layer "In5.Cu") (net 436))
  (segment (start 176.359592 104.302566) (end 176.528942 104.471916) (width 0.09) (layer "In5.Cu") (net 436))
  (segment (start 176.572876 104.577982) (end 176.572876 104.605) (width 0.09) (layer "In5.Cu") (net 436))
  (segment (start 181.917876 109.95) (end 205.012134 109.95) (width 0.1) (layer "In5.Cu") (net 436))
  (segment (start 245.14797 104.65) (end 246.187866 104.65) (width 0.1) (layer "In5.Cu") (net 436))
  (segment (start 176.822778 105.133617) (end 176.856069 105.100325) (width 0.1) (layer "In5.Cu") (net 436))
  (segment (start 176.141144 104.302566) (end 176.359592 104.302566) (width 0.09) (layer "In5.Cu") (net 436))
  (segment (start 176.643938 104.888194) (end 176.610646 104.921485) (width 0.1) (layer "In5.Cu") (net 436))
  (segment (start 176.643937 104.888195) (end 176.643938 104.888194) (width 0.1) (layer "In5.Cu") (net 436))
  (segment (start 176.819992 101.460008) (end 176.793603 101.460008) (width 0.09) (layer "In5.Cu") (net 436))
  (segment (start 246.187866 104.65) (end 246.765867 105.228001) (width 0.1) (layer "In5.Cu") (net 436))
  (segment (start 175.839445 104.000867) (end 176.141144 104.302566) (width 0.09) (layer "In5.Cu") (net 436))
  (segment (start 177.636328 101.363672) (end 177.539992 101.460008) (width 0.09) (layer "In5.Cu") (net 436))
  (segment (start 176.034 102.836) (end 176.034 102.886) (width 0.09) (layer "In5.Cu") (net 436))
  (segment (start 205.012134 109.95) (end 211.812134 103.15) (width 0.1) (layer "In5.Cu") (net 436))
  (segment (start 177.636328 101.060008) (end 177.636328 101.363672) (width 0.09) (layer "In5.Cu") (net 436))
  (segment (start 176.25957 101.460008) (end 176.034 101.685578) (width 0.09) (layer "In5.Cu") (net 436))
  (segment (start 231.937866 103.15) (end 232.937866 104.15) (width 0.1) (layer "In5.Cu") (net 436))
  (segment (start 177.539992 101.460008) (end 177.419992 101.460008) (width 0.09) (layer "In5.Cu") (net 436))
  (segment (start 244.82397 104.326) (end 245.14797 104.65) (width 0.1) (layer "In5.Cu") (net 436))
  (segment (start 176.034 101.685578) (end 176.034 102.286) (width 0.09) (layer "In5.Cu") (net 436))
  (segment (start 244.13203 104.67) (end 244.47603 104.326) (width 0.1) (layer "In5.Cu") (net 436))
  (segment (start 177.068201 105.100325) (end 177.068202 105.100326) (width 0.1) (layer "In5.Cu") (net 436))
  (segment (start 244.47603 104.326) (end 244.82397 104.326) (width 0.1) (layer "In5.Cu") (net 436))
  (segment (start 176.572876 104.605) (end 176.643938 104.676062) (width 0.1) (layer "In5.Cu") (net 436))
  (segment (start 232.937866 104.15) (end 242.187866 104.15) (width 0.1) (layer "In5.Cu") (net 436))
  (segment (start 176.034 103.384578) (end 175.839445 103.579133) (width 0.09) (layer "In5.Cu") (net 436))
  (segment (start 176.793603 101.460008) (end 176.25957 101.460008) (width 0.09) (layer "In5.Cu") (net 436))
  (segment (start 242.707866 104.67) (end 244.13203 104.67) (width 0.1) (layer "In5.Cu") (net 436))
  (segment (start 175.784 102.536) (end 175.784 102.586) (width 0.09) (layer "In5.Cu") (net 436))
  (segment (start 242.187866 104.15) (end 242.707866 104.67) (width 0.1) (layer "In5.Cu") (net 436))
  (segment (start 246.765867 105.228001) (end 247.008001 105.228001) (width 0.1) (layer "In5.Cu") (net 436))
  (segment (start 176.822779 105.133616) (end 176.822778 105.133617) (width 0.1) (layer "In5.Cu") (net 436))
  (arc (start 176.856069 105.100325) (mid 176.962135 105.056391) (end 177.068201 105.100325) (width 0.1) (layer "In5.Cu") (net 436))
  (arc (start 176.969992 101.310008) (mid 176.926058 101.416074) (end 176.819992 101.460008) (width 0.09) (layer "In5.Cu") (net 436))
  (arc (start 177.119992 101.160008) (mid 177.013926 101.203942) (end 176.969992 101.310008) (width 0.09) (layer "In5.Cu") (net 436))
  (arc (start 176.643938 104.676062) (mid 176.687872 104.782129) (end 176.643937 104.888195) (width 0.1) (layer "In5.Cu") (net 436))
  (arc (start 177.419992 101.460008) (mid 177.313926 101.416074) (end 177.269992 101.310008) (width 0.09) (layer "In5.Cu") (net 436))
  (arc (start 176.034 102.286) (mid 175.997388 102.374388) (end 175.909 102.411) (width 0.09) (layer "In5.Cu") (net 436))
  (arc (start 175.784 102.586) (mid 175.820612 102.674388) (end 175.909 102.711) (width 0.09) (layer "In5.Cu") (net 436))
  (arc (start 176.610646 104.921485) (mid 176.566712 105.027551) (end 176.610646 105.133617) (width 0.1) (layer "In5.Cu") (net 436))
  (arc (start 177.269992 101.310008) (mid 177.226058 101.203942) (end 177.119992 101.160008) (width 0.09) (layer "In5.Cu") (net 436))
  (arc (start 175.909 102.411) (mid 175.820612 102.447612) (end 175.784 102.536) (width 0.09) (layer "In5.Cu") (net 436))
  (arc (start 176.528942 104.471916) (mid 176.561458 104.520579) (end 176.572876 104.577982) (width 0.09) (layer "In5.Cu") (net 436))
  (arc (start 176.610646 105.133617) (mid 176.716713 105.177551) (end 176.822779 105.133616) (width 0.1) (layer "In5.Cu") (net 436))
  (arc (start 175.909 102.711) (mid 175.997388 102.747612) (end 176.034 102.836) (width 0.09) (layer "In5.Cu") (net 436))
  (segment (start 247.753001 105.228001) (end 247.825 105.3) (width 0.1) (layer "B.Cu") (net 436))
  (segment (start 247.19 105.41) (end 247.371999 105.228001) (width 0.1) (layer "B.Cu") (net 436))
  (segment (start 247.371999 105.228001) (end 247.753001 105.228001) (width 0.1) (layer "B.Cu") (net 436))
  (segment (start 247.825 105.3) (end 247.825 105.715) (width 0.1) (layer "B.Cu") (net 436))
  (segment (start 182.136328 99.560008) (end 181.636328 99.060008) (width 0.1) (layer "F.Cu") (net 437))
  (via blind (at 181.636328 99.060008) (size 0.5) (drill 0.2) (layers "F.Cu" "In5.Cu") (net 437))
  (via (at 248.46 95.25) (size 0.5) (drill 0.2) (layers "F.Cu" "B.Cu") (net 437))
  (segment (start 188.250877 104.35099) (end 188.250877 104.530877) (width 0.1) (layer "In5.Cu") (net 437))
  (segment (start 248.641999 95.068001) (end 248.46 95.25) (width 0.1) (layer "In5.Cu") (net 437))
  (segment (start 187.253123 104.530877) (end 187.253123 104.35099) (width 0.1) (layer "In5.Cu") (net 437))
  (segment (start 181.374422 99.468) (end 181.884992 99.468) (width 0.09) (layer "In5.Cu") (net 437))
  (segment (start 184.108831 100.269697) (end 184.199567 100.360433) (width 0.1) (layer "In5.Cu") (net 437))
  (segment (start 184.640527 100.55587) (end 184.640528 100.555869) (width 0.1) (layer "In5.Cu") (net 437))
  (segment (start 188.653123 104.530877) (end 188.653123 104.35099) (width 0.1) (layer "In5.Cu") (net 437))
  (segment (start 242.137866 95.4) (end 245.162134 95.4) (width 0.1) (layer "In5.Cu") (net 437))
  (segment (start 183.555067 99.715933) (end 183.684567 99.845433) (width 0.1) (layer "In5.Cu") (net 437))
  (segment (start 183.861344 99.845432) (end 183.861343 99.845433) (width 0.1) (layer "In5.Cu") (net 437))
  (segment (start 249.25 95.737866) (end 249.25 95.462134) (width 0.1) (layer "In5.Cu") (net 437))
  (segment (start 181.311992 99.060008) (end 181.636328 99.060008) (width 0.09) (layer "In5.Cu") (net 437))
  (segment (start 184.073475 100.234342) (end 184.108831 100.269697) (width 0.1) (layer "In5.Cu") (net 437))
  (segment (start 189.852 104.732) (end 192.330866 104.732) (width 0.1) (layer "In5.Cu") (net 437))
  (segment (start 185.274 101.434866) (end 185.274 102.961866) (width 0.1) (layer "In5.Cu") (net 437))
  (segment (start 186.638134 104.732) (end 187.052 104.732) (width 0.1) (layer "In5.Cu") (net 437))
  (segment (start 245.462134 95.7) (end 246.317 95.7) (width 0.1) (layer "In5.Cu") (net 437))
  (segment (start 248.061 95.7) (end 248.062134 95.7) (width 0.1) (layer "In5.Cu") (net 437))
  (segment (start 182.283496 100.215008) (end 182.283496 99.866504) (width 0.09) (layer "In5.Cu") (net 437))
  (segment (start 207.437866 96.6) (end 240.937866 96.6) (width 0.1) (layer "In5.Cu") (net 437))
  (segment (start 248.855867 95.068001) (end 248.641999 95.068001) (width 0.1) (layer "In5.Cu") (net 437))
  (segment (start 184.640528 100.555869) (end 184.62383 100.572564) (width 0.1) (layer "In5.Cu") (net 437))
  (segment (start 181.374422 99.468) (end 181.235 99.328578) (width 0.09) (layer "In5.Cu") (net 437))
  (segment (start 248.412134 96.05) (end 248.937866 96.05) (width 0.1) (layer "In5.Cu") (net 437))
  (segment (start 184.4117 100.360432) (end 184.411699 100.360433) (width 0.1) (layer "In5.Cu") (net 437))
  (segment (start 249.25 95.462134) (end 248.855867 95.068001) (width 0.1) (layer "In5.Cu") (net 437))
  (segment (start 181.235 99.137) (end 181.311992 99.060008) (width 0.09) (layer "In5.Cu") (net 437))
  (segment (start 186.442 104.129866) (end 186.442 104.535866) (width 0.1) (layer "In5.Cu") (net 437))
  (segment (start 247.536 95.525) (end 247.536 95.509528) (width 0.1) (layer "In5.Cu") (net 437))
  (segment (start 183.555067 99.715933) (end 183.552523 99.715933) (width 0.09) (layer "In5.Cu") (net 437))
  (segment (start 184.62383 100.784696) (end 184.623831 100.784697) (width 0.1) (layer "In5.Cu") (net 437))
  (segment (start 240.937866 96.6) (end 242.137866 95.4) (width 0.1) (layer "In5.Cu") (net 437))
  (segment (start 184.623831 100.784697) (end 185.274 101.434866) (width 0.1) (layer "In5.Cu") (net 437))
  (segment (start 185.274 102.961866) (end 186.442 104.129866) (width 0.1) (layer "In5.Cu") (net 437))
  (segment (start 192.330866 104.732) (end 193.237866 103.825) (width 0.1) (layer "In5.Cu") (net 437))
  (segment (start 184.038119 99.845433) (end 184.073474 99.880788) (width 0.1) (layer "In5.Cu") (net 437))
  (segment (start 193.237866 103.825) (end 200.212866 103.825) (width 0.1) (layer "In5.Cu") (net 437))
  (segment (start 189.650877 104.35099) (end 189.650877 104.530877) (width 0.1) (layer "In5.Cu") (net 437))
  (segment (start 247.886 95.509528) (end 247.886 95.525) (width 0.1) (layer "In5.Cu") (net 437))
  (segment (start 200.212866 103.825) (end 207.437866 96.6) (width 0.1) (layer "In5.Cu") (net 437))
  (segment (start 186.442 104.535866) (end 186.638134 104.732) (width 0.1) (layer "In5.Cu") (net 437))
  (segment (start 181.235 99.328578) (end 181.235 99.137) (width 0.09) (layer "In5.Cu") (net 437))
  (segment (start 248.937866 96.05) (end 249.25 95.737866) (width 0.1) (layer "In5.Cu") (net 437))
  (segment (start 248.062134 95.7) (end 248.412134 96.05) (width 0.1) (layer "In5.Cu") (net 437))
  (segment (start 247.017 95.7) (end 247.361 95.7) (width 0.1) (layer "In5.Cu") (net 437))
  (segment (start 184.073473 100.057565) (end 184.073475 100.057566) (width 0.1) (layer "In5.Cu") (net 437))
  (segment (start 183.134762 99.468) (end 183.084992 99.468) (width 0.09) (layer "In5.Cu") (net 437))
  (segment (start 184.411699 100.360433) (end 184.428396 100.343737) (width 0.1) (layer "In5.Cu") (net 437))
  (segment (start 182.686488 99.866504) (end 182.686488 100.215008) (width 0.09) (layer "In5.Cu") (net 437))
  (segment (start 245.162134 95.4) (end 245.462134 95.7) (width 0.1) (layer "In5.Cu") (net 437))
  (segment (start 183.446457 99.671999) (end 183.31861 99.544152) (width 0.09) (layer "In5.Cu") (net 437))
  (arc (start 189.650877 104.530877) (mid 189.709785 104.673092) (end 189.852 104.732) (width 0.1) (layer "In5.Cu") (net 437))
  (arc (start 183.552523 99.715933) (mid 183.49512 99.704515) (end 183.446457 99.671999) (width 0.09) (layer "In5.Cu") (net 437))
  (arc (start 247.711 95.334528) (mid 247.834744 95.385784) (end 247.886 95.509528) (width 0.1) (layer "In5.Cu") (net 437))
  (arc (start 246.667 95.35) (mid 246.790744 95.401256) (end 246.842 95.525) (width 0.1) (layer "In5.Cu") (net 437))
  (arc (start 184.62383 100.572564) (mid 184.579896 100.67863) (end 184.62383 100.784696) (width 0.1) (layer "In5.Cu") (net 437))
  (arc (start 247.361 95.7) (mid 247.484744 95.648744) (end 247.536 95.525) (width 0.1) (layer "In5.Cu") (net 437))
  (arc (start 188.653123 104.35099) (mid 188.799241 103.998231) (end 189.152 103.852113) (width 0.1) (layer "In5.Cu") (net 437))
  (arc (start 183.861343 99.845433) (mid 183.949731 99.808821) (end 184.038119 99.845433) (width 0.1) (layer "In5.Cu") (net 437))
  (arc (start 184.073474 99.880788) (mid 184.110085 99.969177) (end 184.073473 100.057565) (width 0.1) (layer "In5.Cu") (net 437))
  (arc (start 182.283496 99.866504) (mid 182.166777 99.584719) (end 181.884992 99.468) (width 0.09) (layer "In5.Cu") (net 437))
  (arc (start 189.152 103.852113) (mid 189.504759 103.998231) (end 189.650877 104.35099) (width 0.1) (layer "In5.Cu") (net 437))
  (arc (start 247.536 95.509528) (mid 247.587256 95.385784) (end 247.711 95.334528) (width 0.1) (layer "In5.Cu") (net 437))
  (arc (start 184.640528 100.343737) (mid 184.684461 100.449803) (end 184.640527 100.55587) (width 0.1) (layer "In5.Cu") (net 437))
  (arc (start 246.317 95.7) (mid 246.440744 95.648744) (end 246.492 95.525) (width 0.1) (layer "In5.Cu") (net 437))
  (arc (start 182.686488 100.215008) (mid 182.627471 100.357487) (end 182.484992 100.416504) (width 0.09) (layer "In5.Cu") (net 437))
  (arc (start 183.134762 99.468) (mid 183.23426 99.487791) (end 183.31861 99.544152) (width 0.09) (layer "In5.Cu") (net 437))
  (arc (start 247.886 95.525) (mid 247.937256 95.648744) (end 248.061 95.7) (width 0.1) (layer "In5.Cu") (net 437))
  (arc (start 183.084992 99.468) (mid 182.803207 99.584719) (end 182.686488 99.866504) (width 0.09) (layer "In5.Cu") (net 437))
  (arc (start 188.452 104.732) (mid 188.594215 104.673092) (end 188.653123 104.530877) (width 0.1) (layer "In5.Cu") (net 437))
  (arc (start 184.199567 100.360433) (mid 184.305635 100.404368) (end 184.4117 100.360432) (width 0.1) (layer "In5.Cu") (net 437))
  (arc (start 187.253123 104.35099) (mid 187.399241 103.998231) (end 187.752 103.852113) (width 0.1) (layer "In5.Cu") (net 437))
  (arc (start 187.052 104.732) (mid 187.194215 104.673092) (end 187.253123 104.530877) (width 0.1) (layer "In5.Cu") (net 437))
  (arc (start 187.752 103.852113) (mid 188.104759 103.998231) (end 188.250877 104.35099) (width 0.1) (layer "In5.Cu") (net 437))
  (arc (start 246.492 95.525) (mid 246.543256 95.401256) (end 246.667 95.35) (width 0.1) (layer "In5.Cu") (net 437))
  (arc (start 246.842 95.525) (mid 246.893256 95.648744) (end 247.017 95.7) (width 0.1) (layer "In5.Cu") (net 437))
  (arc (start 184.073475 100.057566) (mid 184.036863 100.145954) (end 184.073475 100.234342) (width 0.1) (layer "In5.Cu") (net 437))
  (arc (start 183.684567 99.845433) (mid 183.772956 99.882044) (end 183.861344 99.845432) (width 0.1) (layer "In5.Cu") (net 437))
  (arc (start 182.484992 100.416504) (mid 182.342513 100.357487) (end 182.283496 100.215008) (width 0.09) (layer "In5.Cu") (net 437))
  (arc (start 184.428396 100.343737) (mid 184.534462 100.299803) (end 184.640528 100.343737) (width 0.1) (layer "In5.Cu") (net 437))
  (arc (start 188.250877 104.530877) (mid 188.309785 104.673092) (end 188.452 104.732) (width 0.1) (layer "In5.Cu") (net 437))
  (segment (start 248.641999 95.068001) (end 249.023001 95.068001) (width 0.1) (layer "B.Cu") (net 437))
  (segment (start 248.46 95.25) (end 248.641999 95.068001) (width 0.1) (layer "B.Cu") (net 437))
  (segment (start 249.023001 95.068001) (end 249.095 95.14) (width 0.1) (layer "B.Cu") (net 437))
  (segment (start 249.095 95.14) (end 249.095 95.555) (width 0.1) (layer "B.Cu") (net 437))
  (segment (start 255.195 91.875) (end 255.492922 92.172922) (width 0.122) (layer "F.Cu") (net 438))
  (segment (start 255.953079 92.172921) (end 256.08 92.046) (width 0.122) (layer "F.Cu") (net 438))
  (segment (start 255.634343 92.2315) (end 255.811657 92.2315) (width 0.122) (layer "F.Cu") (net 438))
  (via (at 256.08 92.046) (size 0.5) (drill 0.2) (layers "F.Cu" "B.Cu") (net 438))
  (arc (start 255.492922 92.172922) (mid 255.557807 92.216276) (end 255.634343 92.2315) (width 0.122) (layer "F.Cu") (net 438))
  (arc (start 255.953079 92.172921) (mid 255.888194 92.216276) (end 255.811657 92.2315) (width 0.122) (layer "F.Cu") (net 438))
  (segment (start 256.669079 92.175921) (end 256.685711 92.159289) (width 0.122) (layer "B.Cu") (net 438))
  (segment (start 256.08 92.046) (end 256.209922 92.175922) (width 0.122) (layer "B.Cu") (net 438))
  (segment (start 256.351343 92.2345) (end 256.527657 92.2345) (width 0.122) (layer "B.Cu") (net 438))
  (segment (start 256.715 92.088579) (end 256.715 91.745) (width 0.122) (layer "B.Cu") (net 438))
  (arc (start 256.527657 92.2345) (mid 256.604194 92.219276) (end 256.669079 92.175921) (width 0.122) (layer "B.Cu") (net 438))
  (arc (start 256.351343 92.2345) (mid 256.274807 92.219276) (end 256.209922 92.175922) (width 0.122) (layer "B.Cu") (net 438))
  (arc (start 256.685711 92.159289) (mid 256.707388 92.126847) (end 256.715 92.088579) (width 0.122) (layer "B.Cu") (net 438))
  (segment (start 249.033406 93.773654) (end 250.468654 92.338406) (width 0.122) (layer "F.Cu") (net 439))
  (segment (start 196.706984 99.843016) (end 196.706984 99.840168) (width 0.1) (layer "F.Cu") (net 439))
  (segment (start 198.15 99.9265) (end 200.183453 99.9265) (width 0.122) (layer "F.Cu") (net 439))
  (segment (start 200.537007 99.780053) (end 204.055786 96.261274) (width 0.122) (layer "F.Cu") (net 439))
  (segment (start 248.419139 96.007921) (end 248.867922 95.559138) (width 0.122) (layer "F.Cu") (net 439))
  (segment (start 198.137774 99.938726) (end 198.15 99.9265) (width 0.1) (layer "F.Cu") (net 439))
  (segment (start 196.136328 99.560008) (end 195.885429 99.560008) (width 0.1) (layer "F.Cu") (net 439))
  (segment (start 253.927079 92.172921) (end 254.225 91.875) (width 0.122) (layer "F.Cu") (net 439))
  (segment (start 248.9265 95.417717) (end 248.9265 94.031748) (width 0.122) (layer "F.Cu") (net 439))
  (segment (start 195.731328 99.714109) (end 195.731328 99.810571) (width 0.1) (layer "F.Cu") (net 439))
  (segment (start 197.081984 99.968016) (end 198.067063 99.968016) (width 0.1) (layer "F.Cu") (net 439))
  (segment (start 195.814718 99.589298) (end 195.760617 99.643399) (width 0.1) (layer "F.Cu") (net 439))
  (segment (start 204.526012 96.0665) (end 248.277717 96.0665) (width 0.122) (layer "F.Cu") (net 439))
  (segment (start 195.888773 99.968016) (end 196.581984 99.968016) (width 0.1) (layer "F.Cu") (net 439))
  (segment (start 196.956984 99.840168) (end 196.956984 99.843016) (width 0.1) (layer "F.Cu") (net 439))
  (segment (start 250.726748 92.2315) (end 253.785657 92.2315) (width 0.122) (layer "F.Cu") (net 439))
  (segment (start 195.760618 99.881282) (end 195.818063 99.938727) (width 0.1) (layer "F.Cu") (net 439))
  (arc (start 195.818063 99.938727) (mid 195.850505 99.960404) (end 195.888773 99.968016) (width 0.1) (layer "F.Cu") (net 439))
  (arc (start 198.067063 99.968016) (mid 198.105332 99.960404) (end 198.137774 99.938726) (width 0.1) (layer "F.Cu") (net 439))
  (arc (start 250.468654 92.338406) (mid 250.587069 92.259284) (end 250.726748 92.2315) (width 0.122) (layer "F.Cu") (net 439))
  (arc (start 196.956984 99.843016) (mid 196.993596 99.931404) (end 197.081984 99.968016) (width 0.1) (layer "F.Cu") (net 439))
  (arc (start 200.183453 99.9265) (mid 200.374795 99.88844) (end 200.537007 99.780053) (width 0.122) (layer "F.Cu") (net 439))
  (arc (start 196.831984 99.715168) (mid 196.920372 99.75178) (end 196.956984 99.840168) (width 0.1) (layer "F.Cu") (net 439))
  (arc (start 196.706984 99.840168) (mid 196.743596 99.75178) (end 196.831984 99.715168) (width 0.1) (layer "F.Cu") (net 439))
  (arc (start 195.731328 99.810571) (mid 195.73894 99.84884) (end 195.760618 99.881282) (width 0.1) (layer "F.Cu") (net 439))
  (arc (start 248.9265 94.031748) (mid 248.954284 93.892069) (end 249.033406 93.773654) (width 0.122) (layer "F.Cu") (net 439))
  (arc (start 204.055786 96.261274) (mid 204.271528 96.11712) (end 204.526012 96.0665) (width 0.122) (layer "F.Cu") (net 439))
  (arc (start 248.867922 95.559138) (mid 248.911276 95.494253) (end 248.9265 95.417717) (width 0.122) (layer "F.Cu") (net 439))
  (arc (start 196.581984 99.968016) (mid 196.670372 99.931404) (end 196.706984 99.843016) (width 0.1) (layer "F.Cu") (net 439))
  (arc (start 248.277717 96.0665) (mid 248.354254 96.051276) (end 248.419139 96.007921) (width 0.122) (layer "F.Cu") (net 439))
  (arc (start 195.760617 99.643399) (mid 195.73894 99.675841) (end 195.731328 99.714109) (width 0.1) (layer "F.Cu") (net 439))
  (arc (start 253.927079 92.172921) (mid 253.862194 92.216276) (end 253.785657 92.2315) (width 0.122) (layer "F.Cu") (net 439))
  (arc (start 195.885429 99.560008) (mid 195.84716 99.56762) (end 195.814718 99.589298) (width 0.1) (layer "F.Cu") (net 439))
  (segment (start 255.947079 87.497079) (end 256.08 87.63) (width 0.122) (layer "F.Cu") (net 440))
  (segment (start 255.634343 87.4385) (end 255.805657 87.4385) (width 0.122) (layer "F.Cu") (net 440))
  (segment (start 255.195 87.795) (end 255.492922 87.497078) (width 0.122) (layer "F.Cu") (net 440))
  (via (at 256.08 87.63) (size 0.5) (drill 0.2) (layers "F.Cu" "B.Cu") (net 440))
  (arc (start 255.947079 87.497079) (mid 255.882194 87.453724) (end 255.805657 87.4385) (width 0.122) (layer "F.Cu") (net 440))
  (arc (start 255.634343 87.4385) (mid 255.557807 87.453724) (end 255.492922 87.497078) (width 0.122) (layer "F.Cu") (net 440))
  (segment (start 256.685079 87.500079) (end 256.685711 87.500711) (width 0.122) (layer "B.Cu") (net 440))
  (segment (start 256.715 87.571421) (end 256.715 87.935) (width 0.122) (layer "B.Cu") (net 440))
  (segment (start 256.351343 87.4415) (end 256.543657 87.4415) (width 0.122) (layer "B.Cu") (net 440))
  (segment (start 256.08 87.63) (end 256.209922 87.500078) (width 0.122) (layer "B.Cu") (net 440))
  (arc (start 256.715 87.571421) (mid 256.707388 87.533153) (end 256.685711 87.500711) (width 0.122) (layer "B.Cu") (net 440))
  (arc (start 256.543657 87.4415) (mid 256.620194 87.456724) (end 256.685079 87.500079) (width 0.122) (layer "B.Cu") (net 440))
  (arc (start 256.351343 87.4415) (mid 256.274807 87.456724) (end 256.209922 87.500078) (width 0.122) (layer "B.Cu") (net 440))
  (segment (start 181.136328 99.560008) (end 180.636328 99.060008) (width 0.1) (layer "F.Cu") (net 444))
  (via blind (at 180.636328 99.060008) (size 0.5) (drill 0.2) (layers "F.Cu" "In5.Cu") (net 444))
  (via (at 248.46 94.586) (size 0.5) (drill 0.2) (layers "F.Cu" "B.Cu") (net 444))
  (segment (start 192.45738 105.029754) (end 189.852 105.029754) (width 0.1) (layer "In5.Cu") (net 444))
  (segment (start 184.974 103.086134) (end 184.974 101.559134) (width 0.1) (layer "In5.Cu") (net 444))
  (segment (start 241.062134 96.9) (end 207.562134 96.9) (width 0.1) (layer "In5.Cu") (net 444))
  (segment (start 188.950877 104.35099) (end 188.950877 104.530877) (width 0.1) (layer "In5.Cu") (net 444))
  (segment (start 187.550877 104.35099) (end 187.550877 104.530877) (width 0.1) (layer "In5.Cu") (net 444))
  (segment (start 248.46 94.586) (end 248.641999 94.767999) (width 0.1) (layer "In5.Cu") (net 444))
  (segment (start 183.342933 99.913451) (end 183.342933 99.928067) (width 0.09) (layer "In5.Cu") (net 444))
  (segment (start 248.980133 94.767999) (end 249.55 95.337866) (width 0.1) (layer "In5.Cu") (net 444))
  (segment (start 245.037866 95.7) (end 242.262134 95.7) (width 0.1) (layer "In5.Cu") (net 444))
  (segment (start 187.052 105.029754) (end 186.51162 105.029754) (width 0.1) (layer "In5.Cu") (net 444))
  (segment (start 181.035 99.411422) (end 181.291578 99.668) (width 0.09) (layer "In5.Cu") (net 444))
  (segment (start 180.636328 99.060008) (end 180.973008 99.060008) (width 0.09) (layer "In5.Cu") (net 444))
  (segment (start 181.472713 99.665008) (end 181.884992 99.665008) (width 0.09) (layer "In5.Cu") (net 444))
  (segment (start 181.035 99.122) (end 181.035 99.411422) (width 0.09) (layer "In5.Cu") (net 444))
  (segment (start 187.953123 104.530877) (end 187.953123 104.35099) (width 0.1) (layer "In5.Cu") (net 444))
  (segment (start 189.353123 104.530877) (end 189.353123 104.35099) (width 0.1) (layer "In5.Cu") (net 444))
  (segment (start 207.562134 96.9) (end 200.337134 104.125) (width 0.1) (layer "In5.Cu") (net 444))
  (segment (start 245.337866 96) (end 245.037866 95.7) (width 0.1) (layer "In5.Cu") (net 444))
  (segment (start 181.469721 99.668) (end 181.472713 99.665008) (width 0.09) (layer "In5.Cu") (net 444))
  (segment (start 247.937866 96) (end 245.337866 96) (width 0.1) (layer "In5.Cu") (net 444))
  (segment (start 182.883496 100.215008) (end 182.883496 99.866504) (width 0.09) (layer "In5.Cu") (net 444))
  (segment (start 248.641999 94.767999) (end 248.980133 94.767999) (width 0.1) (layer "In5.Cu") (net 444))
  (segment (start 200.337134 104.125) (end 193.362134 104.125) (width 0.1) (layer "In5.Cu") (net 444))
  (segment (start 182.086488 99.866504) (end 182.086488 100.215008) (width 0.09) (layer "In5.Cu") (net 444))
  (segment (start 184.974 101.559134) (end 183.342933 99.928067) (width 0.1) (layer "In5.Cu") (net 444))
  (segment (start 249.55 95.862134) (end 249.062134 96.35) (width 0.1) (layer "In5.Cu") (net 444))
  (segment (start 186.142 104.254134) (end 184.974 103.086134) (width 0.1) (layer "In5.Cu") (net 444))
  (segment (start 180.973008 99.060008) (end 181.035 99.122) (width 0.09) (layer "In5.Cu") (net 444))
  (segment (start 242.262134 95.7) (end 241.062134 96.9) (width 0.1) (layer "In5.Cu") (net 444))
  (segment (start 249.55 95.337866) (end 249.55 95.862134) (width 0.1) (layer "In5.Cu") (net 444))
  (segment (start 183.084992 99.665008) (end 183.09449 99.665008) (width 0.09) (layer "In5.Cu") (net 444))
  (segment (start 186.51162 105.029754) (end 186.142 104.660134) (width 0.1) (layer "In5.Cu") (net 444))
  (segment (start 183.200556 99.708942) (end 183.298999 99.807385) (width 0.09) (layer "In5.Cu") (net 444))
  (segment (start 248.287866 96.35) (end 247.937866 96) (width 0.1) (layer "In5.Cu") (net 444))
  (segment (start 181.291578 99.668) (end 181.469721 99.668) (width 0.09) (layer "In5.Cu") (net 444))
  (segment (start 186.142 104.660134) (end 186.142 104.254134) (width 0.1) (layer "In5.Cu") (net 444))
  (segment (start 193.362134 104.125) (end 192.45738 105.029754) (width 0.1) (layer "In5.Cu") (net 444))
  (segment (start 249.062134 96.35) (end 248.287866 96.35) (width 0.1) (layer "In5.Cu") (net 444))
  (arc (start 188.452 105.029754) (mid 188.099241 104.883636) (end 187.953123 104.530877) (width 0.1) (layer "In5.Cu") (net 444))
  (arc (start 187.550877 104.530877) (mid 187.404759 104.883636) (end 187.052 105.029754) (width 0.1) (layer "In5.Cu") (net 444))
  (arc (start 182.484992 100.613512) (mid 182.766777 100.496793) (end 182.883496 100.215008) (width 0.09) (layer "In5.Cu") (net 444))
  (arc (start 189.353123 104.35099) (mid 189.294215 104.208775) (end 189.152 104.149867) (width 0.1) (layer "In5.Cu") (net 444))
  (arc (start 189.852 105.029754) (mid 189.499241 104.883636) (end 189.353123 104.530877) (width 0.1) (layer "In5.Cu") (net 444))
  (arc (start 183.298999 99.807385) (mid 183.331515 99.856048) (end 183.342933 99.913451) (width 0.09) (layer "In5.Cu") (net 444))
  (arc (start 182.086488 100.215008) (mid 182.203207 100.496793) (end 182.484992 100.613512) (width 0.09) (layer "In5.Cu") (net 444))
  (arc (start 183.09449 99.665008) (mid 183.151893 99.676426) (end 183.200556 99.708942) (width 0.09) (layer "In5.Cu") (net 444))
  (arc (start 182.883496 99.866504) (mid 182.942513 99.724025) (end 183.084992 99.665008) (width 0.09) (layer "In5.Cu") (net 444))
  (arc (start 189.152 104.149867) (mid 189.009785 104.208775) (end 188.950877 104.35099) (width 0.1) (layer "In5.Cu") (net 444))
  (arc (start 181.884992 99.665008) (mid 182.027471 99.724025) (end 182.086488 99.866504) (width 0.09) (layer "In5.Cu") (net 444))
  (arc (start 188.950877 104.530877) (mid 188.804759 104.883636) (end 188.452 105.029754) (width 0.1) (layer "In5.Cu") (net 444))
  (arc (start 187.953123 104.35099) (mid 187.894215 104.208775) (end 187.752 104.149867) (width 0.1) (layer "In5.Cu") (net 444))
  (arc (start 187.752 104.149867) (mid 187.609785 104.208775) (end 187.550877 104.35099) (width 0.1) (layer "In5.Cu") (net 444))
  (segment (start 248.641999 94.767999) (end 248.992001 94.767999) (width 0.1) (layer "B.Cu") (net 444))
  (segment (start 249.095 94.665) (end 249.095 94.285) (width 0.1) (layer "B.Cu") (net 444))
  (segment (start 248.46 94.586) (end 248.641999 94.767999) (width 0.1) (layer "B.Cu") (net 444))
  (segment (start 248.992001 94.767999) (end 249.095 94.665) (width 0.1) (layer "B.Cu") (net 444))
  (segment (start 179.136328 99.560008) (end 178.636328 100.060008) (width 0.1) (layer "F.Cu") (net 445))
  (via (at 178.636328 100.060008) (size 0.5) (drill 0.2) (layers "F.Cu" "B.Cu") (net 445))
  (via (at 244.65 100.936) (size 0.5) (drill 0.2) (layers "F.Cu" "B.Cu") (net 445))
  (segment (start 243.396 100.526) (end 243.216 100.526) (width 0.1) (layer "In7.Cu") (net 445))
  (segment (start 181.994105 101.792526) (end 181.994107 101.792528) (width 0.09) (layer "In7.Cu") (net 445))
  (segment (start 245.24 100.734204) (end 245.031796 100.526) (width 0.1) (layer "In7.Cu") (net 445))
  (segment (start 245.031796 100.526) (end 244.346 100.526) (width 0.1) (layer "In7.Cu") (net 445))
  (segment (start 180.767818 100.955146) (end 180.767817 100.955147) (width 0.09) (layer "In7.Cu") (net 445))
  (segment (start 182.035 102.846422) (end 183.211578 104.023) (width 0.09) (layer "In7.Cu") (net 445))
  (segment (start 183.211578 104.023) (end 198.027579 104.023) (width 0.09) (layer "In7.Cu") (net 445))
  (segment (start 182.070016 101.186284) (end 181.994103 101.262196) (width 0.09) (layer "In7.Cu") (net 445))
  (segment (start 180.44962 99.717711) (end 180.803172 99.364156) (width 0.09) (layer "In7.Cu") (net 445))
  (segment (start 182.070017 100.938798) (end 182.070015 100.938797) (width 0.09) (layer "In7.Cu") (net 445))
  (segment (start 243.016 100.726) (end 243.016 100.741318) (width 0.1) (layer "In7.Cu") (net 445))
  (segment (start 243.671 100.901) (end 243.671 100.751) (width 0.1) (layer "In7.Cu") (net 445))
  (segment (start 244.831999 101.117999) (end 245.065867 101.117999) (width 0.1) (layer "In7.Cu") (net 445))
  (segment (start 181.746619 101.014709) (end 181.822529 100.938798) (width 0.09) (layer "In7.Cu") (net 445))
  (segment (start 244.121 100.751) (end 244.121 100.901) (width 0.1) (layer "In7.Cu") (net 445))
  (segment (start 181.050659 99.611643) (end 180.237487 100.424817) (width 0.09) (layer "In7.Cu") (net 445))
  (segment (start 181.05066 99.364156) (end 181.05066 99.364157) (width 0.09) (layer "In7.Cu") (net 445))
  (segment (start 244.65 100.936) (end 244.831999 101.117999) (width 0.1) (layer "In7.Cu") (net 445))
  (segment (start 180.767817 100.955147) (end 180.838527 100.884436) (width 0.09) (layer "In7.Cu") (net 445))
  (segment (start 206.936134 100.526) (end 203.394134 104.068) (width 0.1) (layer "In7.Cu") (net 445))
  (segment (start 243.446 100.526) (end 243.396 100.526) (width 0.1) (layer "In7.Cu") (net 445))
  (segment (start 203.394134 104.068) (end 198.114 104.068) (width 0.1) (layer "In7.Cu") (net 445))
  (segment (start 181.050659 99.611644) (end 181.050659 99.611643) (width 0.09) (layer "In7.Cu") (net 445))
  (segment (start 178.636328 100.060008) (end 178.636328 99.763672) (width 0.09) (layer "In7.Cu") (net 445))
  (segment (start 181.086015 100.884436) (end 181.216289 101.01471) (width 0.09) (layer "In7.Cu") (net 445))
  (segment (start 181.216289 101.01471) (end 181.216289 101.014711) (width 0.09) (layer "In7.Cu") (net 445))
  (segment (start 198.09829 104.05229) (end 198.114 104.068) (width 0.09) (layer "In7.Cu") (net 445))
  (segment (start 179.861586 99.660008) (end 179.919288 99.717709) (width 0.09) (layer "In7.Cu") (net 445))
  (segment (start 178.636328 99.763672) (end 178.739992 99.660008) (width 0.09) (layer "In7.Cu") (net 445))
  (segment (start 245.24 100.943866) (end 245.24 100.734204) (width 0.1) (layer "In7.Cu") (net 445))
  (segment (start 242.416 100.526) (end 206.936134 100.526) (width 0.1) (layer "In7.Cu") (net 445))
  (segment (start 182.035 101.833422) (end 182.035 102.846422) (width 0.09) (layer "In7.Cu") (net 445))
  (segment (start 245.065867 101.117999) (end 245.24 100.943866) (width 0.1) (layer "In7.Cu") (net 445))
  (segment (start 178.739992 99.660008) (end 179.861586 99.660008) (width 0.09) (layer "In7.Cu") (net 445))
  (segment (start 242.616 100.741318) (end 242.616 100.726) (width 0.1) (layer "In7.Cu") (net 445))
  (segment (start 181.994107 101.792528) (end 182.035 101.833422) (width 0.09) (layer "In7.Cu") (net 445))
  (arc (start 179.919288 99.717709) (mid 180.184455 99.827546) (end 180.44962 99.717711) (width 0.09) (layer "In7.Cu") (net 445))
  (arc (start 242.816 100.941318) (mid 242.674579 100.882739) (end 242.616 100.741318) (width 0.1) (layer "In7.Cu") (net 445))
  (arc (start 242.616 100.726) (mid 242.557421 100.584579) (end 242.416 100.526) (width 0.1) (layer "In7.Cu") (net 445))
  (arc (start 243.216 100.526) (mid 243.074579 100.584579) (end 243.016 100.726) (width 0.1) (layer "In7.Cu") (net 445))
  (arc (start 180.237487 100.955147) (mid 180.502653 101.064982) (end 180.767818 100.955146) (width 0.09) (layer "In7.Cu") (net 445))
  (arc (start 182.070015 100.938797) (mid 182.121273 101.062541) (end 182.070016 101.186284) (width 0.09) (layer "In7.Cu") (net 445))
  (arc (start 180.803172 99.364156) (mid 180.926916 99.3129) (end 181.05066 99.364156) (width 0.09) (layer "In7.Cu") (net 445))
  (arc (start 244.121 100.901) (mid 244.055099 101.060099) (end 243.896 101.126) (width 0.1) (layer "In7.Cu") (net 445))
  (arc (start 243.016 100.741318) (mid 242.957421 100.882739) (end 242.816 100.941318) (width 0.1) (layer "In7.Cu") (net 445))
  (arc (start 181.216289 101.014711) (mid 181.481454 101.124544) (end 181.746619 101.014709) (width 0.09) (layer "In7.Cu") (net 445))
  (arc (start 243.896 101.126) (mid 243.736901 101.060099) (end 243.671 100.901) (width 0.1) (layer "In7.Cu") (net 445))
  (arc (start 180.838527 100.884436) (mid 180.962271 100.83318) (end 181.086015 100.884436) (width 0.09) (layer "In7.Cu") (net 445))
  (arc (start 198.027579 104.023) (mid 198.065848 104.030612) (end 198.09829 104.05229) (width 0.09) (layer "In7.Cu") (net 445))
  (arc (start 244.346 100.526) (mid 244.186901 100.591901) (end 244.121 100.751) (width 0.1) (layer "In7.Cu") (net 445))
  (arc (start 181.822529 100.938798) (mid 181.946273 100.887542) (end 182.070017 100.938798) (width 0.09) (layer "In7.Cu") (net 445))
  (arc (start 181.05066 99.364157) (mid 181.101916 99.487901) (end 181.050659 99.611644) (width 0.09) (layer "In7.Cu") (net 445))
  (arc (start 181.994103 101.262196) (mid 181.884268 101.527361) (end 181.994105 101.792526) (width 0.09) (layer "In7.Cu") (net 445))
  (arc (start 243.671 100.751) (mid 243.605099 100.591901) (end 243.446 100.526) (width 0.1) (layer "In7.Cu") (net 445))
  (arc (start 180.237487 100.424817) (mid 180.127652 100.689982) (end 180.237487 100.955147) (width 0.09) (layer "In7.Cu") (net 445))
  (segment (start 244.65 100.936) (end 244.831999 101.117999) (width 0.1) (layer "B.Cu") (net 445))
  (segment (start 245.285 101.015) (end 245.285 100.635) (width 0.1) (layer "B.Cu") (net 445))
  (segment (start 245.182001 101.117999) (end 245.285 101.015) (width 0.1) (layer "B.Cu") (net 445))
  (segment (start 244.831999 101.117999) (end 245.182001 101.117999) (width 0.1) (layer "B.Cu") (net 445))
  (segment (start 182.136328 98.560008) (end 182.636328 98.060008) (width 0.1) (layer "F.Cu") (net 448))
  (via blind (at 182.636328 98.060008) (size 0.5) (drill 0.2) (layers "F.Cu" "In5.Cu") (net 448))
  (via (at 247.19 93.98) (size 0.5) (drill 0.2) (layers "F.Cu" "B.Cu") (net 448))
  (segment (start 199.807561 102.880302) (end 199.807562 102.880304) (width 0.1) (layer "In5.Cu") (net 448))
  (segment (start 188.19 101.86) (end 188.24 101.86) (width 0.09) (layer "In5.Cu") (net 448))
  (segment (start 247.764133 93.798001) (end 248.06 93.502134) (width 0.1) (layer "In5.Cu") (net 448))
  (segment (start 182.374422 98.468) (end 182.386905 98.468) (width 0.09) (layer "In5.Cu") (net 448))
  (segment (start 183.482732 98.465027) (end 183.598853 98.581148) (width 0.09) (layer "In5.Cu") (net 448))
  (segment (start 182.235 98.137) (end 182.235 98.328578) (width 0.09) (layer "In5.Cu") (net 448))
  (segment (start 248.06 93.502134) (end 248.06 92.977866) (width 0.1) (layer "In5.Cu") (net 448))
  (segment (start 183.598851 98.970042) (end 183.528148 99.040744) (width 0.09) (layer "In5.Cu") (net 448))
  (segment (start 242.650019 93.361773) (end 242.650019 93.587847) (width 0.1) (layer "In5.Cu") (net 448))
  (segment (start 182.636328 98.060008) (end 182.311992 98.060008) (width 0.09) (layer "In5.Cu") (net 448))
  (segment (start 199.807562 102.880304) (end 199.777506 102.91036) (width 0.1) (layer "In5.Cu") (net 448))
  (segment (start 189.165 102.835) (end 189.165 102.985) (width 0.09) (layer "In5.Cu") (net 448))
  (segment (start 244.998153 92.596019) (end 243.415773 92.596019) (width 0.1) (layer "In5.Cu") (net 448))
  (segment (start 200.99 101.047866) (end 200.99 101.697866) (width 0.1) (layer "In5.Cu") (net 448))
  (segment (start 186.36 101.491751) (end 185.851371 102.000379) (width 0.09) (layer "In5.Cu") (net 448))
  (segment (start 183.528147 99.146825) (end 183.528148 99.146826) (width 0.09) (layer "In5.Cu") (net 448))
  (segment (start 186.36 101.023348) (end 186.36 101.491751) (width 0.09) (layer "In5.Cu") (net 448))
  (segment (start 185.472713 100.455008) (end 185.79166 100.455008) (width 0.09) (layer "In5.Cu") (net 448))
  (segment (start 247.19 93.98) (end 247.371999 93.798001) (width 0.1) (layer "In5.Cu") (net 448))
  (segment (start 190.631422 102.46) (end 191.121054 102.949632) (width 0.09) (layer "In5.Cu") (net 448))
  (segment (start 200.99 101.697866) (end 200.938933 101.748933) (width 0.1) (layer "In5.Cu") (net 448))
  (segment (start 242.650019 93.587847) (end 240.637866 95.6) (width 0.1) (layer "In5.Cu") (net 448))
  (segment (start 183.77565 99.288247) (end 183.846352 99.217544) (width 0.09) (layer "In5.Cu") (net 448))
  (segment (start 189.515 102.985) (end 189.515 102.835) (width 0.09) (layer "In5.Cu") (net 448))
  (segment (start 187.159518 102.1418) (end 187.477719 102.46) (width 0.09) (layer "In5.Cu") (net 448))
  (segment (start 247.652134 92.57) (end 246.777866 92.57) (width 0.1) (layer "In5.Cu") (net 448))
  (segment (start 185.186669 100.168964) (end 185.472713 100.455008) (width 0.09) (layer "In5.Cu") (net 448))
  (segment (start 182.235 98.328578) (end 182.374422 98.468) (width 0.09) (layer "In5.Cu") (net 448))
  (segment (start 206.437866 95.6) (end 200.99 101.047866) (width 0.1) (layer "In5.Cu") (net 448))
  (segment (start 186.240279 102.389288) (end 186.487766 102.1418) (width 0.09) (layer "In5.Cu") (net 448))
  (segment (start 185.257372 99.850759) (end 185.257374 99.85076) (width 0.09) (layer "In5.Cu") (net 448))
  (segment (start 182.311992 98.060008) (end 182.235 98.137) (width 0.09) (layer "In5.Cu") (net 448))
  (segment (start 248.06 92.977866) (end 247.652134 92.57) (width 0.1) (layer "In5.Cu") (net 448))
  (segment (start 184.656355 99.391149) (end 184.727057 99.320444) (width 0.09) (layer "In5.Cu") (net 448))
  (segment (start 182.386905 98.468) (end 182.389878 98.465027) (width 0.09) (layer "In5.Cu") (net 448))
  (segment (start 184.235245 99.217543) (end 184.235246 99.217544) (width 0.09) (layer "In5.Cu") (net 448))
  (segment (start 246.777866 92.57) (end 246.407866 92.94) (width 0.1) (layer "In5.Cu") (net 448))
  (segment (start 184.235246 99.217544) (end 184.408851 99.391147) (width 0.09) (layer "In5.Cu") (net 448))
  (segment (start 188.59 102.21) (end 188.59 102.31) (width 0.09) (layer "In5.Cu") (net 448))
  (segment (start 247.371999 93.798001) (end 247.764133 93.798001) (width 0.1) (layer "In5.Cu") (net 448))
  (segment (start 183.775651 99.288247) (end 183.77565 99.288247) (width 0.09) (layer "In5.Cu") (net 448))
  (segment (start 187.477719 102.46) (end 187.69 102.46) (width 0.09) (layer "In5.Cu") (net 448))
  (segment (start 200.585381 101.748933) (end 200.395846 101.559398) (width 0.1) (layer "In5.Cu") (net 448))
  (segment (start 182.389878 98.465027) (end 183.482732 98.465027) (width 0.09) (layer "In5.Cu") (net 448))
  (segment (start 199.618027 102.337216) (end 199.807561 102.52675) (width 0.1) (layer "In5.Cu") (net 448))
  (segment (start 183.528148 99.146826) (end 183.669569 99.288247) (width 0.09) (layer "In5.Cu") (net 448))
  (segment (start 246.407866 92.94) (end 245.342134 92.94) (width 0.1) (layer "In5.Cu") (net 448))
  (segment (start 245.342134 92.94) (end 244.998153 92.596019) (width 0.1) (layer "In5.Cu") (net 448))
  (segment (start 199.777506 102.91036) (end 191.921194 102.91036) (width 0.1) (layer "In5.Cu") (net 448))
  (segment (start 189.89 102.46) (end 190.631422 102.46) (width 0.09) (layer "In5.Cu") (net 448))
  (segment (start 240.637866 95.6) (end 206.437866 95.6) (width 0.1) (layer "In5.Cu") (net 448))
  (segment (start 243.415773 92.596019) (end 242.650019 93.361773) (width 0.1) (layer "In5.Cu") (net 448))
  (segment (start 191.911212 102.920342) (end 191.921194 102.91036) (width 0.09) (layer "In5.Cu") (net 448))
  (segment (start 188.74 102.46) (end 188.79 102.46) (width 0.09) (layer "In5.Cu") (net 448))
  (segment (start 183.598851 98.970041) (end 183.598851 98.970042) (width 0.09) (layer "In5.Cu") (net 448))
  (segment (start 186.24028 102.389287) (end 186.240279 102.389288) (width 0.09) (layer "In5.Cu") (net 448))
  (segment (start 183.598853 98.581148) (end 183.598851 98.581149) (width 0.09) (layer "In5.Cu") (net 448))
  (segment (start 185.257374 99.85076) (end 185.186669 99.921462) (width 0.09) (layer "In5.Cu") (net 448))
  (segment (start 185.79166 100.455008) (end 186.36 101.023348) (width 0.09) (layer "In5.Cu") (net 448))
  (segment (start 191.121054 102.949632) (end 191.840501 102.949632) (width 0.09) (layer "In5.Cu") (net 448))
  (segment (start 185.851371 102.389287) (end 185.851371 102.389288) (width 0.09) (layer "In5.Cu") (net 448))
  (segment (start 199.618027 101.559399) (end 199.618027 101.559398) (width 0.1) (layer "In5.Cu") (net 448))
  (segment (start 187.84 102.31) (end 187.84 102.21) (width 0.09) (layer "In5.Cu") (net 448))
  (arc (start 187.84 102.21) (mid 187.942513 101.962513) (end 188.19 101.86) (width 0.09) (layer "In5.Cu") (net 448))
  (arc (start 200.938933 101.748933) (mid 200.762157 101.822156) (end 200.585381 101.748933) (width 0.1) (layer "In5.Cu") (net 448))
  (arc (start 186.487766 102.1418) (mid 186.823642 102.002676) (end 187.159518 102.1418) (width 0.09) (layer "In5.Cu") (net 448))
  (arc (start 188.59 102.31) (mid 188.633934 102.416066) (end 188.74 102.46) (width 0.09) (layer "In5.Cu") (net 448))
  (arc (start 183.598851 98.581149) (mid 183.679393 98.775595) (end 183.598851 98.970041) (width 0.09) (layer "In5.Cu") (net 448))
  (arc (start 189.165 102.985) (mid 189.216256 103.108744) (end 189.34 103.16) (width 0.09) (layer "In5.Cu") (net 448))
  (arc (start 187.69 102.46) (mid 187.796066 102.416066) (end 187.84 102.31) (width 0.09) (layer "In5.Cu") (net 448))
  (arc (start 183.846352 99.217544) (mid 184.040798 99.137001) (end 184.235245 99.217543) (width 0.09) (layer "In5.Cu") (net 448))
  (arc (start 184.727057 99.320444) (mid 184.992215 99.210612) (end 185.257373 99.320444) (width 0.09) (layer "In5.Cu") (net 448))
  (arc (start 185.186669 99.921462) (mid 185.13541 100.045213) (end 185.186669 100.168964) (width 0.09) (layer "In5.Cu") (net 448))
  (arc (start 189.515 102.835) (mid 189.624835 102.569835) (end 189.89 102.46) (width 0.09) (layer "In5.Cu") (net 448))
  (arc (start 185.851371 102.389288) (mid 186.045826 102.469833) (end 186.24028 102.389287) (width 0.09) (layer "In5.Cu") (net 448))
  (arc (start 185.851371 102.000379) (mid 185.770826 102.194833) (end 185.851371 102.389287) (width 0.09) (layer "In5.Cu") (net 448))
  (arc (start 183.669569 99.288247) (mid 183.72261 99.310217) (end 183.775651 99.288247) (width 0.09) (layer "In5.Cu") (net 448))
  (arc (start 191.840501 102.949632) (mid 191.87877 102.94202) (end 191.911212 102.920342) (width 0.09) (layer "In5.Cu") (net 448))
  (arc (start 200.395846 101.559398) (mid 200.006936 101.398307) (end 199.618027 101.559399) (width 0.1) (layer "In5.Cu") (net 448))
  (arc (start 183.528148 99.040744) (mid 183.506177 99.093784) (end 183.528147 99.146825) (width 0.09) (layer "In5.Cu") (net 448))
  (arc (start 188.24 101.86) (mid 188.487487 101.962513) (end 188.59 102.21) (width 0.09) (layer "In5.Cu") (net 448))
  (arc (start 184.408851 99.391147) (mid 184.532604 99.442408) (end 184.656355 99.391149) (width 0.09) (layer "In5.Cu") (net 448))
  (arc (start 199.807561 102.52675) (mid 199.880784 102.703526) (end 199.807561 102.880302) (width 0.1) (layer "In5.Cu") (net 448))
  (arc (start 188.79 102.46) (mid 189.055165 102.569835) (end 189.165 102.835) (width 0.09) (layer "In5.Cu") (net 448))
  (arc (start 199.618027 101.559398) (mid 199.456936 101.948307) (end 199.618027 102.337216) (width 0.1) (layer "In5.Cu") (net 448))
  (arc (start 185.257373 99.320444) (mid 185.367205 99.585603) (end 185.257372 99.850759) (width 0.09) (layer "In5.Cu") (net 448))
  (arc (start 189.34 103.16) (mid 189.463744 103.108744) (end 189.515 102.985) (width 0.09) (layer "In5.Cu") (net 448))
  (segment (start 247.825 93.87) (end 247.825 94.285) (width 0.1) (layer "B.Cu") (net 448))
  (segment (start 247.371999 93.798001) (end 247.753001 93.798001) (width 0.1) (layer "B.Cu") (net 448))
  (segment (start 247.753001 93.798001) (end 247.825 93.87) (width 0.1) (layer "B.Cu") (net 448))
  (segment (start 247.19 93.98) (end 247.371999 93.798001) (width 0.1) (layer "B.Cu") (net 448))
  (segment (start 173.136328 97.536328) (end 172.65 97.05) (width 0.127) (layer "F.Cu") (net 449))
  (segment (start 173.136328 97.560008) (end 173.136328 97.536328) (width 0.127) (layer "F.Cu") (net 449))
  (via (at 172.65 97.05) (size 0.5) (drill 0.2) (layers "F.Cu" "B.Cu") (net 449))
  (segment (start 221.15 126.15) (end 221.4 125.9) (width 0.1) (layer "B.Cu") (net 449))
  (segment (start 221.95 113.15) (end 218.45 113.15) (width 0.1) (layer "B.Cu") (net 449))
  (segment (start 221.15 130.625) (end 221.15 126.15) (width 0.1) (layer "B.Cu") (net 449))
  (segment (start 247.94 127.311544) (end 247.301544 127.95) (width 0.1) (layer "B.Cu") (net 449))
  (segment (start 255.3 125.35) (end 253.7 125.35) (width 0.1) (layer "B.Cu") (net 449))
  (segment (start 177.05 106.3) (end 173.2 102.45) (width 0.1) (layer "B.Cu") (net 449))
  (segment (start 253.7 125.35) (end 252.9 126.15) (width 0.1) (layer "B.Cu") (net 449))
  (segment (start 173.2 102.45) (end 173.2 100.072136) (width 0.1) (layer "B.Cu") (net 449))
  (segment (start 173.2 100.072136) (end 172.797872 99.670008) (width 0.1) (layer "B.Cu") (net 449))
  (segment (start 217.5 112.2) (end 214.75 112.2) (width 0.1) (layer "B.Cu") (net 449))
  (segment (start 244.7 127.95) (end 243.45 129.2) (width 0.1) (layer "B.Cu") (net 449))
  (segment (start 221.4 125.525) (end 226.35 120.575) (width 0.1) (layer "B.Cu") (net 449))
  (segment (start 172.246328 98.88426) (end 172.6 98.530588) (width 0.1) (layer "B.Cu") (net 449))
  (segment (start 247.301544 127.95) (end 244.7 127.95) (width 0.1) (layer "B.Cu") (net 449))
  (segment (start 210.5 107.95) (end 187.55 107.95) (width 0.1) (layer "B.Cu") (net 449))
  (segment (start 242.3 132.6) (end 240.449998 132.6) (width 0.1) (layer "B.Cu") (net 449))
  (segment (start 240.099999 132.949999) (end 223.474999 132.949999) (width 0.1) (layer "B.Cu") (net 449))
  (segment (start 243.45 131.45) (end 242.3 132.6) (width 0.1) (layer "B.Cu") (net 449))
  (segment (start 214.75 112.2) (end 210.5 107.95) (width 0.1) (layer "B.Cu") (net 449))
  (segment (start 226.35 120.575) (end 226.35 117.55) (width 0.1) (layer "B.Cu") (net 449))
  (segment (start 223.474999 132.949999) (end 221.15 130.625) (width 0.1) (layer "B.Cu") (net 449))
  (segment (start 172.6 97.1) (end 172.65 97.05) (width 0.1) (layer "B.Cu") (net 449))
  (segment (start 255.445 124.765) (end 255.445 125.205) (width 0.1) (layer "B.Cu") (net 449))
  (segment (start 185.9 106.3) (end 177.05 106.3) (width 0.1) (layer "B.Cu") (net 449))
  (segment (start 218.45 113.15) (end 217.5 112.2) (width 0.1) (layer "B.Cu") (net 449))
  (segment (start 172.570008 99.670008) (end 172.246328 99.346328) (width 0.1) (layer "B.Cu") (net 449))
  (segment (start 172.246328 99.346328) (end 172.246328 98.88426) (width 0.1) (layer "B.Cu") (net 449))
  (segment (start 172.797872 99.670008) (end 172.570008 99.670008) (width 0.1) (layer "B.Cu") (net 449))
  (segment (start 247.94 127.11) (end 247.94 127.311544) (width 0.1) (layer "B.Cu") (net 449))
  (segment (start 252.9 126.15) (end 248.9 126.15) (width 0.1) (layer "B.Cu") (net 449))
  (segment (start 226.35 117.55) (end 221.95 113.15) (width 0.1) (layer "B.Cu") (net 449))
  (segment (start 221.4 125.9) (end 221.4 125.525) (width 0.1) (layer "B.Cu") (net 449))
  (segment (start 248.9 126.15) (end 247.94 127.11) (width 0.1) (layer "B.Cu") (net 449))
  (segment (start 243.45 129.2) (end 243.45 131.45) (width 0.1) (layer "B.Cu") (net 449))
  (segment (start 240.449998 132.6) (end 240.099999 132.949999) (width 0.1) (layer "B.Cu") (net 449))
  (segment (start 255.445 125.205) (end 255.3 125.35) (width 0.1) (layer "B.Cu") (net 449))
  (segment (start 187.55 107.95) (end 185.9 106.3) (width 0.1) (layer "B.Cu") (net 449))
  (segment (start 172.6 98.530588) (end 172.6 97.1) (width 0.1) (layer "B.Cu") (net 449))
  (segment (start 243.182385 93.190555) (end 241.63066 94.74228) (width 0.122) (layer "F.Cu") (net 450))
  (segment (start 246.952895 92.865484) (end 246.78988 93.028499) (width 0.122) (layer "F.Cu") (net 450))
  (segment (start 249.136594 91.987612) (end 248.424206 92.7) (width 0.122) (layer "F.Cu") (net 450))
  (segment (start 244.745684 92.806906) (end 244.554316 92.806906) (width 0.122) (layer "F.Cu") (net 450))
  (segment (start 248.166112 92.806906) (end 247.094316 92.806906) (width 0.122) (layer "F.Cu") (net 450))
  (segment (start 203.062994 95.229946) (end 200.313503 97.979437) (width 0.122) (layer "F.Cu") (net 450))
  (segment (start 240.806881 95.0835) (end 203.416547 95.0835) (width 0.122) (layer "F.Cu") (net 450))
  (segment (start 249.2435 89.062283) (end 249.2435 91.729518) (width 0.122) (layer "F.Cu") (net 450))
  (segment (start 195.445282 97.589298) (end 195.512039 97.656055) (width 0.1) (layer "F.Cu") (net 450))
  (segment (start 250.725862 87.497078) (end 249.302078 88.920862) (width 0.122) (layer "F.Cu") (net 450))
  (segment (start 246.531786 93.135406) (end 245.308214 93.135406) (width 0.122) (layer "F.Cu") (net 450))
  (segment (start 253.785657 87.4385) (end 250.867283 87.4385) (width 0.122) (layer "F.Cu") (net 450))
  (segment (start 243.995215 93.131976) (end 243.323807 93.131976) (width 0.122) (layer "F.Cu") (net 450))
  (segment (start 195.136328 97.560008) (end 195.374571 97.560008) (width 0.1) (layer "F.Cu") (net 450))
  (segment (start 199.772567 98.2035) (end 198.15 98.2035) (width 0.122) (layer "F.Cu") (net 450))
  (segment (start 244.412895 92.865484) (end 244.253309 93.02507) (width 0.122) (layer "F.Cu") (net 450))
  (segment (start 245.05012 93.028499) (end 244.887106 92.865485) (width 0.122) (layer "F.Cu") (net 450))
  (segment (start 195.541328 97.726765) (end 195.541328 97.851995) (width 0.1) (layer "F.Cu") (net 450))
  (segment (start 198.14845 98.20195) (end 198.15 98.2035) (width 0.1) (layer "F.Cu") (net 450))
  (segment (start 254.225 87.795) (end 253.927078 87.497078) (width 0.122) (layer "F.Cu") (net 450))
  (segment (start 195.596978 97.986346) (end 195.712999 98.102367) (width 0.1) (layer "F.Cu") (net 450))
  (segment (start 195.847349 98.158016) (end 198.042384 98.158016) (width 0.1) (layer "F.Cu") (net 450))
  (arc (start 195.541328 97.726765) (mid 195.533716 97.688497) (end 195.512039 97.656055) (width 0.1) (layer "F.Cu") (net 450))
  (arc (start 253.785657 87.4385) (mid 253.862193 87.453724) (end 253.927078 87.497078) (width 0.122) (layer "F.Cu") (net 450))
  (arc (start 195.847349 98.158016) (mid 195.774639 98.143553) (end 195.712999 98.102367) (width 0.1) (layer "F.Cu") (net 450))
  (arc (start 246.78988 93.028499) (mid 246.671466 93.107622) (end 246.531786 93.135406) (width 0.122) (layer "F.Cu") (net 450))
  (arc (start 244.887106 92.865485) (mid 244.822221 92.82213) (end 244.745684 92.806906) (width 0.122) (layer "F.Cu") (net 450))
  (arc (start 198.042384 98.158016) (mid 198.099787 98.169434) (end 198.14845 98.20195) (width 0.1) (layer "F.Cu") (net 450))
  (arc (start 247.094316 92.806906) (mid 247.01778 92.82213) (end 246.952895 92.865484) (width 0.122) (layer "F.Cu") (net 450))
  (arc (start 249.2435 91.729518) (mid 249.215716 91.869197) (end 249.136594 91.987612) (width 0.122) (layer "F.Cu") (net 450))
  (arc (start 240.806881 95.0835) (mid 241.252707 94.99482) (end 241.63066 94.74228) (width 0.122) (layer "F.Cu") (net 450))
  (arc (start 243.995215 93.131976) (mid 244.134894 93.104192) (end 244.253309 93.02507) (width 0.122) (layer "F.Cu") (net 450))
  (arc (start 195.541328 97.851995) (mid 195.555791 97.924705) (end 195.596978 97.986346) (width 0.1) (layer "F.Cu") (net 450))
  (arc (start 244.554316 92.806906) (mid 244.47778 92.82213) (end 244.412895 92.865484) (width 0.122) (layer "F.Cu") (net 450))
  (arc (start 245.308214 93.135406) (mid 245.168534 93.107622) (end 245.05012 93.028499) (width 0.122) (layer "F.Cu") (net 450))
  (arc (start 250.867283 87.4385) (mid 250.790747 87.453724) (end 250.725862 87.497078) (width 0.122) (layer "F.Cu") (net 450))
  (arc (start 249.2435 89.062283) (mid 249.258724 88.985747) (end 249.302078 88.920862) (width 0.122) (layer "F.Cu") (net 450))
  (arc (start 243.323807 93.131976) (mid 243.24727 93.1472) (end 243.182385 93.190555) (width 0.122) (layer "F.Cu") (net 450))
  (arc (start 195.445282 97.589298) (mid 195.41284 97.56762) (end 195.374571 97.560008) (width 0.1) (layer "F.Cu") (net 450))
  (arc (start 203.416547 95.0835) (mid 203.225206 95.12156) (end 203.062994 95.229946) (width 0.122) (layer "F.Cu") (net 450))
  (arc (start 200.313503 97.979437) (mid 200.065319 98.145268) (end 199.772567 98.2035) (width 0.122) (layer "F.Cu") (net 450))
  (arc (start 248.166112 92.806906) (mid 248.305791 92.779122) (end 248.424206 92.7) (width 0.122) (layer "F.Cu") (net 450))
  (segment (start 255.953079 87.092921) (end 256.08 86.966) (width 0.122) (layer "F.Cu") (net 451))
  (segment (start 255.634343 87.1515) (end 255.811657 87.1515) (width 0.122) (layer "F.Cu") (net 451))
  (segment (start 255.195 86.795) (end 255.492922 87.092922) (width 0.122) (layer "F.Cu") (net 451))
  (via (at 256.08 86.966) (size 0.5) (drill 0.2) (layers "F.Cu" "B.Cu") (net 451))
  (arc (start 255.634343 87.1515) (mid 255.557807 87.136276) (end 255.492922 87.092922) (width 0.122) (layer "F.Cu") (net 451))
  (arc (start 255.953079 87.092921) (mid 255.888194 87.136276) (end 255.811657 87.1515) (width 0.122) (layer "F.Cu") (net 451))
  (segment (start 256.715 87.008579) (end 256.715 86.665) (width 0.122) (layer "B.Cu") (net 451))
  (segment (start 256.351343 87.1545) (end 256.527657 87.1545) (width 0.122) (layer "B.Cu") (net 451))
  (segment (start 256.669079 87.095921) (end 256.685711 87.079289) (width 0.122) (layer "B.Cu") (net 451))
  (segment (start 256.08 86.966) (end 256.209922 87.095922) (width 0.122) (layer "B.Cu") (net 451))
  (arc (start 256.351343 87.1545) (mid 256.274807 87.139276) (end 256.209922 87.095922) (width 0.122) (layer "B.Cu") (net 451))
  (arc (start 256.527657 87.1545) (mid 256.604194 87.139276) (end 256.669079 87.095921) (width 0.122) (layer "B.Cu") (net 451))
  (arc (start 256.685711 87.079289) (mid 256.707388 87.046847) (end 256.715 87.008579) (width 0.122) (layer "B.Cu") (net 451))
  (segment (start 181.136328 98.560008) (end 181.636328 98.060008) (width 0.1) (layer "F.Cu") (net 456))
  (via blind (at 181.636328 98.060008) (size 0.5) (drill 0.2) (layers "F.Cu" "In5.Cu") (net 456))
  (via (at 247.19 93.316) (size 0.5) (drill 0.2) (layers "F.Cu" "B.Cu") (net 456))
  (segment (start 245.217866 93.24) (end 244.873866 92.896) (width 0.1) (layer "In5.Cu") (net 456))
  (segment (start 247.527866 92.87) (end 246.902134 92.87) (width 0.1) (layer "In5.Cu") (net 456))
  (segment (start 185.115965 99.709352) (end 185.115967 99.709353) (width 0.09) (layer "In5.Cu") (net 456))
  (segment (start 185.389878 100.654989) (end 185.708797 100.654989) (width 0.09) (layer "In5.Cu") (net 456))
  (segment (start 199.83016 102.125081) (end 199.83016 102.125082) (width 0.1) (layer "In5.Cu") (net 456))
  (segment (start 201.29 101.822134) (end 201.151066 101.961066) (width 0.1) (layer "In5.Cu") (net 456))
  (segment (start 188.39 102.21) (end 188.39 102.31) (width 0.09) (layer "In5.Cu") (net 456))
  (segment (start 185.708797 100.654989) (end 185.756904 100.703096) (width 0.09) (layer "In5.Cu") (net 456))
  (segment (start 185.756904 100.879872) (end 185.667582 100.969193) (width 0.09) (layer "In5.Cu") (net 456))
  (segment (start 200.373247 101.961066) (end 200.183712 101.771531) (width 0.1) (layer "In5.Cu") (net 456))
  (segment (start 243.54003 92.896) (end 242.95 93.48603) (width 0.1) (layer "In5.Cu") (net 456))
  (segment (start 186.381701 102.530708) (end 186.381701 102.530709) (width 0.09) (layer "In5.Cu") (net 456))
  (segment (start 206.562134 95.9) (end 201.29 101.172134) (width 0.1) (layer "In5.Cu") (net 456))
  (segment (start 200.019695 103.092437) (end 199.901774 103.21036) (width 0.1) (layer "In5.Cu") (net 456))
  (segment (start 246.902134 92.87) (end 246.532134 93.24) (width 0.1) (layer "In5.Cu") (net 456))
  (segment (start 185.756903 100.879873) (end 185.756904 100.879872) (width 0.09) (layer "In5.Cu") (net 456))
  (segment (start 181.636328 98.060008) (end 181.973008 98.060008) (width 0.09) (layer "In5.Cu") (net 456))
  (segment (start 186.381701 102.530709) (end 186.629188 102.283221) (width 0.09) (layer "In5.Cu") (net 456))
  (segment (start 242.95 93.48603) (end 242.95 93.712134) (width 0.1) (layer "In5.Cu") (net 456))
  (segment (start 190.548578 102.66) (end 191.03821 103.149632) (width 0.09) (layer "In5.Cu") (net 456))
  (segment (start 188.965 102.835) (end 188.965 102.985) (width 0.09) (layer "In5.Cu") (net 456))
  (segment (start 182.035 98.411422) (end 182.291578 98.668) (width 0.09) (layer "In5.Cu") (net 456))
  (segment (start 186.110456 101.056648) (end 186.16 101.106192) (width 0.09) (layer "In5.Cu") (net 456))
  (segment (start 188.19 102.06) (end 188.24 102.06) (width 0.09) (layer "In5.Cu") (net 456))
  (segment (start 201.29 101.172134) (end 201.29 101.822134) (width 0.1) (layer "In5.Cu") (net 456))
  (segment (start 185.844359 101.145969) (end 185.844358 101.14597) (width 0.09) (layer "In5.Cu") (net 456))
  (segment (start 186.16 101.106192) (end 186.16 101.408909) (width 0.09) (layer "In5.Cu") (net 456))
  (segment (start 247.371999 93.497999) (end 247.639867 93.497999) (width 0.1) (layer "In5.Cu") (net 456))
  (segment (start 185.667581 101.14597) (end 185.667582 101.14597) (width 0.09) (layer "In5.Cu") (net 456))
  (segment (start 184.09384 99.358949) (end 184.267444 99.532554) (width 0.09) (layer "In5.Cu") (net 456))
  (segment (start 187.394875 102.66) (end 187.69 102.66) (width 0.09) (layer "In5.Cu") (net 456))
  (segment (start 184.797762 99.532556) (end 184.868464 99.461851) (width 0.09) (layer "In5.Cu") (net 456))
  (segment (start 186.110456 101.056647) (end 186.110456 101.056648) (width 0.09) (layer "In5.Cu") (net 456))
  (segment (start 246.532134 93.24) (end 245.217866 93.24) (width 0.1) (layer "In5.Cu") (net 456))
  (segment (start 185.70995 102.53071) (end 185.70995 102.530709) (width 0.09) (layer "In5.Cu") (net 456))
  (segment (start 182.472713 98.665008) (end 183.399897 98.665008) (width 0.09) (layer "In5.Cu") (net 456))
  (segment (start 247.19 93.316) (end 247.371999 93.497999) (width 0.1) (layer "In5.Cu") (net 456))
  (segment (start 199.901774 103.21036) (end 191.921194 103.21036) (width 0.1) (layer "In5.Cu") (net 456))
  (segment (start 191.03821 103.149632) (end 191.819045 103.149632) (width 0.09) (layer "In5.Cu") (net 456))
  (segment (start 200.373248 101.961066) (end 200.373247 101.961066) (width 0.1) (layer "In5.Cu") (net 456))
  (segment (start 185.115967 99.709353) (end 185.045262 99.780055) (width 0.09) (layer "In5.Cu") (net 456))
  (segment (start 189.89 102.66) (end 190.548578 102.66) (width 0.09) (layer "In5.Cu") (net 456))
  (segment (start 191.889756 103.178922) (end 191.921194 103.21036) (width 0.09) (layer "In5.Cu") (net 456))
  (segment (start 200.019693 103.092435) (end 200.019695 103.092437) (width 0.1) (layer "In5.Cu") (net 456))
  (segment (start 188.74 102.66) (end 188.79 102.66) (width 0.09) (layer "In5.Cu") (net 456))
  (segment (start 189.715 102.985) (end 189.715 102.835) (width 0.09) (layer "In5.Cu") (net 456))
  (segment (start 199.83016 102.125082) (end 200.019694 102.314616) (width 0.1) (layer "In5.Cu") (net 456))
  (segment (start 183.457446 98.828636) (end 183.386743 98.899338) (width 0.09) (layer "In5.Cu") (net 456))
  (segment (start 185.045262 100.310371) (end 185.389878 100.654989) (width 0.09) (layer "In5.Cu") (net 456))
  (segment (start 181.973008 98.060008) (end 182.035 98.122) (width 0.09) (layer "In5.Cu") (net 456))
  (segment (start 247.76 93.102134) (end 247.527866 92.87) (width 0.1) (layer "In5.Cu") (net 456))
  (segment (start 188.04 102.31) (end 188.04 102.21) (width 0.09) (layer "In5.Cu") (net 456))
  (segment (start 183.386742 99.288231) (end 183.528164 99.429653) (width 0.09) (layer "In5.Cu") (net 456))
  (segment (start 182.291578 98.668) (end 182.469721 98.668) (width 0.09) (layer "In5.Cu") (net 456))
  (segment (start 247.76 93.377866) (end 247.76 93.102134) (width 0.1) (layer "In5.Cu") (net 456))
  (segment (start 244.873866 92.896) (end 243.54003 92.896) (width 0.1) (layer "In5.Cu") (net 456))
  (segment (start 185.844358 101.14597) (end 185.933679 101.056648) (width 0.09) (layer "In5.Cu") (net 456))
  (segment (start 183.917057 99.429652) (end 183.917057 99.429653) (width 0.09) (layer "In5.Cu") (net 456))
  (segment (start 247.639867 93.497999) (end 247.76 93.377866) (width 0.1) (layer "In5.Cu") (net 456))
  (segment (start 183.399897 98.665008) (end 183.457446 98.722554) (width 0.09) (layer "In5.Cu") (net 456))
  (segment (start 183.917057 99.429653) (end 183.987759 99.35895) (width 0.09) (layer "In5.Cu") (net 456))
  (segment (start 240.762134 95.9) (end 206.562134 95.9) (width 0.1) (layer "In5.Cu") (net 456))
  (segment (start 182.469721 98.668) (end 182.472713 98.665008) (width 0.09) (layer "In5.Cu") (net 456))
  (segment (start 242.95 93.712134) (end 240.762134 95.9) (width 0.1) (layer "In5.Cu") (net 456))
  (segment (start 182.035 98.122) (end 182.035 98.411422) (width 0.09) (layer "In5.Cu") (net 456))
  (segment (start 187.018096 102.283221) (end 187.394875 102.66) (width 0.09) (layer "In5.Cu") (net 456))
  (segment (start 186.16 101.408909) (end 185.70995 101.858958) (width 0.09) (layer "In5.Cu") (net 456))
  (arc (start 185.70995 101.858958) (mid 185.570826 102.194834) (end 185.70995 102.53071) (width 0.09) (layer "In5.Cu") (net 456))
  (arc (start 185.667582 101.14597) (mid 185.755971 101.182581) (end 185.844359 101.145969) (width 0.09) (layer "In5.Cu") (net 456))
  (arc (start 191.819045 103.149632) (mid 191.857314 103.157244) (end 191.889756 103.178922) (width 0.09) (layer "In5.Cu") (net 456))
  (arc (start 188.965 102.985) (mid 189.074835 103.250165) (end 189.34 103.36) (width 0.09) (layer "In5.Cu") (net 456))
  (arc (start 187.69 102.66) (mid 187.937487 102.557487) (end 188.04 102.31) (width 0.09) (layer "In5.Cu") (net 456))
  (arc (start 183.987759 99.35895) (mid 184.040799 99.336979) (end 184.09384 99.358949) (width 0.09) (layer "In5.Cu") (net 456))
  (arc (start 201.151066 101.961066) (mid 200.762157 102.122157) (end 200.373248 101.961066) (width 0.1) (layer "In5.Cu") (net 456))
  (arc (start 188.24 102.06) (mid 188.346066 102.103934) (end 188.39 102.21) (width 0.09) (layer "In5.Cu") (net 456))
  (arc (start 184.267444 99.532554) (mid 184.532604 99.642388) (end 184.797762 99.532556) (width 0.09) (layer "In5.Cu") (net 456))
  (arc (start 185.115966 99.461851) (mid 185.167225 99.585602) (end 185.115965 99.709352) (width 0.09) (layer "In5.Cu") (net 456))
  (arc (start 188.04 102.21) (mid 188.083934 102.103934) (end 188.19 102.06) (width 0.09) (layer "In5.Cu") (net 456))
  (arc (start 185.933679 101.056648) (mid 186.022067 101.020036) (end 186.110456 101.056647) (width 0.09) (layer "In5.Cu") (net 456))
  (arc (start 185.756904 100.703096) (mid 185.793515 100.791485) (end 185.756903 100.879873) (width 0.09) (layer "In5.Cu") (net 456))
  (arc (start 186.629188 102.283221) (mid 186.823642 102.202676) (end 187.018096 102.283221) (width 0.09) (layer "In5.Cu") (net 456))
  (arc (start 200.183712 101.771531) (mid 200.006936 101.698308) (end 199.83016 101.771531) (width 0.1) (layer "In5.Cu") (net 456))
  (arc (start 184.868464 99.461851) (mid 184.992215 99.410592) (end 185.115966 99.461851) (width 0.09) (layer "In5.Cu") (net 456))
  (arc (start 189.34 103.36) (mid 189.605165 103.250165) (end 189.715 102.985) (width 0.09) (layer "In5.Cu") (net 456))
  (arc (start 183.457446 98.722554) (mid 183.479416 98.775595) (end 183.457446 98.828636) (width 0.09) (layer "In5.Cu") (net 456))
  (arc (start 185.045262 99.780055) (mid 184.93543 100.045213) (end 185.045262 100.310371) (width 0.09) (layer "In5.Cu") (net 456))
  (arc (start 188.39 102.31) (mid 188.492513 102.557487) (end 188.74 102.66) (width 0.09) (layer "In5.Cu") (net 456))
  (arc (start 185.667582 100.969193) (mid 185.63097 101.057581) (end 185.667581 101.14597) (width 0.09) (layer "In5.Cu") (net 456))
  (arc (start 200.019694 102.314616) (mid 200.180785 102.703526) (end 200.019693 103.092435) (width 0.1) (layer "In5.Cu") (net 456))
  (arc (start 183.386743 98.899338) (mid 183.3062 99.093784) (end 183.386742 99.288231) (width 0.09) (layer "In5.Cu") (net 456))
  (arc (start 183.528164 99.429653) (mid 183.722611 99.510195) (end 183.917057 99.429652) (width 0.09) (layer "In5.Cu") (net 456))
  (arc (start 199.83016 101.771531) (mid 199.756937 101.948306) (end 199.83016 102.125081) (width 0.1) (layer "In5.Cu") (net 456))
  (arc (start 188.79 102.66) (mid 188.913744 102.711256) (end 188.965 102.835) (width 0.09) (layer "In5.Cu") (net 456))
  (arc (start 185.70995 102.530709) (mid 186.045826 102.669833) (end 186.381701 102.530708) (width 0.09) (layer "In5.Cu") (net 456))
  (arc (start 189.715 102.835) (mid 189.766256 102.711256) (end 189.89 102.66) (width 0.09) (layer "In5.Cu") (net 456))
  (segment (start 247.825 93.395) (end 247.825 93.015) (width 0.1) (layer "B.Cu") (net 456))
  (segment (start 247.371999 93.497999) (end 247.722001 93.497999) (width 0.1) (layer "B.Cu") (net 456))
  (segment (start 247.722001 93.497999) (end 247.825 93.395) (width 0.1) (layer "B.Cu") (net 456))
  (segment (start 247.19 93.316) (end 247.371999 93.497999) (width 0.1) (layer "B.Cu") (net 456))
  (segment (start 180.136328 98.560008) (end 179.636328 99.060008) (width 0.1) (layer "F.Cu") (net 457))
  (via (at 245.92 98.396) (size 0.5) (drill 0.2) (layers "F.Cu" "B.Cu") (net 457))
  (via (at 179.636328 99.060008) (size 0.5) (drill 0.2) (layers "F.Cu" "B.Cu") (net 457))
  (segment (start 242.95 98.95) (end 242.95 98.5) (width 0.1) (layer "In7.Cu") (net 457))
  (segment (start 245.92 98.396) (end 246.101999 98.577999) (width 0.1) (layer "In7.Cu") (net 457))
  (segment (start 185.421 102.03947) (end 185.421 102.262) (width 0.09) (layer "In7.Cu") (net 457))
  (segment (start 185.821 102.662) (end 192.100578 102.662) (width 0.09) (layer "In7.Cu") (net 457))
  (segment (start 182.859 100.579422) (end 182.859 102.349422) (width 0.09) (layer "In7.Cu") (net 457))
  (segment (start 179.636328 98.741672) (end 179.717992 98.660008) (width 0.09) (layer "In7.Cu") (net 457))
  (segment (start 183.171578 102.662) (end 183.421 102.662) (width 0.09) (layer "In7.Cu") (net 457))
  (segment (start 182.859 102.349422) (end 183.171578 102.662) (width 0.09) (layer "In7.Cu") (net 457))
  (segment (start 245.137866 99.45) (end 243.45 99.45) (width 0.1) (layer "In7.Cu") (net 457))
  (segment (start 192.100578 102.662) (end 192.229578 102.791) (width 0.09) (layer "In7.Cu") (net 457))
  (segment (start 184.221 101.93947) (end 184.221 103.03453) (width 0.09) (layer "In7.Cu") (net 457))
  (segment (start 198.18729 102.82029) (end 198.207 102.84) (width 0.09) (layer "In7.Cu") (net 457))
  (segment (start 180.939586 98.660008) (end 182.859 100.579422) (width 0.09) (layer "In7.Cu") (net 457))
  (segment (start 183.821 102.262) (end 183.821 101.93947) (width 0.09) (layer "In7.Cu") (net 457))
  (segment (start 179.636328 99.060008) (end 179.636328 98.741672) (width 0.09) (layer "In7.Cu") (net 457))
  (segment (start 245.587866 99.9) (end 245.137866 99.45) (width 0.1) (layer "In7.Cu") (net 457))
  (segment (start 246.296064 99.9) (end 245.587866 99.9) (width 0.1) (layer "In7.Cu") (net 457))
  (segment (start 185.021 103.03453) (end 185.021 102.03947) (width 0.09) (layer "In7.Cu") (net 457))
  (segment (start 246.101999 98.577999) (end 246.460133 98.577999) (width 0.1) (layer "In7.Cu") (net 457))
  (segment (start 205.762134 99.45) (end 202.372134 102.84) (width 0.1) (layer "In7.Cu") (net 457))
  (segment (start 242.05 99.45) (end 205.762134 99.45) (width 0.1) (layer "In7.Cu") (net 457))
  (segment (start 246.460133 98.577999) (end 246.81 98.927866) (width 0.1) (layer "In7.Cu") (net 457))
  (segment (start 242.55 98.5) (end 242.55 98.95) (width 0.1) (layer "In7.Cu") (net 457))
  (segment (start 179.717992 98.660008) (end 180.939586 98.660008) (width 0.09) (layer "In7.Cu") (net 457))
  (segment (start 202.372134 102.84) (end 198.207 102.84) (width 0.1) (layer "In7.Cu") (net 457))
  (segment (start 246.81 98.927866) (end 246.81 99.386064) (width 0.1) (layer "In7.Cu") (net 457))
  (segment (start 192.229578 102.791) (end 198.116579 102.791) (width 0.09) (layer "In7.Cu") (net 457))
  (segment (start 246.81 99.386064) (end 246.296064 99.9) (width 0.1) (layer "In7.Cu") (net 457))
  (arc (start 183.421 102.662) (mid 183.703843 102.544843) (end 183.821 102.262) (width 0.09) (layer "In7.Cu") (net 457))
  (arc (start 184.221 103.03453) (mid 184.338157 103.317373) (end 184.621 103.43453) (width 0.09) (layer "In7.Cu") (net 457))
  (arc (start 242.55 98.95) (mid 242.403553 99.303553) (end 242.05 99.45) (width 0.1) (layer "In7.Cu") (net 457))
  (arc (start 184.021 101.73947) (mid 184.162421 101.798049) (end 184.221 101.93947) (width 0.09) (layer "In7.Cu") (net 457))
  (arc (start 184.621 103.43453) (mid 184.903843 103.317373) (end 185.021 103.03453) (width 0.09) (layer "In7.Cu") (net 457))
  (arc (start 185.421 102.262) (mid 185.538157 102.544843) (end 185.821 102.662) (width 0.09) (layer "In7.Cu") (net 457))
  (arc (start 198.116579 102.791) (mid 198.154848 102.798612) (end 198.18729 102.82029) (width 0.09) (layer "In7.Cu") (net 457))
  (arc (start 242.75 98.3) (mid 242.608579 98.358579) (end 242.55 98.5) (width 0.1) (layer "In7.Cu") (net 457))
  (arc (start 183.821 101.93947) (mid 183.879579 101.798049) (end 184.021 101.73947) (width 0.09) (layer "In7.Cu") (net 457))
  (arc (start 185.221 101.83947) (mid 185.362421 101.898049) (end 185.421 102.03947) (width 0.09) (layer "In7.Cu") (net 457))
  (arc (start 242.95 98.5) (mid 242.891421 98.358579) (end 242.75 98.3) (width 0.1) (layer "In7.Cu") (net 457))
  (arc (start 243.45 99.45) (mid 243.096447 99.303553) (end 242.95 98.95) (width 0.1) (layer "In7.Cu") (net 457))
  (arc (start 185.021 102.03947) (mid 185.079579 101.898049) (end 185.221 101.83947) (width 0.09) (layer "In7.Cu") (net 457))
  (segment (start 246.101999 98.577999) (end 246.452001 98.577999) (width 0.1) (layer "B.Cu") (net 457))
  (segment (start 245.92 98.396) (end 246.101999 98.577999) (width 0.1) (layer "B.Cu") (net 457))
  (segment (start 246.555 98.475) (end 246.555 98.095) (width 0.1) (layer "B.Cu") (net 457))
  (segment (start 246.452001 98.577999) (end 246.555 98.475) (width 0.1) (layer "B.Cu") (net 457))
  (segment (start 179.136328 98.560008) (end 178.636328 99.060008) (width 0.1) (layer "F.Cu") (net 458))
  (via (at 244.65 101.6) (size 0.5) (drill 0.2) (layers "F.Cu" "B.Cu") (net 458))
  (via (at 178.636328 99.060008) (size 0.5) (drill 0.2) (layers "F.Cu" "B.Cu") (net 458))
  (segment (start 244.831999 101.418001) (end 245.190133 101.418001) (width 0.1) (layer "In7.Cu") (net 458))
  (segment (start 182.235 102.763578) (end 183.294422 103.823) (width 0.09) (layer "In7.Cu") (net 458))
  (segment (start 182.211438 101.327706) (end 182.135525 101.403616) (width 0.09) (layer "In7.Cu") (net 458))
  (segment (start 181.605196 100.873288) (end 181.681108 100.797377) (width 0.09) (layer "In7.Cu") (net 458))
  (segment (start 206.811866 100.226) (end 203.269866 103.768) (width 0.1) (layer "In7.Cu") (net 458))
  (segment (start 182.211436 101.327705) (end 182.211438 101.327706) (width 0.09) (layer "In7.Cu") (net 458))
  (segment (start 244.65 101.6) (end 244.831999 101.418001) (width 0.1) (layer "In7.Cu") (net 458))
  (segment (start 245.54 100.609936) (end 245.156064 100.226) (width 0.1) (layer "In7.Cu") (net 458))
  (segment (start 181.19208 99.753066) (end 180.378908 100.566238) (width 0.09) (layer "In7.Cu") (net 458))
  (segment (start 180.308199 99.57629) (end 180.661751 99.222735) (width 0.09) (layer "In7.Cu") (net 458))
  (segment (start 198.08829 103.79371) (end 198.114 103.768) (width 0.09) (layer "In7.Cu") (net 458))
  (segment (start 203.269866 103.768) (end 198.114 103.768) (width 0.1) (layer "In7.Cu") (net 458))
  (segment (start 180.626395 100.813725) (end 180.626395 100.813726) (width 0.09) (layer "In7.Cu") (net 458))
  (segment (start 181.227435 100.743015) (end 181.357708 100.873288) (width 0.09) (layer "In7.Cu") (net 458))
  (segment (start 179.94443 99.460008) (end 180.060709 99.576288) (width 0.09) (layer "In7.Cu") (net 458))
  (segment (start 245.54 101.068134) (end 245.54 100.609936) (width 0.1) (layer "In7.Cu") (net 458))
  (segment (start 245.156064 100.226) (end 206.811866 100.226) (width 0.1) (layer "In7.Cu") (net 458))
  (segment (start 245.190133 101.418001) (end 245.54 101.068134) (width 0.1) (layer "In7.Cu") (net 458))
  (segment (start 182.135525 101.651104) (end 182.135526 101.651104) (width 0.09) (layer "In7.Cu") (net 458))
  (segment (start 180.626395 100.813726) (end 180.697105 100.743015) (width 0.09) (layer "In7.Cu") (net 458))
  (segment (start 182.135526 101.651104) (end 182.235 101.750578) (width 0.09) (layer "In7.Cu") (net 458))
  (segment (start 178.636328 99.060008) (end 178.636328 99.391328) (width 0.09) (layer "In7.Cu") (net 458))
  (segment (start 183.294422 103.823) (end 198.017579 103.823) (width 0.09) (layer "In7.Cu") (net 458))
  (segment (start 178.636328 99.391328) (end 178.705008 99.460008) (width 0.09) (layer "In7.Cu") (net 458))
  (segment (start 182.235 101.750578) (end 182.235 102.763578) (width 0.09) (layer "In7.Cu") (net 458))
  (segment (start 178.705008 99.460008) (end 179.94443 99.460008) (width 0.09) (layer "In7.Cu") (net 458))
  (arc (start 181.192081 99.222735) (mid 181.301917 99.487902) (end 181.19208 99.753066) (width 0.09) (layer "In7.Cu") (net 458))
  (arc (start 180.378908 100.566238) (mid 180.327652 100.689982) (end 180.378908 100.813726) (width 0.09) (layer "In7.Cu") (net 458))
  (arc (start 180.060709 99.576288) (mid 180.184455 99.627546) (end 180.308199 99.57629) (width 0.09) (layer "In7.Cu") (net 458))
  (arc (start 182.211438 100.797375) (mid 182.321273 101.062541) (end 182.211436 101.327705) (width 0.09) (layer "In7.Cu") (net 458))
  (arc (start 181.681108 100.797377) (mid 181.946273 100.687542) (end 182.211438 100.797375) (width 0.09) (layer "In7.Cu") (net 458))
  (arc (start 180.697105 100.743015) (mid 180.96227 100.63318) (end 181.227435 100.743015) (width 0.09) (layer "In7.Cu") (net 458))
  (arc (start 181.357708 100.873288) (mid 181.481452 100.924544) (end 181.605196 100.873288) (width 0.09) (layer "In7.Cu") (net 458))
  (arc (start 198.017579 103.823) (mid 198.055848 103.815388) (end 198.08829 103.79371) (width 0.09) (layer "In7.Cu") (net 458))
  (arc (start 180.378908 100.813726) (mid 180.502652 100.864982) (end 180.626395 100.813725) (width 0.09) (layer "In7.Cu") (net 458))
  (arc (start 180.661751 99.222735) (mid 180.926916 99.1129) (end 181.192081 99.222735) (width 0.09) (layer "In7.Cu") (net 458))
  (arc (start 182.135525 101.403616) (mid 182.084269 101.527362) (end 182.135525 101.651104) (width 0.09) (layer "In7.Cu") (net 458))
  (segment (start 245.213001 101.418001) (end 245.285 101.49) (width 0.1) (layer "B.Cu") (net 458))
  (segment (start 244.831999 101.418001) (end 245.213001 101.418001) (width 0.1) (layer "B.Cu") (net 458))
  (segment (start 244.65 101.6) (end 244.831999 101.418001) (width 0.1) (layer "B.Cu") (net 458))
  (segment (start 245.285 101.49) (end 245.285 101.905) (width 0.1) (layer "B.Cu") (net 458))
  (segment (start 176.636328 99.060008) (end 177.136328 98.560008) (width 0.1) (layer "F.Cu") (net 459))
  (via (at 244.65 104.746) (size 0.5) (drill 0.2) (layers "F.Cu" "B.Cu") (net 459))
  (via (at 176.636328 99.060008) (size 0.5) (drill 0.2) (layers "F.Cu" "B.Cu") (net 459))
  (segment (start 179.665866 103.664) (end 179.065 103.664) (width 0.1) (layer "In7.Cu") (net 459))
  (segment (start 180.074 104.072134) (end 179.665866 103.664) (width 0.1) (layer "In7.Cu") (net 459))
  (segment (start 176.888 98.625) (end 176.729656 98.625) (width 0.09) (layer "In7.Cu") (net 459))
  (segment (start 191.537866 106.85) (end 190.912866 106.225) (width 0.1) (layer "In7.Cu") (net 459))
  (segment (start 177.041347 98.778347) (end 176.888 98.625) (width 0.09) (layer "In7.Cu") (net 459))
  (segment (start 199.482134 106.85) (end 191.537866 106.85) (width 0.1) (layer "In7.Cu") (net 459))
  (segment (start 176.636328 99.060008) (end 176.636328 98.718328) (width 0.09) (layer "In7.Cu") (net 459))
  (segment (start 244.831999 104.927999) (end 244.65 104.746) (width 0.1) (layer "In7.Cu") (net 459))
  (segment locked (start 232.837866 103.25) (end 233.725379 104.137513) (width 0.1) (layer "In7.Cu") (net 459))
  (segment (start 180.074 105.270134) (end 180.074 104.072134) (width 0.1) (layer "In7.Cu") (net 459))
  (segment (start 244.337513 104.137513) (end 244.833309 104.137513) (width 0.1) (layer "In7.Cu") (net 459))
  (segment (start 177.041347 100.881769) (end 177.041347 98.778347) (width 0.09) (layer "In7.Cu") (net 459))
  (segment (start 245.24 104.544204) (end 245.24 104.753866) (width 0.1) (layer "In7.Cu") (net 459))
  (segment (start 178.865 103.864) (end 178.865 103.878258) (width 0.1) (layer "In7.Cu") (net 459))
  (segment (start 200.107134 106.225) (end 199.482134 106.85) (width 0.1) (layer "In7.Cu") (net 459))
  (segment (start 176.729656 98.625) (end 176.636328 98.718328) (width 0.09) (layer "In7.Cu") (net 459))
  (segment (start 177.159837 103.316971) (end 177.159837 101.453691) (width 0.1) (layer "In7.Cu") (net 459))
  (segment (start 233.725379 104.137513) (end 243.537513 104.137513) (width 0.1) (layer "In7.Cu") (net 459))
  (segment (start 177.208 101.048422) (end 177.041347 100.881769) (width 0.09) (layer "In7.Cu") (net 459))
  (segment (start 181.028866 106.225) (end 180.074 105.270134) (width 0.1) (layer "In7.Cu") (net 459))
  (segment (start 244.137513 104.387513) (end 244.137513 104.337513) (width 0.1) (layer "In7.Cu") (net 459))
  (segment (start 177.208 101.405528) (end 177.208 101.048422) (width 0.09) (layer "In7.Cu") (net 459))
  (segment (start 244.833309 104.137513) (end 245.24 104.544204) (width 0.1) (layer "In7.Cu") (net 459))
  (segment locked (start 208.462134 103.25) (end 232.837866 103.25) (width 0.1) (layer "In7.Cu") (net 459))
  (segment (start 177.506866 103.664) (end 177.159837 103.316971) (width 0.1) (layer "In7.Cu") (net 459))
  (segment (start 178.465 103.878258) (end 178.465 103.864) (width 0.1) (layer "In7.Cu") (net 459))
  (segment (start 245.24 104.753866) (end 245.065867 104.927999) (width 0.1) (layer "In7.Cu") (net 459))
  (segment (start 177.506866 103.664) (end 178.265 103.664) (width 0.1) (layer "In7.Cu") (net 459))
  (segment (start 190.912866 106.225) (end 181.028866 106.225) (width 0.1) (layer "In7.Cu") (net 459))
  (segment (start 208.462134 103.25) (end 205.487134 106.225) (width 0.1) (layer "In7.Cu") (net 459))
  (segment (start 245.065867 104.927999) (end 244.831999 104.927999) (width 0.1) (layer "In7.Cu") (net 459))
  (segment (start 243.737513 104.337513) (end 243.737513 104.387513) (width 0.1) (layer "In7.Cu") (net 459))
  (segment (start 205.487134 106.225) (end 200.107134 106.225) (width 0.1) (layer "In7.Cu") (net 459))
  (segment (start 177.159837 101.453691) (end 177.208 101.405528) (width 0.09) (layer "In7.Cu") (net 459))
  (arc (start 244.137513 104.337513) (mid 244.196092 104.196092) (end 244.337513 104.137513) (width 0.1) (layer "In7.Cu") (net 459))
  (arc (start 243.537513 104.137513) (mid 243.678934 104.196092) (end 243.737513 104.337513) (width 0.1) (layer "In7.Cu") (net 459))
  (arc (start 178.465 103.864) (mid 178.406421 103.722579) (end 178.265 103.664) (width 0.1) (layer "In7.Cu") (net 459))
  (arc (start 243.737513 104.387513) (mid 243.796092 104.528934) (end 243.937513 104.587513) (width 0.1) (layer "In7.Cu") (net 459))
  (arc (start 243.937513 104.587513) (mid 244.078934 104.528934) (end 244.137513 104.387513) (width 0.1) (layer "In7.Cu") (net 459))
  (arc (start 179.065 103.664) (mid 178.923579 103.722579) (end 178.865 103.864) (width 0.1) (layer "In7.Cu") (net 459))
  (arc (start 178.665 104.078258) (mid 178.523579 104.019679) (end 178.465 103.878258) (width 0.1) (layer "In7.Cu") (net 459))
  (arc (start 178.865 103.878258) (mid 178.806421 104.019679) (end 178.665 104.078258) (width 0.1) (layer "In7.Cu") (net 459))
  (segment (start 245.285 104.825) (end 245.285 104.445) (width 0.1) (layer "B.Cu") (net 459))
  (segment (start 244.65 104.746) (end 244.831999 104.927999) (width 0.1) (layer "B.Cu") (net 459))
  (segment (start 245.182001 104.927999) (end 245.285 104.825) (width 0.1) (layer "B.Cu") (net 459))
  (segment (start 244.831999 104.927999) (end 245.182001 104.927999) (width 0.1) (layer "B.Cu") (net 459))
  (segment (start 182.136328 97.560008) (end 182.636328 97.060008) (width 0.1) (layer "F.Cu") (net 460))
  (via (at 248.46 90.776) (size 0.5) (drill 0.2) (layers "F.Cu" "B.Cu") (net 460))
  (via blind (at 182.636328 97.060008) (size 0.5) (drill 0.2) (layers "F.Cu" "In5.Cu") (net 460))
  (segment (start 196.855 102.4) (end 196.905 102.4) (width 0.1) (layer "In5.Cu") (net 460))
  (segment (start 182.339992 97.060008) (end 182.23 97.17) (width 0.09) (layer "In5.Cu") (net 460))
  (segment (start 182.23 97.17) (end 182.23 97.288578) (width 0.09) (layer "In5.Cu") (net 460))
  (segment (start 198.387866 101.65) (end 205.687866 94.35) (width 0.1) (layer "In5.Cu") (net 460))
  (segment (start 187.804951 101.45) (end 187.809959 101.455008) (width 0.09) (layer "In5.Cu") (net 460))
  (segment (start 191.162134 101.22) (end 191.562134 101.62) (width 0.1) (layer "In5.Cu") (net 460))
  (segment (start 245.74603 91.86) (end 246.09397 91.86) (width 0.1) (layer "In5.Cu") (net 460))
  (segment (start 187.122283 99.209035) (end 187.122285 99.209036) (width 0.09) (layer "In5.Cu") (net 460))
  (segment (start 187.467705 101.45) (end 187.472713 101.455008) (width 0.09) (layer "In5.Cu") (net 460))
  (segment (start 246.34 91.6) (end 247.337866 91.6) (width 0.1) (layer "In5.Cu") (net 460))
  (segment (start 246.34 91.61397) (end 246.34 91.6) (width 0.1) (layer "In5.Cu") (net 460))
  (segment (start 246.09397 91.86) (end 246.34 91.61397) (width 0.1) (layer "In5.Cu") (net 460))
  (segment (start 187.401422 101.45) (end 187.467705 101.45) (width 0.09) (layer "In5.Cu") (net 460))
  (segment (start 189.879077 101.259501) (end 190.339078 101.259501) (width 0.09) (layer "In5.Cu") (net 460))
  (segment (start 184.421422 98.67) (end 185.321422 98.67) (width 0.09) (layer "In5.Cu") (net 460))
  (segment (start 193.367866 101.14) (end 194.992134 101.14) (width 0.1) (layer "In5.Cu") (net 460))
  (segment (start 186.34995 99.486397) (end 186.627309 99.209035) (width 0.09) (layer "In5.Cu") (net 460))
  (segment (start 187.18 100.528578) (end 187.18 101.228578) (width 0.09) (layer "In5.Cu") (net 460))
  (segment (start 196.705 102.1) (end 196.705 102.25) (width 0.1) (layer "In5.Cu") (net 460))
  (segment (start 186.379821 99.032257) (end 186.137816 99.274263) (width 0.09) (layer "In5.Cu") (net 460))
  (segment (start 242.987866 91.6) (end 245.48603 91.6) (width 0.1) (layer "In5.Cu") (net 460))
  (segment (start 194.992134 101.14) (end 195.502134 101.65) (width 0.1) (layer "In5.Cu") (net 460))
  (segment (start 190.42 101.22) (end 191.162134 101.22) (width 0.1) (layer "In5.Cu") (net 460))
  (segment (start 187.809959 101.455008) (end 189.68357 101.455008) (width 0.09) (layer "In5.Cu") (net 460))
  (segment (start 186.844925 100.193504) (end 187.18 100.528578) (width 0.09) (layer "In5.Cu") (net 460))
  (segment (start 185.642843 98.77929) (end 185.884847 98.537283) (width 0.09) (layer "In5.Cu") (net 460))
  (segment (start 245.48603 91.6) (end 245.74603 91.86) (width 0.1) (layer "In5.Cu") (net 460))
  (segment (start 195.502134 101.65) (end 196.255 101.65) (width 0.1) (layer "In5.Cu") (net 460))
  (segment (start 191.562134 101.62) (end 191.656 101.62) (width 0.1) (layer "In5.Cu") (net 460))
  (segment (start 190.409789 101.230211) (end 190.42 101.22) (width 0.09) (layer "In5.Cu") (net 460))
  (segment (start 191.856 101.42) (end 191.856 101.353726) (width 0.1) (layer "In5.Cu") (net 460))
  (segment (start 183.361422 97.89) (end 183.641422 97.89) (width 0.09) (layer "In5.Cu") (net 460))
  (segment (start 186.844923 100.193501) (end 186.844925 100.193504) (width 0.09) (layer "In5.Cu") (net 460))
  (segment (start 197.055 102.25) (end 197.055 100.525) (width 0.1) (layer "In5.Cu") (net 460))
  (segment (start 182.401422 97.46) (end 182.931422 97.46) (width 0.09) (layer "In5.Cu") (net 460))
  (segment (start 187.472713 101.455008) (end 187.799943 101.455008) (width 0.09) (layer "In5.Cu") (net 460))
  (segment (start 182.23 97.288578) (end 182.401422 97.46) (width 0.09) (layer "In5.Cu") (net 460))
  (segment (start 186.379822 98.537284) (end 186.379821 98.537283) (width 0.09) (layer "In5.Cu") (net 460))
  (segment (start 189.68357 101.455008) (end 189.879077 101.259501) (width 0.09) (layer "In5.Cu") (net 460))
  (segment (start 247.979867 90.957999) (end 248.278001 90.957999) (width 0.1) (layer "In5.Cu") (net 460))
  (segment (start 185.321422 98.67) (end 185.430709 98.779288) (width 0.09) (layer "In5.Cu") (net 460))
  (segment (start 187.799943 101.455008) (end 187.804951 101.45) (width 0.09) (layer "In5.Cu") (net 460))
  (segment (start 187.122285 99.70401) (end 186.844923 99.981369) (width 0.09) (layer "In5.Cu") (net 460))
  (segment (start 192.887866 101.62) (end 193.367866 101.14) (width 0.1) (layer "In5.Cu") (net 460))
  (segment (start 240.237866 94.35) (end 242.987866 91.6) (width 0.1) (layer "In5.Cu") (net 460))
  (segment (start 183.641422 97.89) (end 184.421422 98.67) (width 0.09) (layer "In5.Cu") (net 460))
  (segment (start 186.37982 99.032258) (end 186.379821 99.032257) (width 0.09) (layer "In5.Cu") (net 460))
  (segment (start 182.636328 97.060008) (end 182.339992 97.060008) (width 0.09) (layer "In5.Cu") (net 460))
  (segment (start 192.256 101.353726) (end 192.256 101.42) (width 0.1) (layer "In5.Cu") (net 460))
  (segment (start 205.687866 94.35) (end 240.237866 94.35) (width 0.1) (layer "In5.Cu") (net 460))
  (segment (start 198.18 101.65) (end 198.387866 101.65) (width 0.1) (layer "In5.Cu") (net 460))
  (segment (start 192.456 101.62) (end 192.506 101.62) (width 0.1) (layer "In5.Cu") (net 460))
  (segment (start 247.337866 91.6) (end 247.979867 90.957999) (width 0.1) (layer "In5.Cu") (net 460))
  (segment (start 182.931422 97.46) (end 183.361422 97.89) (width 0.09) (layer "In5.Cu") (net 460))
  (segment (start 248.278001 90.957999) (end 248.46 90.776) (width 0.1) (layer "In5.Cu") (net 460))
  (segment (start 192.506 101.62) (end 192.887866 101.62) (width 0.1) (layer "In5.Cu") (net 460))
  (segment (start 187.122284 99.704011) (end 187.122285 99.70401) (width 0.09) (layer "In5.Cu") (net 460))
  (segment (start 187.18 101.228578) (end 187.401422 101.45) (width 0.09) (layer "In5.Cu") (net 460))
  (segment (start 198.005 100.525) (end 198.005 101.475) (width 0.1) (layer "In5.Cu") (net 460))
  (arc (start 192.256 101.42) (mid 192.314579 101.561421) (end 192.456 101.62) (width 0.1) (layer "In5.Cu") (net 460))
  (arc (start 197.055 100.525) (mid 197.194124 100.189124) (end 197.53 100.05) (width 0.1) (layer "In5.Cu") (net 460))
  (arc (start 191.656 101.62) (mid 191.797421 101.561421) (end 191.856 101.42) (width 0.1) (layer "In5.Cu") (net 460))
  (arc (start 186.137816 99.274263) (mid 186.093882 99.380329) (end 186.137816 99.486395) (width 0.09) (layer "In5.Cu") (net 460))
  (arc (start 198.005 101.475) (mid 198.056256 101.598744) (end 198.18 101.65) (width 0.1) (layer "In5.Cu") (net 460))
  (arc (start 196.255 101.65) (mid 196.573198 101.781802) (end 196.705 102.1) (width 0.1) (layer "In5.Cu") (net 460))
  (arc (start 190.339078 101.259501) (mid 190.377347 101.251889) (end 190.409789 101.230211) (width 0.09) (layer "In5.Cu") (net 460))
  (arc (start 186.627309 99.209035) (mid 186.874797 99.106524) (end 187.122283 99.209035) (width 0.09) (layer "In5.Cu") (net 460))
  (arc (start 192.056 101.153726) (mid 192.197421 101.212305) (end 192.256 101.353726) (width 0.1) (layer "In5.Cu") (net 460))
  (arc (start 185.884847 98.537283) (mid 186.132335 98.434771) (end 186.379822 98.537284) (width 0.09) (layer "In5.Cu") (net 460))
  (arc (start 186.137816 99.486395) (mid 186.243884 99.530331) (end 186.34995 99.486397) (width 0.09) (layer "In5.Cu") (net 460))
  (arc (start 196.705 102.25) (mid 196.748934 102.356066) (end 196.855 102.4) (width 0.1) (layer "In5.Cu") (net 460))
  (arc (start 186.844923 99.981369) (mid 186.800989 100.087435) (end 186.844923 100.193501) (width 0.09) (layer "In5.Cu") (net 460))
  (arc (start 191.856 101.353726) (mid 191.914579 101.212305) (end 192.056 101.153726) (width 0.1) (layer "In5.Cu") (net 460))
  (arc (start 185.430709 98.779288) (mid 185.536777 98.823224) (end 185.642843 98.77929) (width 0.09) (layer "In5.Cu") (net 460))
  (arc (start 187.122285 99.209036) (mid 187.224797 99.456524) (end 187.122284 99.704011) (width 0.09) (layer "In5.Cu") (net 460))
  (arc (start 186.379821 98.537283) (mid 186.482333 98.784771) (end 186.37982 99.032258) (width 0.09) (layer "In5.Cu") (net 460))
  (arc (start 197.53 100.05) (mid 197.865876 100.189124) (end 198.005 100.525) (width 0.1) (layer "In5.Cu") (net 460))
  (arc (start 196.905 102.4) (mid 197.011066 102.356066) (end 197.055 102.25) (width 0.1) (layer "In5.Cu") (net 460))
  (segment (start 248.46 90.776) (end 248.641999 90.957999) (width 0.1) (layer "B.Cu") (net 460))
  (segment (start 249.095 90.855) (end 249.095 90.475) (width 0.1) (layer "B.Cu") (net 460))
  (segment (start 248.641999 90.957999) (end 248.992001 90.957999) (width 0.1) (layer "B.Cu") (net 460))
  (segment (start 248.992001 90.957999) (end 249.095 90.855) (width 0.1) (layer "B.Cu") (net 460))
  (segment (start 195.888773 97.968016) (end 196.581984 97.968016) (width 0.1) (layer "F.Cu") (net 463))
  (segment (start 245.358722 92.848406) (end 246.481278 92.848406) (width 0.122) (layer "F.Cu") (net 463))
  (segment (start 195.814718 97.589298) (end 195.760617 97.643399) (width 0.1) (layer "F.Cu") (net 463))
  (segment (start 250.816748 87.1515) (end 253.785657 87.1515) (width 0.122) (layer "F.Cu") (net 463))
  (segment (start 246.6227 92.789827) (end 246.785696 92.626831) (width 0.122) (layer "F.Cu") (net 463))
  (segment (start 247.04379 92.519925) (end 248.115558 92.519925) (width 0.122) (layer "F.Cu") (net 463))
  (segment (start 203.366012 94.7965) (end 240.756346 94.7965) (width 0.122) (layer "F.Cu") (net 463))
  (segment (start 196.706984 97.843016) (end 196.706984 97.828808) (width 0.1) (layer "F.Cu") (net 463))
  (segment (start 248.25698 92.461346) (end 248.897922 91.820404) (width 0.122) (layer "F.Cu") (net 463))
  (segment (start 198.142418 97.924082) (end 198.15 97.9165) (width 0.1) (layer "F.Cu") (net 463))
  (segment (start 244.08613 92.786397) (end 244.245696 92.626831) (width 0.122) (layer "F.Cu") (net 463))
  (segment (start 200.117006 97.770054) (end 202.895786 94.991274) (width 0.122) (layer "F.Cu") (net 463))
  (segment (start 249.063406 88.753654) (end 250.558654 87.258406) (width 0.122) (layer "F.Cu") (net 463))
  (segment (start 243.273272 92.844976) (end 243.944708 92.844976) (width 0.122) (layer "F.Cu") (net 463))
  (segment (start 197.081984 97.968016) (end 198.036352 97.968016) (width 0.1) (layer "F.Cu") (net 463))
  (segment (start 244.503791 92.519925) (end 244.796212 92.519926) (width 0.122) (layer "F.Cu") (net 463))
  (segment (start 196.136328 97.560008) (end 195.885429 97.560008) (width 0.1) (layer "F.Cu") (net 463))
  (segment (start 248.9565 91.678983) (end 248.9565 89.011748) (width 0.122) (layer "F.Cu") (net 463))
  (segment (start 196.956984 97.828808) (end 196.956984 97.843016) (width 0.1) (layer "F.Cu") (net 463))
  (segment (start 241.463453 94.503607) (end 243.015178 92.951882) (width 0.122) (layer "F.Cu") (net 463))
  (segment (start 195.731328 97.714109) (end 195.731328 97.810571) (width 0.1) (layer "F.Cu") (net 463))
  (segment (start 245.054305 92.626832) (end 245.217301 92.789828) (width 0.122) (layer "F.Cu") (net 463))
  (segment (start 253.927079 87.092921) (end 254.225 86.795) (width 0.122) (layer "F.Cu") (net 463))
  (segment (start 198.15 97.9165) (end 199.763453 97.9165) (width 0.122) (layer "F.Cu") (net 463))
  (segment (start 195.760618 97.881282) (end 195.818063 97.938727) (width 0.1) (layer "F.Cu") (net 463))
  (arc (start 195.885429 97.560008) (mid 195.84716 97.56762) (end 195.814718 97.589298) (width 0.1) (layer "F.Cu") (net 463))
  (arc (start 250.816748 87.1515) (mid 250.677069 87.179284) (end 250.558654 87.258406) (width 0.122) (layer "F.Cu") (net 463))
  (arc (start 244.796212 92.519926) (mid 244.935891 92.54771) (end 245.054305 92.626832) (width 0.122) (layer "F.Cu") (net 463))
  (arc (start 196.831984 97.703808) (mid 196.920372 97.74042) (end 196.956984 97.828808) (width 0.1) (layer "F.Cu") (net 463))
  (arc (start 198.036352 97.968016) (mid 198.093755 97.956598) (end 198.142418 97.924082) (width 0.1) (layer "F.Cu") (net 463))
  (arc (start 246.785696 92.626831) (mid 246.904111 92.547709) (end 247.04379 92.519925) (width 0.122) (layer "F.Cu") (net 463))
  (arc (start 199.763453 97.9165) (mid 199.954794 97.87844) (end 200.117006 97.770054) (width 0.122) (layer "F.Cu") (net 463))
  (arc (start 248.897922 91.820404) (mid 248.941276 91.755519) (end 248.9565 91.678983) (width 0.122) (layer "F.Cu") (net 463))
  (arc (start 248.9565 89.011748) (mid 248.984284 88.872069) (end 249.063406 88.753654) (width 0.122) (layer "F.Cu") (net 463))
  (arc (start 244.245696 92.626831) (mid 244.364111 92.547709) (end 244.503791 92.519925) (width 0.122) (layer "F.Cu") (net 463))
  (arc (start 248.25698 92.461346) (mid 248.192095 92.504701) (end 248.115558 92.519925) (width 0.122) (layer "F.Cu") (net 463))
  (arc (start 245.217301 92.789828) (mid 245.282186 92.833182) (end 245.358722 92.848406) (width 0.122) (layer "F.Cu") (net 463))
  (arc (start 196.706984 97.828808) (mid 196.743596 97.74042) (end 196.831984 97.703808) (width 0.1) (layer "F.Cu") (net 463))
  (arc (start 196.956984 97.843016) (mid 196.993596 97.931404) (end 197.081984 97.968016) (width 0.1) (layer "F.Cu") (net 463))
  (arc (start 195.731328 97.810571) (mid 195.73894 97.84884) (end 195.760618 97.881282) (width 0.1) (layer "F.Cu") (net 463))
  (arc (start 243.944708 92.844976) (mid 244.021245 92.829752) (end 244.08613 92.786397) (width 0.122) (layer "F.Cu") (net 463))
  (arc (start 243.015178 92.951882) (mid 243.133593 92.87276) (end 243.273272 92.844976) (width 0.122) (layer "F.Cu") (net 463))
  (arc (start 203.366012 94.7965) (mid 203.111528 94.84712) (end 202.895786 94.991274) (width 0.122) (layer "F.Cu") (net 463))
  (arc (start 195.818063 97.938727) (mid 195.850505 97.960404) (end 195.888773 97.968016) (width 0.1) (layer "F.Cu") (net 463))
  (arc (start 253.785657 87.1515) (mid 253.862194 87.136276) (end 253.927079 87.092921) (width 0.122) (layer "F.Cu") (net 463))
  (arc (start 246.481278 92.848406) (mid 246.557815 92.833182) (end 246.6227 92.789827) (width 0.122) (layer "F.Cu") (net 463))
  (arc (start 241.463453 94.503607) (mid 241.13903 94.72038) (end 240.756346 94.7965) (width 0.122) (layer "F.Cu") (net 463))
  (arc (start 195.760617 97.643399) (mid 195.73894 97.675841) (end 195.731328 97.714109) (width 0.1) (layer "F.Cu") (net 463))
  (arc (start 196.581984 97.968016) (mid 196.670372 97.931404) (end 196.706984 97.843016) (width 0.1) (layer "F.Cu") (net 463))
  (segment (start 255.195 82.73) (end 255.492922 82.432078) (width 0.122) (layer "F.Cu") (net 464))
  (segment (start 255.947079 82.432079) (end 256.08 82.565) (width 0.122) (layer "F.Cu") (net 464))
  (segment (start 255.634343 82.3735) (end 255.805657 82.3735) (width 0.122) (layer "F.Cu") (net 464))
  (via (at 256.08 82.55) (size 0.5) (drill 0.2) (layers "F.Cu" "B.Cu") (net 464))
  (arc (start 255.492922 82.432078) (mid 255.557807 82.388724) (end 255.634343 82.3735) (width 0.122) (layer "F.Cu") (net 464))
  (arc (start 255.947079 82.432079) (mid 255.882194 82.388724) (end 255.805657 82.3735) (width 0.122) (layer "F.Cu") (net 464))
  (segment (start 256.08 82.55) (end 256.209922 82.420078) (width 0.122) (layer "B.Cu") (net 464))
  (segment (start 256.685079 82.420079) (end 256.685711 82.420711) (width 0.122) (layer "B.Cu") (net 464))
  (segment (start 256.351343 82.3615) (end 256.543657 82.3615) (width 0.122) (layer "B.Cu") (net 464))
  (segment (start 256.715 82.491421) (end 256.715 82.855) (width 0.122) (layer "B.Cu") (net 464))
  (arc (start 256.351343 82.3615) (mid 256.274807 82.376724) (end 256.209922 82.420078) (width 0.122) (layer "B.Cu") (net 464))
  (arc (start 256.715 82.491421) (mid 256.707388 82.453153) (end 256.685711 82.420711) (width 0.122) (layer "B.Cu") (net 464))
  (arc (start 256.543657 82.3615) (mid 256.620194 82.376724) (end 256.685079 82.420079) (width 0.122) (layer "B.Cu") (net 464))
  (segment (start 250.170862 81.832078) (end 249.302079 82.700861) (width 0.122) (layer "F.Cu") (net 465))
  (segment (start 253.358654 82.251594) (end 252.939139 81.832079) (width 0.122) (layer "F.Cu") (net 465))
  (segment (start 246.198158 92.253594) (end 245.701842 92.253594) (width 0.122) (layer "F.Cu") (net 465))
  (segment (start 195.445282 95.589298) (end 195.512039 95.656055) (width 0.1) (layer "F.Cu") (net 465))
  (segment (start 252.797717 81.7735) (end 250.312283 81.7735) (width 0.122) (layer "F.Cu") (net 465))
  (segment (start 245.443748 92.146688) (end 245.249138 91.952078) (width 0.122) (layer "F.Cu") (net 465))
  (segment (start 240.306881 93.8135) (end 201.976547 93.8135) (width 0.122) (layer "F.Cu") (net 465))
  (segment (start 195.136328 95.560008) (end 195.374571 95.560008) (width 0.1) (layer "F.Cu") (net 465))
  (segment (start 195.847349 96.158016) (end 198.048557 96.158016) (width 0.1) (layer "F.Cu") (net 465))
  (segment (start 253.785657 82.3585) (end 253.616748 82.3585) (width 0.122) (layer "F.Cu") (net 465))
  (segment (start 247.458252 91.8935) (end 246.792283 91.8935) (width 0.122) (layer "F.Cu") (net 465))
  (segment (start 195.541328 95.726765) (end 195.541328 95.851995) (width 0.1) (layer "F.Cu") (net 465))
  (segment (start 198.154623 96.20195) (end 198.157007 96.204334) (width 0.1) (layer "F.Cu") (net 465))
  (segment (start 245.107717 91.8935) (end 242.792283 91.8935) (width 0.122) (layer "F.Cu") (net 465))
  (segment (start 242.650861 91.952079) (end 241.13066 93.47228) (width 0.122) (layer "F.Cu") (net 465))
  (segment (start 248.0035 85.462283) (end 248.0035 91.348252) (width 0.122) (layer "F.Cu") (net 465))
  (segment (start 249.136594 84.246346) (end 248.062079 85.320861) (width 0.122) (layer "F.Cu") (net 465))
  (segment (start 201.622993 93.959947) (end 199.602669 95.980271) (width 0.122) (layer "F.Cu") (net 465))
  (segment (start 247.896594 91.606346) (end 247.716346 91.786594) (width 0.122) (layer "F.Cu") (net 465))
  (segment (start 199.061733 96.204334) (end 198.157007 96.204334) (width 0.122) (layer "F.Cu") (net 465))
  (segment (start 249.2435 82.842283) (end 249.2435 83.988252) (width 0.122) (layer "F.Cu") (net 465))
  (segment (start 195.596978 95.986346) (end 195.712999 96.102367) (width 0.1) (layer "F.Cu") (net 465))
  (segment (start 246.650861 91.952079) (end 246.456252 92.146688) (width 0.122) (layer "F.Cu") (net 465))
  (segment (start 254.225 82.715) (end 253.927079 82.417079) (width 0.122) (layer "F.Cu") (net 465))
  (arc (start 247.458252 91.8935) (mid 247.597931 91.865716) (end 247.716346 91.786594) (width 0.122) (layer "F.Cu") (net 465))
  (arc (start 199.061733 96.204334) (mid 199.354485 96.146102) (end 199.602669 95.980271) (width 0.122) (layer "F.Cu") (net 465))
  (arc (start 240.306881 93.8135) (mid 240.752707 93.72482) (end 241.13066 93.47228) (width 0.122) (layer "F.Cu") (net 465))
  (arc (start 246.198158 92.253594) (mid 246.337837 92.22581) (end 246.456252 92.146688) (width 0.122) (layer "F.Cu") (net 465))
  (arc (start 249.302079 82.700861) (mid 249.258724 82.765746) (end 249.2435 82.842283) (width 0.122) (layer "F.Cu") (net 465))
  (arc (start 245.701842 92.253594) (mid 245.562163 92.22581) (end 245.443748 92.146688) (width 0.122) (layer "F.Cu") (net 465))
  (arc (start 195.712999 96.102367) (mid 195.774639 96.143554) (end 195.847349 96.158016) (width 0.1) (layer "F.Cu") (net 465))
  (arc (start 249.2435 83.988252) (mid 249.215716 84.127931) (end 249.136594 84.246346) (width 0.122) (layer "F.Cu") (net 465))
  (arc (start 246.792283 91.8935) (mid 246.715746 91.908724) (end 246.650861 91.952079) (width 0.122) (layer "F.Cu") (net 465))
  (arc (start 250.312283 81.7735) (mid 250.235747 81.788724) (end 250.170862 81.832078) (width 0.122) (layer "F.Cu") (net 465))
  (arc (start 198.154623 96.20195) (mid 198.10596 96.169434) (end 198.048557 96.158016) (width 0.1) (layer "F.Cu") (net 465))
  (arc (start 201.976547 93.8135) (mid 201.785205 93.85156) (end 201.622993 93.959947) (width 0.122) (layer "F.Cu") (net 465))
  (arc (start 248.0035 91.348252) (mid 247.975716 91.487931) (end 247.896594 91.606346) (width 0.122) (layer "F.Cu") (net 465))
  (arc (start 248.062079 85.320861) (mid 248.018724 85.385746) (end 248.0035 85.462283) (width 0.122) (layer "F.Cu") (net 465))
  (arc (start 195.512039 95.656055) (mid 195.533716 95.688497) (end 195.541328 95.726765) (width 0.1) (layer "F.Cu") (net 465))
  (arc (start 245.249138 91.952078) (mid 245.184253 91.908724) (end 245.107717 91.8935) (width 0.122) (layer "F.Cu") (net 465))
  (arc (start 252.939139 81.832079) (mid 252.874254 81.788724) (end 252.797717 81.7735) (width 0.122) (layer "F.Cu") (net 465))
  (arc (start 242.650861 91.952079) (mid 242.715746 91.908724) (end 242.792283 91.8935) (width 0.122) (layer "F.Cu") (net 465))
  (arc (start 195.445282 95.589298) (mid 195.41284 95.56762) (end 195.374571 95.560008) (width 0.1) (layer "F.Cu") (net 465))
  (arc (start 253.616748 82.3585) (mid 253.477069 82.330716) (end 253.358654 82.251594) (width 0.122) (layer "F.Cu") (net 465))
  (arc (start 253.927079 82.417079) (mid 253.862194 82.373724) (end 253.785657 82.3585) (width 0.122) (layer "F.Cu") (net 465))
  (arc (start 195.541328 95.851995) (mid 195.555791 95.924705) (end 195.596978 95.986346) (width 0.1) (layer "F.Cu") (net 465))
  (segment (start 255.195 81.73) (end 255.492922 82.027922) (width 0.122) (layer "F.Cu") (net 466))
  (segment (start 255.634343 82.0865) (end 255.811657 82.0865) (width 0.122) (layer "F.Cu") (net 466))
  (segment (start 255.953079 82.027921) (end 256.08 81.901) (width 0.122) (layer "F.Cu") (net 466))
  (via (at 256.08 81.886) (size 0.5) (drill 0.2) (layers "F.Cu" "B.Cu") (net 466))
  (arc (start 255.811657 82.0865) (mid 255.888194 82.071276) (end 255.953079 82.027921) (width 0.122) (layer "F.Cu") (net 466))
  (arc (start 255.492922 82.027922) (mid 255.557807 82.071276) (end 255.634343 82.0865) (width 0.122) (layer "F.Cu") (net 466))
  (segment (start 256.669079 82.015921) (end 256.685711 81.999289) (width 0.122) (layer "B.Cu") (net 466))
  (segment (start 256.351343 82.0745) (end 256.527657 82.0745) (width 0.122) (layer "B.Cu") (net 466))
  (segment (start 256.715 81.928579) (end 256.715 81.585) (width 0.122) (layer "B.Cu") (net 466))
  (segment (start 256.08 81.886) (end 256.209922 82.015922) (width 0.122) (layer "B.Cu") (net 466))
  (arc (start 256.685711 81.999289) (mid 256.707388 81.966847) (end 256.715 81.928579) (width 0.122) (layer "B.Cu") (net 466))
  (arc (start 256.351343 82.0745) (mid 256.274807 82.059276) (end 256.209922 82.015922) (width 0.122) (layer "B.Cu") (net 466))
  (arc (start 256.527657 82.0745) (mid 256.604194 82.059276) (end 256.669079 82.015921) (width 0.122) (layer "B.Cu") (net 466))
  (segment (start 180.136328 97.560008) (end 179.636328 98.060008) (width 0.1) (layer "F.Cu") (net 472))
  (via (at 179.636328 98.060008) (size 0.5) (drill 0.2) (layers "F.Cu" "B.Cu") (net 472))
  (via (at 245.92 99.06) (size 0.5) (drill 0.2) (layers "F.Cu" "B.Cu") (net 472))
  (segment (start 185.621 102.03947) (end 185.621 102.262) (width 0.09) (layer "In7.Cu") (net 472))
  (segment (start 179.636328 98.348328) (end 179.748008 98.460008) (width 0.09) (layer "In7.Cu") (net 472))
  (segment (start 202.247866 102.54) (end 198.207 102.54) (width 0.1) (layer "In7.Cu") (net 472))
  (segment (start 245.712134 99.6) (end 245.262134 99.15) (width 0.1) (layer "In7.Cu") (net 472))
  (segment (start 184.421 101.93947) (end 184.421 103.03453) (width 0.09) (layer "In7.Cu") (net 472))
  (segment (start 181.02243 98.460008) (end 183.059 100.496578) (width 0.09) (layer "In7.Cu") (net 472))
  (segment (start 184.821 103.03453) (end 184.821 102.03947) (width 0.09) (layer "In7.Cu") (net 472))
  (segment (start 242.25 98.5) (end 242.25 98.95) (width 0.1) (layer "In7.Cu") (net 472))
  (segment (start 246.51 99.261796) (end 246.171796 99.6) (width 0.1) (layer "In7.Cu") (net 472))
  (segment (start 183.254422 102.462) (end 183.421 102.462) (width 0.09) (layer "In7.Cu") (net 472))
  (segment (start 246.335867 98.878001) (end 246.51 99.052134) (width 0.1) (layer "In7.Cu") (net 472))
  (segment (start 186.367 102.337) (end 186.367 102.332118) (width 0.09) (layer "In7.Cu") (net 472))
  (segment (start 246.101999 98.878001) (end 246.335867 98.878001) (width 0.1) (layer "In7.Cu") (net 472))
  (segment (start 243.755 98.725) (end 243.755 98.975) (width 0.1) (layer "In7.Cu") (net 472))
  (segment (start 243.53 99.15) (end 243.45 99.15) (width 0.1) (layer "In7.Cu") (net 472))
  (segment (start 198.18529 102.56171) (end 198.207 102.54) (width 0.09) (layer "In7.Cu") (net 472))
  (segment (start 243.58 99.15) (end 243.53 99.15) (width 0.1) (layer "In7.Cu") (net 472))
  (segment (start 185.821 102.462) (end 186.242 102.462) (width 0.09) (layer "In7.Cu") (net 472))
  (segment (start 183.621 102.262) (end 183.621 101.93947) (width 0.09) (layer "In7.Cu") (net 472))
  (segment (start 186.742 102.462) (end 192.183422 102.462) (width 0.09) (layer "In7.Cu") (net 472))
  (segment (start 179.748008 98.460008) (end 181.02243 98.460008) (width 0.09) (layer "In7.Cu") (net 472))
  (segment (start 244.105 98.975) (end 244.105 98.725) (width 0.1) (layer "In7.Cu") (net 472))
  (segment (start 243.25 98.95) (end 243.25 98.5) (width 0.1) (layer "In7.Cu") (net 472))
  (segment (start 246.51 99.052134) (end 246.51 99.261796) (width 0.1) (layer "In7.Cu") (net 472))
  (segment (start 192.312422 102.591) (end 198.114579 102.591) (width 0.09) (layer "In7.Cu") (net 472))
  (segment (start 186.617 102.332118) (end 186.617 102.337) (width 0.09) (layer "In7.Cu") (net 472))
  (segment (start 183.059 100.496578) (end 183.059 102.266578) (width 0.09) (layer "In7.Cu") (net 472))
  (segment (start 183.059 102.266578) (end 183.254422 102.462) (width 0.09) (layer "In7.Cu") (net 472))
  (segment (start 245.92 99.06) (end 246.101999 98.878001) (width 0.1) (layer "In7.Cu") (net 472))
  (segment (start 242.05 99.15) (end 205.637866 99.15) (width 0.1) (layer "In7.Cu") (net 472))
  (segment (start 245.262134 99.15) (end 244.28 99.15) (width 0.1) (layer "In7.Cu") (net 472))
  (segment (start 192.183422 102.462) (end 192.312422 102.591) (width 0.09) (layer "In7.Cu") (net 472))
  (segment (start 179.636328 98.060008) (end 179.636328 98.348328) (width 0.09) (layer "In7.Cu") (net 472))
  (segment (start 205.637866 99.15) (end 202.247866 102.54) (width 0.1) (layer "In7.Cu") (net 472))
  (segment (start 246.171796 99.6) (end 245.712134 99.6) (width 0.1) (layer "In7.Cu") (net 472))
  (arc (start 198.114579 102.591) (mid 198.152848 102.583388) (end 198.18529 102.56171) (width 0.09) (layer "In7.Cu") (net 472))
  (arc (start 183.421 102.462) (mid 183.562421 102.403421) (end 183.621 102.262) (width 0.09) (layer "In7.Cu") (net 472))
  (arc (start 186.367 102.332118) (mid 186.403612 102.24373) (end 186.492 102.207118) (width 0.09) (layer "In7.Cu") (net 472))
  (arc (start 185.621 102.262) (mid 185.679579 102.403421) (end 185.821 102.462) (width 0.09) (layer "In7.Cu") (net 472))
  (arc (start 243.25 98.5) (mid 243.103553 98.146447) (end 242.75 98) (width 0.1) (layer "In7.Cu") (net 472))
  (arc (start 243.45 99.15) (mid 243.308579 99.091421) (end 243.25 98.95) (width 0.1) (layer "In7.Cu") (net 472))
  (arc (start 184.821 102.03947) (mid 184.938157 101.756627) (end 185.221 101.63947) (width 0.09) (layer "In7.Cu") (net 472))
  (arc (start 242.75 98) (mid 242.396447 98.146447) (end 242.25 98.5) (width 0.1) (layer "In7.Cu") (net 472))
  (arc (start 184.021 101.53947) (mid 184.303843 101.656627) (end 184.421 101.93947) (width 0.09) (layer "In7.Cu") (net 472))
  (arc (start 183.621 101.93947) (mid 183.738157 101.656627) (end 184.021 101.53947) (width 0.09) (layer "In7.Cu") (net 472))
  (arc (start 244.105 98.725) (mid 244.053744 98.601256) (end 243.93 98.55) (width 0.1) (layer "In7.Cu") (net 472))
  (arc (start 184.421 103.03453) (mid 184.479579 103.175951) (end 184.621 103.23453) (width 0.09) (layer "In7.Cu") (net 472))
  (arc (start 186.242 102.462) (mid 186.330388 102.425388) (end 186.367 102.337) (width 0.09) (layer "In7.Cu") (net 472))
  (arc (start 184.621 103.23453) (mid 184.762421 103.175951) (end 184.821 103.03453) (width 0.09) (layer "In7.Cu") (net 472))
  (arc (start 242.25 98.95) (mid 242.191421 99.091421) (end 242.05 99.15) (width 0.1) (layer "In7.Cu") (net 472))
  (arc (start 243.755 98.975) (mid 243.703744 99.098744) (end 243.58 99.15) (width 0.1) (layer "In7.Cu") (net 472))
  (arc (start 243.93 98.55) (mid 243.806256 98.601256) (end 243.755 98.725) (width 0.1) (layer "In7.Cu") (net 472))
  (arc (start 185.221 101.63947) (mid 185.503843 101.756627) (end 185.621 102.03947) (width 0.09) (layer "In7.Cu") (net 472))
  (arc (start 186.492 102.207118) (mid 186.580388 102.24373) (end 186.617 102.332118) (width 0.09) (layer "In7.Cu") (net 472))
  (arc (start 186.617 102.337) (mid 186.653612 102.425388) (end 186.742 102.462) (width 0.09) (layer "In7.Cu") (net 472))
  (arc (start 244.28 99.15) (mid 244.156256 99.098744) (end 244.105 98.975) (width 0.1) (layer "In7.Cu") (net 472))
  (segment (start 246.483001 98.878001) (end 246.555 98.95) (width 0.1) (layer "B.Cu") (net 472))
  (segment (start 245.92 99.06) (end 246.101999 98.878001) (width 0.1) (layer "B.Cu") (net 472))
  (segment (start 246.555 98.95) (end 246.555 99.365) (width 0.1) (layer "B.Cu") (net 472))
  (segment (start 246.101999 98.878001) (end 246.483001 98.878001) (width 0.1) (layer "B.Cu") (net 472))
  (segment (start 178.69 98.006336) (end 178.69 98.08) (width 0.1) (layer "F.Cu") (net 473))
  (segment (start 179.136328 97.560008) (end 178.69 98.006336) (width 0.1) (layer "F.Cu") (net 473))
  (via (at 244.65 97.126) (size 0.5) (drill 0.2) (layers "F.Cu" "B.Cu") (net 473))
  (via (at 178.69 98.08) (size 0.5) (drill 0.2) (layers "F.Cu" "B.Cu") (net 473))
  (segment (start 184.41349 99.585869) (end 184.413489 99.58587) (width 0.09) (layer "In7.Cu") (net 473))
  (segment (start 185.14397 100.917392) (end 184.820074 100.593495) (width 0.09) (layer "In7.Cu") (net 473))
  (segment (start 245.053956 96.7) (end 244.242 96.7) (width 0.1) (layer "In7.Cu") (net 473))
  (segment (start 183.86548 100.699561) (end 183.865479 100.699561) (width 0.09) (layer "In7.Cu") (net 473))
  (segment (start 180.331422 97.661) (end 178.81 97.661) (width 0.09) (layer "In7.Cu") (net 473))
  (segment (start 182.687106 98.460526) (end 182.687106 98.460525) (width 0.09) (layer "In7.Cu") (net 473))
  (segment (start 198.106091 101.510512) (end 197.17491 101.510512) (width 0.09) (layer "In7.Cu") (net 473))
  (segment (start 243.112134 96.7) (end 243.542 96.7) (width 0.1) (layer "In7.Cu") (net 473))
  (segment (start 244.65 97.136) (end 244.821999 97.307999) (width 0.1) (layer "In7.Cu") (net 473))
  (segment (start 180.514422 97.478) (end 180.331422 97.661) (width 0.09) (layer "In7.Cu") (net 473))
  (segment (start 186.038578 101.812) (end 185.92179 101.69521) (width 0.09) (layer "In7.Cu") (net 473))
  (segment (start 183.564961 98.737341) (end 183.56496 98.737342) (width 0.09) (layer "In7.Cu") (net 473))
  (segment (start 243.112134 96.7) (end 241.662134 98.15) (width 0.1) (layer "In7.Cu") (net 473))
  (segment (start 244.067 96.875) (end 244.067 97.111899) (width 0.1) (layer "In7.Cu") (net 473))
  (segment (start 181.909289 97.682711) (end 181.704578 97.478) (width 0.09) (layer "In7.Cu") (net 473))
  (segment (start 244.821999 97.307999) (end 245.055867 97.307999) (width 0.1) (layer "In7.Cu") (net 473))
  (segment (start 181.90929 97.682709) (end 181.909289 97.682711) (width 0.09) (layer "In7.Cu") (net 473))
  (segment (start 184.431165 100.699561) (end 184.431165 100.69956) (width 0.09) (layer "In7.Cu") (net 473))
  (segment (start 186.052418 100.539273) (end 185.674299 100.917392) (width 0.09) (layer "In7.Cu") (net 473))
  (segment (start 183.458895 98.454499) (end 183.458896 98.454499) (width 0.09) (layer "In7.Cu") (net 473))
  (segment (start 183.86548 100.133876) (end 184.41349 99.585869) (width 0.09) (layer "In7.Cu") (net 473))
  (segment (start 182.262842 98.637302) (end 182.262843 98.637301) (width 0.09) (layer "In7.Cu") (net 473))
  (segment (start 183.971548 99.462127) (end 183.900836 99.532836) (width 0.09) (layer "In7.Cu") (net 473))
  (segment (start 181.704578 97.478) (end 180.514422 97.478) (width 0.09) (layer "In7.Cu") (net 473))
  (segment (start 184.307424 99.303027) (end 184.307423 99.303027) (width 0.09) (layer "In7.Cu") (net 473))
  (segment (start 184.130646 99.303026) (end 183.971548 99.462127) (width 0.09) (layer "In7.Cu") (net 473))
  (segment (start 205.062134 98.15) (end 201.652134 101.56) (width 0.1) (layer "In7.Cu") (net 473))
  (segment (start 244.65 97.126) (end 244.65 97.136) (width 0.1) (layer "In7.Cu") (net 473))
  (segment (start 183.900836 99.532836) (end 183.441217 99.992456) (width 0.09) (layer "In7.Cu") (net 473))
  (segment (start 243.717 97.111899) (end 243.717 96.875) (width 0.1) (layer "In7.Cu") (net 473))
  (segment (start 189.472713 101.665008) (end 189.325721 101.812) (width 0.09) (layer "In7.Cu") (net 473))
  (segment (start 185.921789 101.164881) (end 186.299907 100.786761) (width 0.09) (layer "In7.Cu") (net 473))
  (segment (start 183.282119 98.4545) (end 183.211408 98.52521) (width 0.09) (layer "In7.Cu") (net 473))
  (segment (start 195.023586 101.665008) (end 189.472713 101.665008) (width 0.09) (layer "In7.Cu") (net 473))
  (segment (start 184.537231 100.593494) (end 184.431165 100.699561) (width 0.09) (layer "In7.Cu") (net 473))
  (segment (start 186.052418 100.539272) (end 186.052418 100.539273) (width 0.09) (layer "In7.Cu") (net 473))
  (segment (start 182.751788 98.525209) (end 182.687106 98.460526) (width 0.09) (layer "In7.Cu") (net 473))
  (segment (start 198.197 101.56) (end 198.176802 101.539802) (width 0.09) (layer "In7.Cu") (net 473))
  (segment (start 183.564961 98.560565) (end 183.458895 98.454499) (width 0.09) (layer "In7.Cu") (net 473))
  (segment (start 245.25 96.896044) (end 245.053956 96.7) (width 0.1) (layer "In7.Cu") (net 473))
  (segment (start 185.143969 100.917392) (end 185.14397 100.917392) (width 0.09) (layer "In7.Cu") (net 473))
  (segment (start 189.325721 101.812) (end 186.038578 101.812) (width 0.09) (layer "In7.Cu") (net 473))
  (segment (start 197.17491 101.510512) (end 196.585422 102.1) (width 0.09) (layer "In7.Cu") (net 473))
  (segment (start 182.439617 98.460526) (end 182.262842 98.637302) (width 0.09) (layer "In7.Cu") (net 473))
  (segment (start 201.652134 101.56) (end 198.197 101.56) (width 0.1) (layer "In7.Cu") (net 473))
  (segment (start 195.458578 102.1) (end 195.023586 101.665008) (width 0.09) (layer "In7.Cu") (net 473))
  (segment (start 181.732514 98.637302) (end 181.732513 98.637302) (width 0.09) (layer "In7.Cu") (net 473))
  (segment (start 181.732514 98.106973) (end 181.90929 97.930198) (width 0.09) (layer "In7.Cu") (net 473))
  (segment (start 178.69 97.781) (end 178.69 98.08) (width 0.09) (layer "In7.Cu") (net 473))
  (segment (start 184.41349 99.409093) (end 184.307424 99.303027) (width 0.09) (layer "In7.Cu") (net 473))
  (segment (start 178.81 97.661) (end 178.69 97.781) (width 0.09) (layer "In7.Cu") (net 473))
  (segment locked (start 205.062134 98.15) (end 241.662134 98.15) (width 0.1) (layer "In7.Cu") (net 473))
  (segment (start 196.585422 102.1) (end 195.458578 102.1) (width 0.09) (layer "In7.Cu") (net 473))
  (segment (start 245.055867 97.307999) (end 245.25 97.113866) (width 0.1) (layer "In7.Cu") (net 473))
  (segment (start 181.90929 97.930198) (end 181.90929 97.930199) (width 0.09) (layer "In7.Cu") (net 473))
  (segment (start 183.211408 98.52521) (end 183.21141 98.525211) (width 0.09) (layer "In7.Cu") (net 473))
  (segment (start 182.875532 99.426771) (end 183.564961 98.737341) (width 0.09) (layer "In7.Cu") (net 473))
  (segment (start 245.25 97.113866) (end 245.25 96.896044) (width 0.1) (layer "In7.Cu") (net 473))
  (arc (start 182.875532 99.992457) (mid 182.758375 99.709614) (end 182.875532 99.426771) (width 0.09) (layer "In7.Cu") (net 473))
  (arc (start 181.732513 98.637302) (mid 181.622679 98.372137) (end 181.732514 98.106973) (width 0.09) (layer "In7.Cu") (net 473))
  (arc (start 184.307423 99.303027) (mid 184.219035 99.266415) (end 184.130646 99.303026) (width 0.09) (layer "In7.Cu") (net 473))
  (arc (start 184.413489 99.58587) (mid 184.450101 99.497482) (end 184.41349 99.409093) (width 0.09) (layer "In7.Cu") (net 473))
  (arc (start 185.674299 100.917392) (mid 185.409134 101.027227) (end 185.143969 100.917392) (width 0.09) (layer "In7.Cu") (net 473))
  (arc (start 184.431165 100.69956) (mid 184.148323 100.816718) (end 183.86548 100.699561) (width 0.09) (layer "In7.Cu") (net 473))
  (arc (start 243.717 96.875) (mid 243.665744 96.751256) (end 243.542 96.7) (width 0.1) (layer "In7.Cu") (net 473))
  (arc (start 183.56496 98.737342) (mid 183.601572 98.648954) (end 183.564961 98.560565) (width 0.09) (layer "In7.Cu") (net 473))
  (arc (start 181.90929 97.930199) (mid 181.960547 97.806454) (end 181.90929 97.682709) (width 0.09) (layer "In7.Cu") (net 473))
  (arc (start 243.892 97.286899) (mid 243.768256 97.235643) (end 243.717 97.111899) (width 0.1) (layer "In7.Cu") (net 473))
  (arc (start 182.687106 98.460525) (mid 182.563361 98.409269) (end 182.439617 98.460526) (width 0.09) (layer "In7.Cu") (net 473))
  (arc (start 183.441217 99.992456) (mid 183.158375 100.109614) (end 182.875532 99.992457) (width 0.09) (layer "In7.Cu") (net 473))
  (arc (start 244.067 97.111899) (mid 244.015744 97.235643) (end 243.892 97.286899) (width 0.1) (layer "In7.Cu") (net 473))
  (arc (start 183.458896 98.454499) (mid 183.370507 98.417888) (end 183.282119 98.4545) (width 0.09) (layer "In7.Cu") (net 473))
  (arc (start 183.21141 98.525211) (mid 182.9816 98.620401) (end 182.751788 98.525209) (width 0.09) (layer "In7.Cu") (net 473))
  (arc (start 186.299907 100.786761) (mid 186.351163 100.663017) (end 186.299907 100.539273) (width 0.09) (layer "In7.Cu") (net 473))
  (arc (start 182.262843 98.637301) (mid 181.997679 98.747136) (end 181.732514 98.637302) (width 0.09) (layer "In7.Cu") (net 473))
  (arc (start 184.820074 100.593495) (mid 184.678653 100.534916) (end 184.537231 100.593494) (width 0.09) (layer "In7.Cu") (net 473))
  (arc (start 183.865479 100.699561) (mid 183.748322 100.416718) (end 183.86548 100.133876) (width 0.09) (layer "In7.Cu") (net 473))
  (arc (start 186.299907 100.539273) (mid 186.176163 100.488016) (end 186.052418 100.539272) (width 0.09) (layer "In7.Cu") (net 473))
  (arc (start 185.92179 101.69521) (mid 185.811955 101.430046) (end 185.921789 101.164881) (width 0.09) (layer "In7.Cu") (net 473))
  (arc (start 244.242 96.7) (mid 244.118256 96.751256) (end 244.067 96.875) (width 0.1) (layer "In7.Cu") (net 473))
  (arc (start 198.176802 101.539802) (mid 198.14436 101.518124) (end 198.106091 101.510512) (width 0.09) (layer "In7.Cu") (net 473))
  (segment (start 244.65 97.126) (end 244.831999 97.307999) (width 0.1) (layer "B.Cu") (net 473))
  (segment (start 244.831999 97.307999) (end 245.182001 97.307999) (width 0.1) (layer "B.Cu") (net 473))
  (segment (start 245.285 97.205) (end 245.285 96.825) (width 0.1) (layer "B.Cu") (net 473))
  (segment (start 245.182001 97.307999) (end 245.285 97.205) (width 0.1) (layer "B.Cu") (net 473))
  (segment (start 177.636328 98.060008) (end 178.136328 97.560008) (width 0.1) (layer "F.Cu") (net 474))
  (via (at 177.636328 98.060008) (size 0.5) (drill 0.2) (layers "F.Cu" "B.Cu") (net 474))
  (via (at 244.65 105.41) (size 0.5) (drill 0.2) (layers "F.Cu" "B.Cu") (net 474))
  (segment (start 177.241328 98.455008) (end 177.636328 98.060008) (width 0.09) (layer "In7.Cu") (net 474))
  (segment (start 180.374 105.145866) (end 180.374 103.947866) (width 0.1) (layer "In7.Cu") (net 474))
  (segment (start 244.65 105.41) (end 244.831999 105.228001) (width 0.1) (layer "In7.Cu") (net 474))
  (segment (start 191.037134 105.925) (end 181.153134 105.925) (width 0.1) (layer "In7.Cu") (net 474))
  (segment (start 177.408 101.401854) (end 177.408 100.965578) (width 0.09) (layer "In7.Cu") (net 474))
  (segment (start 208.337866 102.95) (end 205.362866 105.925) (width 0.1) (layer "In7.Cu") (net 474))
  (segment (start 199.982866 105.925) (end 199.357866 106.55) (width 0.1) (layer "In7.Cu") (net 474))
  (segment (start 245.54 104.419936) (end 245.54 104.878134) (width 0.1) (layer "In7.Cu") (net 474))
  (segment (start 177.631134 103.364) (end 177.459837 103.192703) (width 0.1) (layer "In7.Cu") (net 474))
  (segment (start 180.374 103.947866) (end 179.790134 103.364) (width 0.1) (layer "In7.Cu") (net 474))
  (segment (start 245.190133 105.228001) (end 244.831999 105.228001) (width 0.1) (layer "In7.Cu") (net 474))
  (segment (start 245.54 104.878134) (end 245.190133 105.228001) (width 0.1) (layer "In7.Cu") (net 474))
  (segment locked (start 232.962134 102.95) (end 233.849647 103.837513) (width 0.1) (layer "In7.Cu") (net 474))
  (segment (start 205.362866 105.925) (end 199.982866 105.925) (width 0.1) (layer "In7.Cu") (net 474))
  (segment (start 177.459837 101.453691) (end 177.408 101.401854) (width 0.09) (layer "In7.Cu") (net 474))
  (segment (start 177.241328 100.798906) (end 177.241328 98.455008) (width 0.09) (layer "In7.Cu") (net 474))
  (segment (start 233.849647 103.837513) (end 244.957577 103.837513) (width 0.1) (layer "In7.Cu") (net 474))
  (segment (start 179.790134 103.364) (end 177.631134 103.364) (width 0.1) (layer "In7.Cu") (net 474))
  (segment (start 232.962134 102.95) (end 208.337866 102.95) (width 0.1) (layer "In7.Cu") (net 474))
  (segment (start 177.459837 103.192703) (end 177.459837 101.453691) (width 0.1) (layer "In7.Cu") (net 474))
  (segment (start 181.153134 105.925) (end 180.374 105.145866) (width 0.1) (layer "In7.Cu") (net 474))
  (segment (start 191.662134 106.55) (end 191.037134 105.925) (width 0.1) (layer "In7.Cu") (net 474))
  (segment (start 199.357866 106.55) (end 191.662134 106.55) (width 0.1) (layer "In7.Cu") (net 474))
  (segment (start 177.408 100.965578) (end 177.241328 100.798906) (width 0.09) (layer "In7.Cu") (net 474))
  (segment (start 244.957577 103.837513) (end 245.54 104.419936) (width 0.1) (layer "In7.Cu") (net 474))
  (segment (start 244.831999 105.228001) (end 245.213001 105.228001) (width 0.1) (layer "B.Cu") (net 474))
  (segment (start 244.65 105.41) (end 244.831999 105.228001) (width 0.1) (layer "B.Cu") (net 474))
  (segment (start 245.213001 105.228001) (end 245.285 105.3) (width 0.1) (layer "B.Cu") (net 474))
  (segment (start 245.285 105.3) (end 245.285 105.715) (width 0.1) (layer "B.Cu") (net 474))
  (segment (start 177.136328 97.560008) (end 176.636328 98.060008) (width 0.1) (layer "F.Cu") (net 475))
  (via (at 176.636328 98.060008) (size 0.5) (drill 0.2) (layers "F.Cu" "B.Cu") (net 475))
  (via (at 244.65 116.176) (size 0.5) (drill 0.2) (layers "F.Cu" "B.Cu") (net 475))
  (segment (start 244.067 115.875) (end 244.067 116.14416) (width 0.1) (layer "In9.Cu") (net 475))
  (segment (start 235.736313 102.748447) (end 232.917866 99.93) (width 0.1) (layer "In9.Cu") (net 475))
  (segment (start 194.257866 97.92) (end 193.623933 97.286067) (width 0.1) (layer "In9.Cu") (net 475))
  (segment (start 180.376414 97.665008) (end 180.671422 97.37) (width 0.09) (layer "In9.Cu") (net 475))
  (segment (start 244.831999 116.357999) (end 245.029867 116.357999) (width 0.1) (layer "In9.Cu") (net 475))
  (segment (start 182.789 97.57) (end 182.789 97.971124) (width 0.09) (layer "In9.Cu") (net 475))
  (segment (start 239.35 109.062134) (end 237.85 107.562134) (width 0.1) (layer "In9.Cu") (net 475))
  (segment (start 177.031328 97.665008) (end 180.376414 97.665008) (width 0.09) (layer "In9.Cu") (net 475))
  (segment (start 237.85 107.562134) (end 237.85 104.112134) (width 0.1) (layer "In9.Cu") (net 475))
  (segment (start 183.789 97.37) (end 190.371422 97.37) (width 0.09) (layer "In9.Cu") (net 475))
  (segment (start 245.087866 115.7) (end 244.242 115.7) (width 0.1) (layer "In9.Cu") (net 475))
  (segment (start 196.557866 97.92) (end 194.257866 97.92) (width 0.1) (layer "In9.Cu") (net 475))
  (segment (start 193.623933 97.284641) (end 193.623933 97.286067) (width 0.09) (layer "In9.Cu") (net 475))
  (segment (start 241.25 112.212134) (end 239.35 110.312134) (width 0.1) (layer "In9.Cu") (net 475))
  (segment (start 183.589 97.971124) (end 183.589 97.57) (width 0.09) (layer "In9.Cu") (net 475))
  (segment (start 191.141422 96.6) (end 193.001424 96.6) (width 0.09) (layer "In9.Cu") (net 475))
  (segment (start 245.25 115.862134) (end 245.087866 115.7) (width 0.1) (layer "In9.Cu") (net 475))
  (segment (start 243.109452 115.7) (end 243.087866 115.7) (width 0.1) (layer "In9.Cu") (net 475))
  (segment (start 237.85 104.112134) (end 236.486313 102.748447) (width 0.1) (layer "In9.Cu") (net 475))
  (segment (start 239.35 110.312134) (end 239.35 109.062134) (width 0.1) (layer "In9.Cu") (net 475))
  (segment (start 241.25 113.062134) (end 241.25 112.212134) (width 0.1) (layer "In9.Cu") (net 475))
  (segment (start 242.15 114.762134) (end 242.15 113.962134) (width 0.1) (layer "In9.Cu") (net 475))
  (segment (start 236.486313 102.748447) (end 235.736313 102.748447) (width 0.1) (layer "In9.Cu") (net 475))
  (segment (start 245.029867 116.357999) (end 245.25 116.137866) (width 0.1) (layer "In9.Cu") (net 475))
  (segment (start 245.25 116.137866) (end 245.25 115.862134) (width 0.1) (layer "In9.Cu") (net 475))
  (segment (start 180.671422 97.37) (end 182.589 97.37) (width 0.09) (layer "In9.Cu") (net 475))
  (segment (start 232.917866 99.93) (end 198.567866 99.93) (width 0.1) (layer "In9.Cu") (net 475))
  (segment (start 190.371422 97.37) (end 191.141422 96.6) (width 0.09) (layer "In9.Cu") (net 475))
  (segment (start 243.087866 115.7) (end 242.15 114.762134) (width 0.1) (layer "In9.Cu") (net 475))
  (segment (start 198.567866 99.93) (end 196.557866 97.92) (width 0.1) (layer "In9.Cu") (net 475))
  (segment (start 244.65 116.176) (end 244.831999 116.357999) (width 0.1) (layer "In9.Cu") (net 475))
  (segment (start 243.717 116.14416) (end 243.717 115.875) (width 0.1) (layer "In9.Cu") (net 475))
  (segment (start 176.636328 98.060008) (end 177.031328 97.665008) (width 0.09) (layer "In9.Cu") (net 475))
  (segment (start 193.001424 96.6) (end 193.579999 97.178575) (width 0.09) (layer "In9.Cu") (net 475))
  (segment (start 242.15 113.962134) (end 241.25 113.062134) (width 0.1) (layer "In9.Cu") (net 475))
  (segment (start 243.542 115.7) (end 243.109452 115.7) (width 0.1) (layer "In9.Cu") (net 475))
  (arc (start 244.242 115.7) (mid 244.118256 115.751256) (end 244.067 115.875) (width 0.1) (layer "In9.Cu") (net 475))
  (arc (start 243.717 115.875) (mid 243.665744 115.751256) (end 243.542 115.7) (width 0.1) (layer "In9.Cu") (net 475))
  (arc (start 182.789 97.971124) (mid 182.906157 98.253967) (end 183.189 98.371124) (width 0.09) (layer "In9.Cu") (net 475))
  (arc (start 183.589 97.57) (mid 183.647579 97.428579) (end 183.789 97.37) (width 0.09) (layer "In9.Cu") (net 475))
  (arc (start 183.189 98.371124) (mid 183.471843 98.253967) (end 183.589 97.971124) (width 0.09) (layer "In9.Cu") (net 475))
  (arc (start 243.892 116.31916) (mid 243.768256 116.267904) (end 243.717 116.14416) (width 0.1) (layer "In9.Cu") (net 475))
  (arc (start 182.589 97.37) (mid 182.730421 97.428579) (end 182.789 97.57) (width 0.09) (layer "In9.Cu") (net 475))
  (arc (start 244.067 116.14416) (mid 244.015744 116.267904) (end 243.892 116.31916) (width 0.1) (layer "In9.Cu") (net 475))
  (arc (start 193.579999 97.178575) (mid 193.612515 97.227238) (end 193.623933 97.284641) (width 0.09) (layer "In9.Cu") (net 475))
  (segment (start 245.285 116.255) (end 245.285 115.875) (width 0.1) (layer "B.Cu") (net 475))
  (segment (start 245.182001 116.357999) (end 245.285 116.255) (width 0.1) (layer "B.Cu") (net 475))
  (segment (start 244.831999 116.357999) (end 245.182001 116.357999) (width 0.1) (layer "B.Cu") (net 475))
  (segment (start 244.65 116.176) (end 244.831999 116.357999) (width 0.1) (layer "B.Cu") (net 475))
  (segment (start 182.136328 96.560008) (end 181.636328 97.060008) (width 0.1) (layer "F.Cu") (net 476))
  (via blind (at 181.636328 97.060008) (size 0.5) (drill 0.2) (layers "F.Cu" "In5.Cu") (net 476))
  (via (at 248.46 91.44) (size 0.5) (drill 0.2) (layers "F.Cu" "B.Cu") (net 476))
  (segment (start 195.377866 101.95) (end 196.255 101.95) (width 0.1) (layer "In5.Cu") (net 476))
  (segment (start 190.388791 101.488791) (end 190.42 101.52) (width 0.09) (layer "In5.Cu") (net 476))
  (segment (start 197.355 100.525) (end 197.355 102.25) (width 0.1) (layer "In5.Cu") (net 476))
  (segment (start 186.703503 100.334924) (end 186.98 100.611422) (width 0.09) (layer "In5.Cu") (net 476))
  (segment (start 189.766433 101.654989) (end 189.961921 101.459501) (width 0.09) (layer "In5.Cu") (net 476))
  (segment (start 182.848578 97.66) (end 183.278578 98.09) (width 0.09) (layer "In5.Cu") (net 476))
  (segment (start 181.636328 97.060008) (end 181.920008 97.060008) (width 0.09) (layer "In5.Cu") (net 476))
  (segment (start 183.558578 98.09) (end 184.338578 98.87) (width 0.09) (layer "In5.Cu") (net 476))
  (segment (start 185.996395 99.627815) (end 185.996397 99.627818) (width 0.09) (layer "In5.Cu") (net 476))
  (segment (start 197.705 101.475) (end 197.705 100.525) (width 0.1) (layer "In5.Cu") (net 476))
  (segment (start 182.318578 97.66) (end 182.848578 97.66) (width 0.09) (layer "In5.Cu") (net 476))
  (segment (start 193.492134 101.44) (end 193.012134 101.92) (width 0.1) (layer "In5.Cu") (net 476))
  (segment (start 186.491371 99.627818) (end 186.491371 99.627817) (width 0.09) (layer "In5.Cu") (net 476))
  (segment (start 182.03 97.17) (end 182.03 97.371422) (width 0.09) (layer "In5.Cu") (net 476))
  (segment (start 195.377866 101.95) (end 194.867866 101.44) (width 0.1) (layer "In5.Cu") (net 476))
  (segment (start 240.362134 94.65) (end 205.812134 94.65) (width 0.1) (layer "In5.Cu") (net 476))
  (segment (start 183.278578 98.09) (end 183.558578 98.09) (width 0.09) (layer "In5.Cu") (net 476))
  (segment (start 247.462134 91.9) (end 246.478208 91.9) (width 0.1) (layer "In5.Cu") (net 476))
  (segment (start 191.037866 101.52) (end 190.42 101.52) (width 0.1) (layer "In5.Cu") (net 476))
  (segment (start 196.905 102.7) (end 196.855 102.7) (width 0.1) (layer "In5.Cu") (net 476))
  (segment (start 186.491371 99.627817) (end 186.768732 99.350457) (width 0.09) (layer "In5.Cu") (net 476))
  (segment (start 185.238578 98.87) (end 185.289288 98.920709) (width 0.09) (layer "In5.Cu") (net 476))
  (segment (start 248.278001 91.258001) (end 248.104133 91.258001) (width 0.1) (layer "In5.Cu") (net 476))
  (segment (start 189.961921 101.459501) (end 190.31808 101.459501) (width 0.09) (layer "In5.Cu") (net 476))
  (segment (start 186.238402 98.890837) (end 185.996395 99.132841) (width 0.09) (layer "In5.Cu") (net 476))
  (segment (start 243.112134 91.9) (end 240.362134 94.65) (width 0.1) (layer "In5.Cu") (net 476))
  (segment (start 186.980863 99.56259) (end 186.980864 99.562589) (width 0.09) (layer "In5.Cu") (net 476))
  (segment (start 246.218226 92.159981) (end 245.621773 92.159981) (width 0.1) (layer "In5.Cu") (net 476))
  (segment (start 205.812134 94.65) (end 198.512134 101.95) (width 0.1) (layer "In5.Cu") (net 476))
  (segment (start 185.996397 99.627818) (end 185.996395 99.627816) (width 0.09) (layer "In5.Cu") (net 476))
  (segment (start 246.478208 91.9) (end 246.218226 92.159981) (width 0.1) (layer "In5.Cu") (net 476))
  (segment (start 181.920008 97.060008) (end 182.03 97.17) (width 0.09) (layer "In5.Cu") (net 476))
  (segment (start 198.512134 101.95) (end 198.18 101.95) (width 0.1) (layer "In5.Cu") (net 476))
  (segment (start 196.405 102.25) (end 196.405 102.1) (width 0.1) (layer "In5.Cu") (net 476))
  (segment (start 184.338578 98.87) (end 185.238578 98.87) (width 0.09) (layer "In5.Cu") (net 476))
  (segment (start 248.46 91.44) (end 248.278001 91.258001) (width 0.1) (layer "In5.Cu") (net 476))
  (segment (start 186.703502 100.334922) (end 186.703503 100.334924) (width 0.09) (layer "In5.Cu") (net 476))
  (segment (start 245.361792 91.9) (end 243.112134 91.9) (width 0.1) (layer "In5.Cu") (net 476))
  (segment (start 187.323567 101.654989) (end 189.766433 101.654989) (width 0.09) (layer "In5.Cu") (net 476))
  (segment (start 185.784264 98.92071) (end 186.02627 98.678705) (width 0.09) (layer "In5.Cu") (net 476))
  (segment (start 186.238401 98.890838) (end 186.238402 98.890837) (width 0.09) (layer "In5.Cu") (net 476))
  (segment (start 186.980864 99.562589) (end 186.703502 99.839948) (width 0.09) (layer "In5.Cu") (net 476))
  (segment (start 194.867866 101.44) (end 193.492134 101.44) (width 0.1) (layer "In5.Cu") (net 476))
  (segment (start 186.98 101.311422) (end 187.323567 101.654989) (width 0.09) (layer "In5.Cu") (net 476))
  (segment (start 191.437866 101.92) (end 191.037866 101.52) (width 0.1) (layer "In5.Cu") (net 476))
  (segment (start 245.621773 92.159981) (end 245.361792 91.9) (width 0.1) (layer "In5.Cu") (net 476))
  (segment (start 248.104133 91.258001) (end 247.462134 91.9) (width 0.1) (layer "In5.Cu") (net 476))
  (segment (start 185.784264 98.920711) (end 185.784264 98.92071) (width 0.09) (layer "In5.Cu") (net 476))
  (segment (start 185.996396 99.627816) (end 185.996395 99.627815) (width 0.09) (layer "In5.Cu") (net 476))
  (segment (start 182.03 97.371422) (end 182.318578 97.66) (width 0.09) (layer "In5.Cu") (net 476))
  (segment (start 186.98 100.611422) (end 186.98 101.311422) (width 0.09) (layer "In5.Cu") (net 476))
  (segment (start 193.012134 101.92) (end 191.437866 101.92) (width 0.1) (layer "In5.Cu") (net 476))
  (arc (start 185.289288 98.920709) (mid 185.536776 99.023222) (end 185.784264 98.920711) (width 0.09) (layer "In5.Cu") (net 476))
  (arc (start 196.405 102.1) (mid 196.361066 101.993934) (end 196.255 101.95) (width 0.1) (layer "In5.Cu") (net 476))
  (arc (start 186.703502 99.839948) (mid 186.600991 100.087436) (end 186.703502 100.334922) (width 0.09) (layer "In5.Cu") (net 476))
  (arc (start 197.355 102.25) (mid 197.223198 102.568198) (end 196.905 102.7) (width 0.1) (layer "In5.Cu") (net 476))
  (arc (start 196.855 102.7) (mid 196.536802 102.568198) (end 196.405 102.25) (width 0.1) (layer "In5.Cu") (net 476))
  (arc (start 190.31808 101.459501) (mid 190.356349 101.467113) (end 190.388791 101.488791) (width 0.09) (layer "In5.Cu") (net 476))
  (arc (start 197.53 100.35) (mid 197.406256 100.401256) (end 197.355 100.525) (width 0.1) (layer "In5.Cu") (net 476))
  (arc (start 186.980864 99.350457) (mid 187.024797 99.456523) (end 186.980863 99.56259) (width 0.09) (layer "In5.Cu") (net 476))
  (arc (start 186.768732 99.350457) (mid 186.874798 99.306523) (end 186.980864 99.350457) (width 0.09) (layer "In5.Cu") (net 476))
  (arc (start 197.705 100.525) (mid 197.653744 100.401256) (end 197.53 100.35) (width 0.1) (layer "In5.Cu") (net 476))
  (arc (start 185.996395 99.627816) (mid 186.243883 99.730329) (end 186.491371 99.627818) (width 0.09) (layer "In5.Cu") (net 476))
  (arc (start 186.238402 98.678705) (mid 186.282335 98.784771) (end 186.238401 98.890838) (width 0.09) (layer "In5.Cu") (net 476))
  (arc (start 186.02627 98.678705) (mid 186.132336 98.634771) (end 186.238402 98.678705) (width 0.09) (layer "In5.Cu") (net 476))
  (arc (start 198.18 101.95) (mid 197.844124 101.810876) (end 197.705 101.475) (width 0.1) (layer "In5.Cu") (net 476))
  (arc (start 185.996395 99.132841) (mid 185.893883 99.380329) (end 185.996396 99.627816) (width 0.09) (layer "In5.Cu") (net 476))
  (segment (start 249.023001 91.258001) (end 249.095 91.33) (width 0.1) (layer "B.Cu") (net 476))
  (segment (start 248.46 91.44) (end 248.641999 91.258001) (width 0.1) (layer "B.Cu") (net 476))
  (segment (start 249.095 91.33) (end 249.095 91.745) (width 0.1) (layer "B.Cu") (net 476))
  (segment (start 248.641999 91.258001) (end 249.023001 91.258001) (width 0.1) (layer "B.Cu") (net 476))
  (segment (start 195.888773 95.968016) (end 196.558016 95.968016) (width 0.1) (layer "F.Cu") (net 479))
  (segment (start 242.741748 91.6065) (end 245.158252 91.6065) (width 0.122) (layer "F.Cu") (net 479))
  (segment (start 201.926012 93.5265) (end 240.256346 93.5265) (width 0.122) (layer "F.Cu") (net 479))
  (segment (start 199.406172 95.770888) (end 201.455786 93.721274) (width 0.122) (layer "F.Cu") (net 479))
  (segment (start 195.760618 95.881282) (end 195.818063 95.938727) (width 0.1) (layer "F.Cu") (net 479))
  (segment (start 249.063406 82.533654) (end 250.003654 81.593406) (width 0.122) (layer "F.Cu") (net 479))
  (segment (start 245.416346 91.713406) (end 245.610956 91.908016) (width 0.122) (layer "F.Cu") (net 479))
  (segment (start 198.157007 95.917334) (end 199.052619 95.917334) (width 0.122) (layer "F.Cu") (net 479))
  (segment (start 247.549139 91.547921) (end 247.657922 91.439138) (width 0.122) (layer "F.Cu") (net 479))
  (segment (start 253.927079 82.012921) (end 254.225 81.715) (width 0.122) (layer "F.Cu") (net 479))
  (segment (start 247.823406 85.153654) (end 248.897922 84.079138) (width 0.122) (layer "F.Cu") (net 479))
  (segment (start 250.261748 81.4865) (end 252.848252 81.4865) (width 0.122) (layer "F.Cu") (net 479))
  (segment (start 245.752377 91.966594) (end 246.147623 91.966594) (width 0.122) (layer "F.Cu") (net 479))
  (segment (start 247.7165 91.297717) (end 247.7165 85.411748) (width 0.122) (layer "F.Cu") (net 479))
  (segment (start 248.9565 83.937717) (end 248.9565 82.791748) (width 0.122) (layer "F.Cu") (net 479))
  (segment (start 196.933016 95.818923) (end 196.933016 95.843016) (width 0.1) (layer "F.Cu") (net 479))
  (segment (start 246.289045 91.908015) (end 246.483654 91.713406) (width 0.122) (layer "F.Cu") (net 479))
  (segment (start 197.058016 95.968016) (end 198.044193 95.968016) (width 0.1) (layer "F.Cu") (net 479))
  (segment (start 253.667283 82.0715) (end 253.785657 82.0715) (width 0.122) (layer "F.Cu") (net 479))
  (segment (start 195.731328 95.714109) (end 195.731328 95.810571) (width 0.1) (layer "F.Cu") (net 479))
  (segment (start 246.741748 91.6065) (end 247.407717 91.6065) (width 0.122) (layer "F.Cu") (net 479))
  (segment (start 240.963453 93.233607) (end 242.483654 91.713406) (width 0.122) (layer "F.Cu") (net 479))
  (segment (start 196.683016 95.843016) (end 196.683016 95.818923) (width 0.1) (layer "F.Cu") (net 479))
  (segment (start 196.136328 95.560008) (end 195.885429 95.560008) (width 0.1) (layer "F.Cu") (net 479))
  (segment (start 253.106346 81.593406) (end 253.525862 82.012922) (width 0.122) (layer "F.Cu") (net 479))
  (segment (start 198.150259 95.924082) (end 198.157007 95.917334) (width 0.1) (layer "F.Cu") (net 479))
  (segment (start 195.814718 95.589298) (end 195.760617 95.643399) (width 0.1) (layer "F.Cu") (net 479))
  (arc (start 195.731328 95.810571) (mid 195.73894 95.84884) (end 195.760618 95.881282) (width 0.1) (layer "F.Cu") (net 479))
  (arc (start 247.7165 91.297717) (mid 247.701276 91.374253) (end 247.657922 91.439138) (width 0.122) (layer "F.Cu") (net 479))
  (arc (start 198.044193 95.968016) (mid 198.101596 95.956598) (end 198.150259 95.924082) (width 0.1) (layer "F.Cu") (net 479))
  (arc (start 240.256346 93.5265) (mid 240.639029 93.45038) (end 240.963453 93.233607) (width 0.122) (layer "F.Cu") (net 479))
  (arc (start 195.885429 95.560008) (mid 195.84716 95.56762) (end 195.814718 95.589298) (width 0.1) (layer "F.Cu") (net 479))
  (arc (start 253.785657 82.0715) (mid 253.862194 82.056276) (end 253.927079 82.012921) (width 0.122) (layer "F.Cu") (net 479))
  (arc (start 247.407717 91.6065) (mid 247.484254 91.591276) (end 247.549139 91.547921) (width 0.122) (layer "F.Cu") (net 479))
  (arc (start 196.933016 95.843016) (mid 196.969628 95.931404) (end 197.058016 95.968016) (width 0.1) (layer "F.Cu") (net 479))
  (arc (start 196.558016 95.968016) (mid 196.646404 95.931404) (end 196.683016 95.843016) (width 0.1) (layer "F.Cu") (net 479))
  (arc (start 252.848252 81.4865) (mid 252.987931 81.514284) (end 253.106346 81.593406) (width 0.122) (layer "F.Cu") (net 479))
  (arc (start 245.752377 91.966594) (mid 245.675841 91.95137) (end 245.610956 91.908016) (width 0.122) (layer "F.Cu") (net 479))
  (arc (start 246.483654 91.713406) (mid 246.602069 91.634284) (end 246.741748 91.6065) (width 0.122) (layer "F.Cu") (net 479))
  (arc (start 196.683016 95.818923) (mid 196.719628 95.730535) (end 196.808016 95.693923) (width 0.1) (layer "F.Cu") (net 479))
  (arc (start 248.9565 82.791748) (mid 248.984284 82.652069) (end 249.063406 82.533654) (width 0.122) (layer "F.Cu") (net 479))
  (arc (start 195.818063 95.938727) (mid 195.850505 95.960404) (end 195.888773 95.968016) (width 0.1) (layer "F.Cu") (net 479))
  (arc (start 195.760617 95.643399) (mid 195.73894 95.675841) (end 195.731328 95.714109) (width 0.1) (layer "F.Cu") (net 479))
  (arc (start 248.897922 84.079138) (mid 248.941276 84.014253) (end 248.9565 83.937717) (width 0.122) (layer "F.Cu") (net 479))
  (arc (start 245.158252 91.6065) (mid 245.297931 91.634284) (end 245.416346 91.713406) (width 0.122) (layer "F.Cu") (net 479))
  (arc (start 247.823406 85.153654) (mid 247.744284 85.272069) (end 247.7165 85.411748) (width 0.122) (layer "F.Cu") (net 479))
  (arc (start 250.003654 81.593406) (mid 250.122069 81.514284) (end 250.261748 81.4865) (width 0.122) (layer "F.Cu") (net 479))
  (arc (start 246.147623 91.966594) (mid 246.22416 91.95137) (end 246.289045 91.908015) (width 0.122) (layer "F.Cu") (net 479))
  (arc (start 199.052619 95.917334) (mid 199.24396 95.879274) (end 199.406172 95.770888) (width 0.122) (layer "F.Cu") (net 479))
  (arc (start 201.455786 93.721274) (mid 201.671528 93.57712) (end 201.926012 93.5265) (width 0.122) (layer "F.Cu") (net 479))
  (arc (start 242.741748 91.6065) (mid 242.602069 91.634284) (end 242.483654 91.713406) (width 0.122) (layer "F.Cu") (net 479))
  (arc (start 253.525862 82.012922) (mid 253.590747 82.056276) (end 253.667283 82.0715) (width 0.122) (layer "F.Cu") (net 479))
  (arc (start 196.808016 95.693923) (mid 196.896404 95.730535) (end 196.933016 95.818923) (width 0.1) (layer "F.Cu") (net 479))
  (segment (start 255.947079 77.337079) (end 256.08 77.47) (width 0.122) (layer "F.Cu") (net 480))
  (segment (start 255.195 77.635) (end 255.492922 77.337078) (width 0.122) (layer "F.Cu") (net 480))
  (segment (start 255.634343 77.2785) (end 255.805657 77.2785) (width 0.122) (layer "F.Cu") (net 480))
  (via (at 256.08 77.47) (size 0.5) (drill 0.2) (layers "F.Cu" "B.Cu") (net 480))
  (arc (start 255.947079 77.337079) (mid 255.882194 77.293724) (end 255.805657 77.2785) (width 0.122) (layer "F.Cu") (net 480))
  (arc (start 255.492922 77.337078) (mid 255.557807 77.293724) (end 255.634343 77.2785) (width 0.122) (layer "F.Cu") (net 480))
  (segment (start 256.715 77.411421) (end 256.715 77.775) (width 0.122) (layer "B.Cu") (net 480))
  (segment (start 256.685079 77.340079) (end 256.685711 77.340711) (width 0.122) (layer "B.Cu") (net 480))
  (segment (start 256.351343 77.2815) (end 256.543657 77.2815) (width 0.122) (layer "B.Cu") (net 480))
  (segment (start 256.08 77.47) (end 256.209922 77.340078) (width 0.122) (layer "B.Cu") (net 480))
  (arc (start 256.543657 77.2815) (mid 256.620194 77.296724) (end 256.685079 77.340079) (width 0.122) (layer "B.Cu") (net 480))
  (arc (start 256.351343 77.2815) (mid 256.274807 77.296724) (end 256.209922 77.340078) (width 0.122) (layer "B.Cu") (net 480))
  (arc (start 256.715 77.411421) (mid 256.707388 77.373153) (end 256.685711 77.340711) (width 0.122) (layer "B.Cu") (net 480))
  (segment (start 198.13145 94.20195) (end 198.14 94.2105) (width 0.1) (layer "F.Cu") (net 481))
  (segment (start 244.0935 89.992283) (end 244.0935 90.158252) (width 0.122) (layer "F.Cu") (net 481))
  (segment (start 195.847349 94.158016) (end 198.025384 94.158016) (width 0.1) (layer "F.Cu") (net 481))
  (segment (start 244.300861 89.702079) (end 244.152078 89.850862) (width 0.122) (layer "F.Cu") (net 481))
  (segment (start 254.18094 77.635) (end 253.895151 77.349211) (width 0.122) (layer "F.Cu") (net 481))
  (segment (start 195.596978 93.986346) (end 195.712999 94.102367) (width 0.1) (layer "F.Cu") (net 481))
  (segment (start 240.006881 92.5435) (end 201.017547 92.5435) (width 0.122) (layer "F.Cu") (net 481))
  (segment (start 253.75373 77.34921) (end 253.602078 77.500862) (width 0.122) (layer "F.Cu") (net 481))
  (segment (start 246.611594 88.491346) (end 245.566346 89.536594) (width 0.122) (layer "F.Cu") (net 481))
  (segment (start 243.408252 90.8435) (end 242.272283 90.8435) (width 0.122) (layer "F.Cu") (net 481))
  (segment (start 195.445282 93.589298) (end 195.512039 93.656055) (width 0.1) (layer "F.Cu") (net 481))
  (segment (start 253.436594 78.566346) (end 251.491346 80.511594) (width 0.122) (layer "F.Cu") (net 481))
  (segment (start 243.986594 90.416346) (end 243.666346 90.736594) (width 0.122) (layer "F.Cu") (net 481))
  (segment (start 195.541328 93.726765) (end 195.541328 93.851995) (width 0.1) (layer "F.Cu") (net 481))
  (segment (start 251.233252 80.6185) (end 249.292283 80.6185) (width 0.122) (layer "F.Cu") (net 481))
  (segment (start 245.308252 89.6435) (end 244.442283 89.6435) (width 0.122) (layer "F.Cu") (net 481))
  (segment (start 198.826567 94.2105) (end 198.14 94.2105) (width 0.122) (layer "F.Cu") (net 481))
  (segment (start 200.663994 92.689946) (end 199.367503 93.986437) (width 0.122) (layer "F.Cu") (net 481))
  (segment (start 253.5435 77.642283) (end 253.5435 78.308252) (width 0.122) (layer "F.Cu") (net 481))
  (segment (start 249.150862 80.677078) (end 246.777078 83.050862) (width 0.122) (layer "F.Cu") (net 481))
  (segment (start 195.136328 93.560008) (end 195.374571 93.560008) (width 0.1) (layer "F.Cu") (net 481))
  (segment (start 246.7185 83.192283) (end 246.7185 88.233252) (width 0.122) (layer "F.Cu") (net 481))
  (segment (start 242.130861 90.902079) (end 240.83066 92.20228) (width 0.122) (layer "F.Cu") (net 481))
  (segment (start 254.225 77.635) (end 254.18094 77.635) (width 0.122) (layer "F.Cu") (net 481))
  (arc (start 253.895151 77.349211) (mid 253.824441 77.319921) (end 253.75373 77.34921) (width 0.122) (layer "F.Cu") (net 481))
  (arc (start 242.272283 90.8435) (mid 242.195746 90.858724) (end 242.130861 90.902079) (width 0.122) (layer "F.Cu") (net 481))
  (arc (start 251.233252 80.6185) (mid 251.372931 80.590716) (end 251.491346 80.511594) (width 0.122) (layer "F.Cu") (net 481))
  (arc (start 246.7185 88.233252) (mid 246.690716 88.372931) (end 246.611594 88.491346) (width 0.122) (layer "F.Cu") (net 481))
  (arc (start 240.006881 92.5435) (mid 240.452707 92.45482) (end 240.83066 92.20228) (width 0.122) (layer "F.Cu") (net 481))
  (arc (start 195.512039 93.656055) (mid 195.533716 93.688497) (end 195.541328 93.726765) (width 0.1) (layer "F.Cu") (net 481))
  (arc (start 244.300861 89.702079) (mid 244.365746 89.658724) (end 244.442283 89.6435) (width 0.122) (layer "F.Cu") (net 481))
  (arc (start 195.596978 93.986346) (mid 195.555791 93.924705) (end 195.541328 93.851995) (width 0.1) (layer "F.Cu") (net 481))
  (arc (start 201.017547 92.5435) (mid 200.826206 92.58156) (end 200.663994 92.689946) (width 0.122) (layer "F.Cu") (net 481))
  (arc (start 195.847349 94.158016) (mid 195.774639 94.143553) (end 195.712999 94.102367) (width 0.1) (layer "F.Cu") (net 481))
  (arc (start 253.5435 78.308252) (mid 253.515716 78.447931) (end 253.436594 78.566346) (width 0.122) (layer "F.Cu") (net 481))
  (arc (start 246.7185 83.192283) (mid 246.733724 83.115747) (end 246.777078 83.050862) (width 0.122) (layer "F.Cu") (net 481))
  (arc (start 249.292283 80.6185) (mid 249.215747 80.633724) (end 249.150862 80.677078) (width 0.122) (layer "F.Cu") (net 481))
  (arc (start 245.566346 89.536594) (mid 245.447931 89.615716) (end 245.308252 89.6435) (width 0.122) (layer "F.Cu") (net 481))
  (arc (start 243.986594 90.416346) (mid 244.065716 90.297931) (end 244.0935 90.158252) (width 0.122) (layer "F.Cu") (net 481))
  (arc (start 199.367503 93.986437) (mid 199.119319 94.152268) (end 198.826567 94.2105) (width 0.122) (layer "F.Cu") (net 481))
  (arc (start 198.13145 94.20195) (mid 198.082787 94.169434) (end 198.025384 94.158016) (width 0.1) (layer "F.Cu") (net 481))
  (arc (start 243.666346 90.736594) (mid 243.547931 90.815716) (end 243.408252 90.8435) (width 0.122) (layer "F.Cu") (net 481))
  (arc (start 244.152078 89.850862) (mid 244.108724 89.915747) (end 244.0935 89.992283) (width 0.122) (layer "F.Cu") (net 481))
  (arc (start 253.602078 77.500862) (mid 253.558724 77.565747) (end 253.5435 77.642283) (width 0.122) (layer "F.Cu") (net 481))
  (arc (start 195.445282 93.589298) (mid 195.41284 93.56762) (end 195.374571 93.560008) (width 0.1) (layer "F.Cu") (net 481))
  (segment (start 255.953079 76.932921) (end 256.08 76.806) (width 0.122) (layer "F.Cu") (net 482))
  (segment (start 255.634343 76.9915) (end 255.811657 76.9915) (width 0.122) (layer "F.Cu") (net 482))
  (segment (start 255.195 76.635) (end 255.492922 76.932922) (width 0.122) (layer "F.Cu") (net 482))
  (via (at 256.08 76.806) (size 0.5) (drill 0.2) (layers "F.Cu" "B.Cu") (net 482))
  (arc (start 255.953079 76.932921) (mid 255.888194 76.976276) (end 255.811657 76.9915) (width 0.122) (layer "F.Cu") (net 482))
  (arc (start 255.634343 76.9915) (mid 255.557807 76.976276) (end 255.492922 76.932922) (width 0.122) (layer "F.Cu") (net 482))
  (segment (start 256.715 76.848579) (end 256.715 76.505) (width 0.122) (layer "B.Cu") (net 482))
  (segment (start 256.351343 76.9945) (end 256.527657 76.9945) (width 0.122) (layer "B.Cu") (net 482))
  (segment (start 256.669079 76.935921) (end 256.685711 76.919289) (width 0.122) (layer "B.Cu") (net 482))
  (segment (start 256.08 76.806) (end 256.209922 76.935922) (width 0.122) (layer "B.Cu") (net 482))
  (arc (start 256.527657 76.9945) (mid 256.604194 76.979276) (end 256.669079 76.935921) (width 0.122) (layer "B.Cu") (net 482))
  (arc (start 256.685711 76.919289) (mid 256.707388 76.886847) (end 256.715 76.848579) (width 0.122) (layer "B.Cu") (net 482))
  (arc (start 256.351343 76.9945) (mid 256.274807 76.979276) (end 256.209922 76.935922) (width 0.122) (layer "B.Cu") (net 482))
  (segment (start 196.136328 93.560008) (end 195.885429 93.560008) (width 0.1) (layer "F.Cu") (net 483))
  (segment (start 196.921984 93.968016) (end 198.033352 93.968016) (width 0.1) (layer "F.Cu") (net 483))
  (segment (start 253.2565 78.257717) (end 253.2565 77.591748) (width 0.122) (layer "F.Cu") (net 483))
  (segment (start 198.139418 93.924082) (end 198.14 93.9235) (width 0.1) (layer "F.Cu") (net 483))
  (segment (start 243.913406 89.683654) (end 244.133654 89.463406) (width 0.122) (layer "F.Cu") (net 483))
  (segment (start 253.363406 77.333654) (end 253.676271 77.020789) (width 0.122) (layer "F.Cu") (net 483))
  (segment (start 245.399139 89.297921) (end 246.372922 88.324138) (width 0.122) (layer "F.Cu") (net 483))
  (segment (start 240.663453 91.963607) (end 241.963654 90.663406) (width 0.122) (layer "F.Cu") (net 483))
  (segment (start 195.888773 93.968016) (end 196.521984 93.968016) (width 0.1) (layer "F.Cu") (net 483))
  (segment (start 246.538406 82.883654) (end 248.983654 80.438406) (width 0.122) (layer "F.Cu") (net 483))
  (segment (start 249.241748 80.3315) (end 251.182717 80.3315) (width 0.122) (layer "F.Cu") (net 483))
  (segment (start 196.621984 93.868016) (end 196.621984 93.85888) (width 0.1) (layer "F.Cu") (net 483))
  (segment (start 199.171007 93.777053) (end 200.496786 92.451274) (width 0.122) (layer "F.Cu") (net 483))
  (segment (start 196.821984 93.85888) (end 196.821984 93.868016) (width 0.1) (layer "F.Cu") (net 483))
  (segment (start 195.760618 93.881282) (end 195.818063 93.938727) (width 0.1) (layer "F.Cu") (net 483))
  (segment (start 251.324139 80.272921) (end 253.197922 78.399138) (width 0.122) (layer "F.Cu") (net 483))
  (segment (start 243.499139 90.497921) (end 243.747922 90.249138) (width 0.122) (layer "F.Cu") (net 483))
  (segment (start 253.746981 76.9915) (end 253.827079 76.9915) (width 0.122) (layer "F.Cu") (net 483))
  (segment (start 200.967012 92.2565) (end 239.956346 92.2565) (width 0.122) (layer "F.Cu") (net 483))
  (segment (start 242.221748 90.5565) (end 243.357717 90.5565) (width 0.122) (layer "F.Cu") (net 483))
  (segment (start 246.4315 88.182717) (end 246.4315 83.141748) (width 0.122) (layer "F.Cu") (net 483))
  (segment (start 195.814718 93.589298) (end 195.760617 93.643399) (width 0.1) (layer "F.Cu") (net 483))
  (segment (start 253.89779 76.96221) (end 254.225 76.635) (width 0.122) (layer "F.Cu") (net 483))
  (segment (start 195.731328 93.714109) (end 195.731328 93.810571) (width 0.1) (layer "F.Cu") (net 483))
  (segment (start 198.14 93.9235) (end 198.817453 93.9235) (width 0.122) (layer "F.Cu") (net 483))
  (segment (start 244.391748 89.3565) (end 245.257717 89.3565) (width 0.122) (layer "F.Cu") (net 483))
  (segment (start 243.8065 90.107717) (end 243.8065 89.941748) (width 0.122) (layer "F.Cu") (net 483))
  (arc (start 253.676271 77.020789) (mid 253.708713 76.999112) (end 253.746981 76.9915) (width 0.122) (layer "F.Cu") (net 483))
  (arc (start 243.913406 89.683654) (mid 243.834284 89.802069) (end 243.8065 89.941748) (width 0.122) (layer "F.Cu") (net 483))
  (arc (start 246.4315 88.182717) (mid 246.416276 88.259253) (end 246.372922 88.324138) (width 0.122) (layer "F.Cu") (net 483))
  (arc (start 196.621984 93.85888) (mid 196.651273 93.788169) (end 196.721984 93.75888) (width 0.1) (layer "F.Cu") (net 483))
  (arc (start 246.4315 83.141748) (mid 246.459284 83.002069) (end 246.538406 82.883654) (width 0.122) (layer "F.Cu") (net 483))
  (arc (start 195.818063 93.938727) (mid 195.850505 93.960404) (end 195.888773 93.968016) (width 0.1) (layer "F.Cu") (net 483))
  (arc (start 240.663453 91.963607) (mid 240.33903 92.18038) (end 239.956346 92.2565) (width 0.122) (layer "F.Cu") (net 483))
  (arc (start 253.197922 78.399138) (mid 253.241276 78.334253) (end 253.2565 78.257717) (width 0.122) (layer "F.Cu") (net 483))
  (arc (start 198.033352 93.968016) (mid 198.090766 93.956615) (end 198.139418 93.924082) (width 0.1) (layer "F.Cu") (net 483))
  (arc (start 198.817453 93.9235) (mid 199.008795 93.88544) (end 199.171007 93.777053) (width 0.122) (layer "F.Cu") (net 483))
  (arc (start 195.760617 93.643399) (mid 195.73894 93.675841) (end 195.731328 93.714109) (width 0.1) (layer "F.Cu") (net 483))
  (arc (start 253.2565 77.591748) (mid 253.284284 77.452069) (end 253.363406 77.333654) (width 0.122) (layer "F.Cu") (net 483))
  (arc (start 253.827079 76.9915) (mid 253.865348 76.983888) (end 253.89779 76.96221) (width 0.122) (layer "F.Cu") (net 483))
  (arc (start 196.521984 93.968016) (mid 196.592695 93.938727) (end 196.621984 93.868016) (width 0.1) (layer "F.Cu") (net 483))
  (arc (start 196.821984 93.868016) (mid 196.851273 93.938727) (end 196.921984 93.968016) (width 0.1) (layer "F.Cu") (net 483))
  (arc (start 195.885429 93.560008) (mid 195.84716 93.56762) (end 195.814718 93.589298) (width 0.1) (layer "F.Cu") (net 483))
  (arc (start 245.257717 89.3565) (mid 245.334254 89.341276) (end 245.399139 89.297921) (width 0.122) (layer "F.Cu") (net 483))
  (arc (start 251.182717 80.3315) (mid 251.259254 80.316276) (end 251.324139 80.272921) (width 0.122) (layer "F.Cu") (net 483))
  (arc (start 243.747922 90.249138) (mid 243.791276 90.184253) (end 243.8065 90.107717) (width 0.122) (layer "F.Cu") (net 483))
  (arc (start 196.721984 93.75888) (mid 196.792695 93.788169) (end 196.821984 93.85888) (width 0.1) (layer "F.Cu") (net 483))
  (arc (start 195.731328 93.810571) (mid 195.73894 93.84884) (end 195.760618 93.881282) (width 0.1) (layer "F.Cu") (net 483))
  (arc (start 249.241748 80.3315) (mid 249.102069 80.359284) (end 248.983654 80.438406) (width 0.122) (layer "F.Cu") (net 483))
  (arc (start 241.963654 90.663406) (mid 242.082069 90.584284) (end 242.221748 90.5565) (width 0.122) (layer "F.Cu") (net 483))
  (arc (start 200.496786 92.451274) (mid 200.712528 92.30712) (end 200.967012 92.2565) (width 0.122) (layer "F.Cu") (net 483))
  (arc (start 244.133654 89.463406) (mid 244.252069 89.384284) (end 244.391748 89.3565) (width 0.122) (layer "F.Cu") (net 483))
  (arc (start 243.499139 90.497921) (mid 243.434254 90.541276) (end 243.357717 90.5565) (width 0.122) (layer "F.Cu") (net 483))
  (segment (start 181.136328 96.560008) (end 180.636328 97.060008) (width 0.1) (layer "F.Cu") (net 490))
  (via (at 247.19 89.506) (size 0.5) (drill 0.2) (layers "F.Cu" "B.Cu") (net 490))
  (via blind (at 180.636328 97.060008) (size 0.5) (drill 0.2) (layers "F.Cu" "In5.Cu") (net 490))
  (segment (start 180.706992 96.660008) (end 182.011414 96.660008) (width 0.09) (layer "In5.Cu") (net 490))
  (segment (start 193.578651 99.366067) (end 193.626067 99.366067) (width 0.09) (layer "In5.Cu") (net 490))
  (segment (start 182.877 96.409412) (end 182.877 96.335) (width 0.09) (layer "In5.Cu") (net 490))
  (segment (start 187.338578 98.66) (end 188.03 98.66) (width 0.09) (layer "In5.Cu") (net 490))
  (segment (start 182.011414 96.660008) (end 182.461422 96.21) (width 0.09) (layer "In5.Cu") (net 490))
  (segment (start 185.224999 97.637669) (end 185.224331 97.637669) (width 0.09) (layer "In5.Cu") (net 490))
  (segment (start 189.33 98.66) (end 189.948578 98.66) (width 0.09) (layer "In5.Cu") (net 490))
  (segment (start 180.636328 97.060008) (end 180.636328 96.730672) (width 0.09) (layer "In5.Cu") (net 490))
  (segment (start 184.365 97.435) (end 184.365 96.385) (width 0.09) (layer "In5.Cu") (net 490))
  (segment (start 183.002 96.21) (end 183.052 96.21) (width 0.09) (layer "In5.Cu") (net 490))
  (segment (start 245.08 89.887748) (end 245.08 89.6) (width 0.1) (layer "In5.Cu") (net 490))
  (segment (start 247.730019 89.557847) (end 247.730019 89.551773) (width 0.1) (layer "In5.Cu") (net 490))
  (segment (start 246.862134 89) (end 246.462134 89.4) (width 0.1) (layer "In5.Cu") (net 490))
  (segment (start 185.686331 98.236331) (end 185.754662 98.168) (width 0.09) (layer "In5.Cu") (net 490))
  (segment (start 242.712134 90.8) (end 240.112134 93.4) (width 0.1) (layer "In5.Cu") (net 490))
  (segment (start 193.257297 99.646) (end 193.507941 99.395356) (width 0.09) (layer "In5.Cu") (net 490))
  (segment (start 240.112134 93.4) (end 205.062134 93.4) (width 0.1) (layer "In5.Cu") (net 490))
  (segment (start 244.197048 90.315086) (end 243.712134 90.8) (width 0.1) (layer "In5.Cu") (net 490))
  (segment (start 190.934578 99.646) (end 193.257297 99.646) (width 0.09) (layer "In5.Cu") (net 490))
  (segment (start 188.255 98.885) (end 188.255 99.235) (width 0.09) (layer "In5.Cu") (net 490))
  (segment (start 247.9 89.112134) (end 247.787866 89) (width 0.1) (layer "In5.Cu") (net 490))
  (segment (start 244.88 89.4) (end 244.782134 89.4) (width 0.1) (layer "In5.Cu") (net 490))
  (segment (start 185.64 96.21) (end 185.698578 96.21) (width 0.09) (layer "In5.Cu") (net 490))
  (segment (start 247.599867 89.687999) (end 247.730019 89.557847) (width 0.1) (layer "In5.Cu") (net 490))
  (segment (start 247.19 89.506) (end 247.371999 89.687999) (width 0.1) (layer "In5.Cu") (net 490))
  (segment (start 185.513999 97.347669) (end 185.512999 97.347669) (width 0.09) (layer "In5.Cu") (net 490))
  (segment (start 185.463 96.83) (end 185.463 96.387) (width 0.09) (layer "In5.Cu") (net 490))
  (segment (start 247.730019 89.551773) (end 247.9 89.381793) (width 0.1) (layer "In5.Cu") (net 490))
  (segment (start 185.75533 98.166) (end 186.580621 97.340709) (width 0.09) (layer "In5.Cu") (net 490))
  (segment (start 183.615 97.365) (end 183.615 97.435) (width 0.09) (layer "In5.Cu") (net 490))
  (segment (start 187.04 98.361422) (end 187.338578 98.66) (width 0.09) (layer "In5.Cu") (net 490))
  (segment (start 186.829288 97.340709) (end 187.04 97.551422) (width 0.09) (layer "In5.Cu") (net 490))
  (segment (start 187.04 97.551422) (end 187.04 98.361422) (width 0.09) (layer "In5.Cu") (net 490))
  (segment (start 185.224999 97.635669) (end 185.224999 97.637669) (width 0.09) (layer "In5.Cu") (net 490))
  (segment (start 244.782134 89.4) (end 244.197048 89.985086) (width 0.1) (layer "In5.Cu") (net 490))
  (segment (start 189.105 99.235) (end 189.105 98.885) (width 0.09) (layer "In5.Cu") (net 490))
  (segment (start 185.463 96.387) (end 185.465 96.385) (width 0.09) (layer "In5.Cu") (net 490))
  (segment (start 185.909868 96.9518) (end 185.513999 97.347669) (width 0.09) (layer "In5.Cu") (net 490))
  (segment (start 243.712134 90.8) (end 242.712134 90.8) (width 0.1) (layer "In5.Cu") (net 490))
  (segment (start 189.948578 98.66) (end 190.934578 99.646) (width 0.09) (layer "In5.Cu") (net 490))
  (segment (start 185.512999 97.347669) (end 185.224999 97.635669) (width 0.09) (layer "In5.Cu") (net 490))
  (segment (start 193.922134 99.07) (end 193.626067 99.366067) (width 0.1) (layer "In5.Cu") (net 490))
  (segment (start 183.49 96.59) (end 183.39 96.59) (width 0.09) (layer "In5.Cu") (net 490))
  (segment (start 183.615 96.385) (end 183.615 96.465) (width 0.09) (layer "In5.Cu") (net 490))
  (segment (start 244.197048 89.985086) (end 244.197048 90.315086) (width 0.1) (layer "In5.Cu") (net 490))
  (segment (start 185.224331 97.637669) (end 185.156 97.706) (width 0.09) (layer "In5.Cu") (net 490))
  (segment (start 184.713 96.387) (end 184.713 96.83) (width 0.09) (layer "In5.Cu") (net 490))
  (segment (start 182.461422 96.21) (end 182.502 96.21) (width 0.09) (layer "In5.Cu") (net 490))
  (segment (start 185.75533 98.168) (end 185.75533 98.166) (width 0.09) (layer "In5.Cu") (net 490))
  (segment (start 199.392134 99.07) (end 193.922134 99.07) (width 0.1) (layer "In5.Cu") (net 490))
  (segment (start 205.062134 93.4) (end 199.392134 99.07) (width 0.1) (layer "In5.Cu") (net 490))
  (segment (start 245.48 89.6) (end 245.48 89.887748) (width 0.1) (layer "In5.Cu") (net 490))
  (segment (start 183.39 97.24) (end 183.49 97.24) (width 0.09) (layer "In5.Cu") (net 490))
  (segment (start 185.698578 96.21) (end 186.05147 96.56289) (width 0.09) (layer "In5.Cu") (net 490))
  (segment (start 247.371999 89.687999) (end 247.599867 89.687999) (width 0.1) (layer "In5.Cu") (net 490))
  (segment (start 186.580621 97.340709) (end 186.5818 97.340709) (width 0.09) (layer "In5.Cu") (net 490))
  (segment (start 180.636328 96.730672) (end 180.706992 96.660008) (width 0.09) (layer "In5.Cu") (net 490))
  (segment (start 184.715 96.385) (end 184.713 96.387) (width 0.09) (layer "In5.Cu") (net 490))
  (segment (start 183.052 96.21) (end 183.44 96.21) (width 0.09) (layer "In5.Cu") (net 490))
  (segment (start 185.754662 98.168) (end 185.75533 98.168) (width 0.09) (layer "In5.Cu") (net 490))
  (segment (start 246.462134 89.4) (end 245.68 89.4) (width 0.1) (layer "In5.Cu") (net 490))
  (segment (start 185.910048 96.9518) (end 185.909868 96.9518) (width 0.09) (layer "In5.Cu") (net 490))
  (segment (start 182.627 96.335) (end 182.627 96.409412) (width 0.09) (layer "In5.Cu") (net 490))
  (segment (start 247.787866 89) (end 246.862134 89) (width 0.1) (layer "In5.Cu") (net 490))
  (segment (start 247.9 89.381793) (end 247.9 89.112134) (width 0.1) (layer "In5.Cu") (net 490))
  (segment (start 186.05147 96.810378) (end 185.910048 96.9518) (width 0.09) (layer "In5.Cu") (net 490))
  (arc (start 245.08 89.6) (mid 245.021421 89.458579) (end 244.88 89.4) (width 0.1) (layer "In5.Cu") (net 490))
  (arc (start 185.156 97.706) (mid 185.046164 97.971165) (end 185.156001 98.236331) (width 0.09) (layer "In5.Cu") (net 490))
  (arc (start 182.877 96.335) (mid 182.913612 96.246612) (end 183.002 96.21) (width 0.09) (layer "In5.Cu") (net 490))
  (arc (start 193.507941 99.395356) (mid 193.540383 99.373679) (end 193.578651 99.366067) (width 0.09) (layer "In5.Cu") (net 490))
  (arc (start 245.48 89.887748) (mid 245.421421 90.029169) (end 245.28 90.087748) (width 0.1) (layer "In5.Cu") (net 490))
  (arc (start 183.615 97.435) (mid 183.724835 97.700165) (end 183.99 97.81) (width 0.09) (layer "In5.Cu") (net 490))
  (arc (start 188.68 99.66) (mid 188.98052 99.53552) (end 189.105 99.235) (width 0.09) (layer "In5.Cu") (net 490))
  (arc (start 183.39 96.59) (mid 183.16019 96.68519) (end 183.065 96.915) (width 0.09) (layer "In5.Cu") (net 490))
  (arc (start 188.255 99.235) (mid 188.37948 99.53552) (end 188.68 99.66) (width 0.09) (layer "In5.Cu") (net 490))
  (arc (start 186.05147 96.56289) (mid 186.102726 96.686634) (end 186.05147 96.810378) (width 0.09) (layer "In5.Cu") (net 490))
  (arc (start 184.54 96.21) (mid 184.663744 96.261256) (end 184.715 96.385) (width 0.09) (layer "In5.Cu") (net 490))
  (arc (start 185.156001 98.236331) (mid 185.421166 98.346166) (end 185.686331 98.236331) (width 0.09) (layer "In5.Cu") (net 490))
  (arc (start 183.065 96.915) (mid 183.16019 97.14481) (end 183.39 97.24) (width 0.09) (layer "In5.Cu") (net 490))
  (arc (start 182.627 96.409412) (mid 182.663612 96.4978) (end 182.752 96.534412) (width 0.09) (layer "In5.Cu") (net 490))
  (arc (start 183.49 97.24) (mid 183.578388 97.276612) (end 183.615 97.365) (width 0.09) (layer "In5.Cu") (net 490))
  (arc (start 183.99 97.81) (mid 184.255165 97.700165) (end 184.365 97.435) (width 0.09) (layer "In5.Cu") (net 490))
  (arc (start 186.5818 97.340709) (mid 186.705544 97.289453) (end 186.829288 97.340709) (width 0.09) (layer "In5.Cu") (net 490))
  (arc (start 184.365 96.385) (mid 184.416256 96.261256) (end 184.54 96.21) (width 0.09) (layer "In5.Cu") (net 490))
  (arc (start 184.713 96.83) (mid 184.822835 97.095165) (end 185.088 97.205) (width 0.09) (layer "In5.Cu") (net 490))
  (arc (start 183.615 96.465) (mid 183.578388 96.553388) (end 183.49 96.59) (width 0.09) (layer "In5.Cu") (net 490))
  (arc (start 245.28 90.087748) (mid 245.138579 90.029169) (end 245.08 89.887748) (width 0.1) (layer "In5.Cu") (net 490))
  (arc (start 185.088 97.205) (mid 185.353165 97.095165) (end 185.463 96.83) (width 0.09) (layer "In5.Cu") (net 490))
  (arc (start 189.105 98.885) (mid 189.170901 98.725901) (end 189.33 98.66) (width 0.09) (layer "In5.Cu") (net 490))
  (arc (start 183.44 96.21) (mid 183.563744 96.261256) (end 183.615 96.385) (width 0.09) (layer "In5.Cu") (net 490))
  (arc (start 185.465 96.385) (mid 185.516256 96.261256) (end 185.64 96.21) (width 0.09) (layer "In5.Cu") (net 490))
  (arc (start 245.68 89.4) (mid 245.538579 89.458579) (end 245.48 89.6) (width 0.1) (layer "In5.Cu") (net 490))
  (arc (start 182.752 96.534412) (mid 182.840388 96.4978) (end 182.877 96.409412) (width 0.09) (layer "In5.Cu") (net 490))
  (arc (start 182.502 96.21) (mid 182.590388 96.246612) (end 182.627 96.335) (width 0.09) (layer "In5.Cu") (net 490))
  (arc (start 188.03 98.66) (mid 188.189099 98.725901) (end 188.255 98.885) (width 0.09) (layer "In5.Cu") (net 490))
  (segment (start 247.19 89.506) (end 247.371999 89.687999) (width 0.1) (layer "B.Cu") (net 490))
  (segment (start 247.722001 89.687999) (end 247.825 89.585) (width 0.1) (layer "B.Cu") (net 490))
  (segment (start 247.371999 89.687999) (end 247.722001 89.687999) (width 0.1) (layer "B.Cu") (net 490))
  (segment (start 247.825 89.585) (end 247.825 89.205) (width 0.1) (layer "B.Cu") (net 490))
  (segment (start 180.136328 96.560008) (end 179.636328 97.060008) (width 0.1) (layer "F.Cu") (net 491))
  (via (at 179.636328 97.060008) (size 0.5) (drill 0.2) (layers "F.Cu" "B.Cu") (net 491))
  (via (at 244.65 97.79) (size 0.5) (drill 0.2) (layers "F.Cu" "B.Cu") (net 491))
  (segment (start 198.197 101.26) (end 198.175778 101.281222) (width 0.09) (layer "In7.Cu") (net 491))
  (segment (start 181.873933 98.248393) (end 182.050709 98.071618) (width 0.09) (layer "In7.Cu") (net 491))
  (segment (start 245.180133 97.608001) (end 245.55 97.238134) (width 0.1) (layer "In7.Cu") (net 491))
  (segment (start 181.873933 98.495882) (end 181.873932 98.495882) (width 0.09) (layer "In7.Cu") (net 491))
  (segment (start 180.248578 97.461) (end 179.097 97.461) (width 0.09) (layer "In7.Cu") (net 491))
  (segment (start 245.55 97.238134) (end 245.55 96.771776) (width 0.1) (layer "In7.Cu") (net 491))
  (segment (start 184.325099 99.957099) (end 184.325101 99.9571) (width 0.09) (layer "In7.Cu") (net 491))
  (segment (start 244.65 97.78) (end 244.821999 97.608001) (width 0.1) (layer "In7.Cu") (net 491))
  (segment (start 184.006901 100.55814) (end 184.0069 100.55814) (width 0.09) (layer "In7.Cu") (net 491))
  (segment (start 184.554911 99.267672) (end 184.448845 99.161606) (width 0.09) (layer "In7.Cu") (net 491))
  (segment (start 186.121422 101.612) (end 186.063209 101.553789) (width 0.09) (layer "In7.Cu") (net 491))
  (segment (start 201.527868 101.26) (end 198.197 101.26) (width 0.1) (layer "In7.Cu") (net 491))
  (segment (start 185.285389 100.775972) (end 185.28539 100.775972) (width 0.09) (layer "In7.Cu") (net 491))
  (segment (start 245.55 96.771776) (end 245.178224 96.4) (width 0.1) (layer "In7.Cu") (net 491))
  (segment (start 179.01 97.374) (end 179.01 97.2) (width 0.09) (layer "In7.Cu") (net 491))
  (segment (start 179.01 97.2) (end 179.149992 97.060008) (width 0.09) (layer "In7.Cu") (net 491))
  (segment (start 179.149992 97.060008) (end 179.636328 97.060008) (width 0.09) (layer "In7.Cu") (net 491))
  (segment (start 196.502578 101.9) (end 195.541422 101.9) (width 0.09) (layer "In7.Cu") (net 491))
  (segment (start 184.448845 99.161606) (end 184.448844 99.161606) (width 0.09) (layer "In7.Cu") (net 491))
  (segment (start 185.910998 100.397853) (end 185.532879 100.775972) (width 0.09) (layer "In7.Cu") (net 491))
  (segment (start 180.431578 97.278) (end 180.248578 97.461) (width 0.09) (layer "In7.Cu") (net 491))
  (segment (start 179.097 97.461) (end 179.01 97.374) (width 0.09) (layer "In7.Cu") (net 491))
  (segment (start 195.541422 101.9) (end 195.106449 101.465027) (width 0.09) (layer "In7.Cu") (net 491))
  (segment (start 185.28539 100.775972) (end 184.961494 100.452074) (width 0.09) (layer "In7.Cu") (net 491))
  (segment (start 197.092066 101.310512) (end 196.502578 101.9) (width 0.09) (layer "In7.Cu") (net 491))
  (segment (start 189.389878 101.465027) (end 189.242905 101.612) (width 0.09) (layer "In7.Cu") (net 491))
  (segment (start 183.299796 99.851035) (end 183.299797 99.851034) (width 0.09) (layer "In7.Cu") (net 491))
  (segment (start 185.910998 100.397852) (end 185.910998 100.397853) (width 0.09) (layer "In7.Cu") (net 491))
  (segment (start 245.178224 96.4) (end 242.987866 96.4) (width 0.1) (layer "In7.Cu") (net 491))
  (segment (start 244.65 97.79) (end 244.65 97.78) (width 0.1) (layer "In7.Cu") (net 491))
  (segment (start 182.298196 98.319106) (end 182.121421 98.495882) (width 0.09) (layer "In7.Cu") (net 491))
  (segment (start 182.828525 98.319106) (end 182.828525 98.319105) (width 0.09) (layer "In7.Cu") (net 491))
  (segment (start 183.706384 98.419145) (end 183.600318 98.313079) (width 0.09) (layer "In7.Cu") (net 491))
  (segment (start 241.537866 97.85) (end 204.937866 97.85) (width 0.1) (layer "In7.Cu") (net 491))
  (segment (start 198.105067 101.310512) (end 197.092066 101.310512) (width 0.09) (layer "In7.Cu") (net 491))
  (segment (start 204.937866 97.85) (end 201.527868 101.26) (width 0.1) (layer "In7.Cu") (net 491))
  (segment (start 182.121421 98.495882) (end 182.121422 98.495881) (width 0.09) (layer "In7.Cu") (net 491))
  (segment (start 183.706383 98.878763) (end 183.706383 98.878764) (width 0.09) (layer "In7.Cu") (net 491))
  (segment (start 182.050709 97.54129) (end 182.050711 97.541289) (width 0.09) (layer "In7.Cu") (net 491))
  (segment (start 182.893209 98.383788) (end 182.828525 98.319106) (width 0.09) (layer "In7.Cu") (net 491))
  (segment (start 184.006901 100.275297) (end 184.325099 99.957099) (width 0.09) (layer "In7.Cu") (net 491))
  (segment (start 183.140698 98.313079) (end 183.069987 98.383789) (width 0.09) (layer "In7.Cu") (net 491))
  (segment (start 184.395809 100.452073) (end 184.289743 100.55814) (width 0.09) (layer "In7.Cu") (net 491))
  (segment (start 183.069987 98.383789) (end 183.069989 98.38379) (width 0.09) (layer "In7.Cu") (net 491))
  (segment (start 242.987866 96.4) (end 241.537866 97.85) (width 0.1) (layer "In7.Cu") (net 491))
  (segment (start 186.063209 101.306301) (end 186.441327 100.928181) (width 0.09) (layer "In7.Cu") (net 491))
  (segment (start 184.289743 100.55814) (end 184.289744 100.558139) (width 0.09) (layer "In7.Cu") (net 491))
  (segment (start 184.325101 99.9571) (end 184.55491 99.727291) (width 0.09) (layer "In7.Cu") (net 491))
  (segment (start 189.242905 101.612) (end 186.121422 101.612) (width 0.09) (layer "In7.Cu") (net 491))
  (segment (start 186.06321 101.3063) (end 186.063209 101.306301) (width 0.09) (layer "In7.Cu") (net 491))
  (segment (start 244.821999 97.608001) (end 245.180133 97.608001) (width 0.1) (layer "In7.Cu") (net 491))
  (segment (start 182.050711 97.541289) (end 181.787422 97.278) (width 0.09) (layer "In7.Cu") (net 491))
  (segment (start 181.787422 97.278) (end 180.431578 97.278) (width 0.09) (layer "In7.Cu") (net 491))
  (segment (start 195.106449 101.465027) (end 189.389878 101.465027) (width 0.09) (layer "In7.Cu") (net 491))
  (segment (start 183.016954 99.568193) (end 183.706383 98.878763) (width 0.09) (layer "In7.Cu") (net 491))
  (segment (start 183.989225 99.161605) (end 183.299796 99.851035) (width 0.09) (layer "In7.Cu") (net 491))
  (arc (start 181.873932 98.495882) (mid 181.822676 98.372137) (end 181.873933 98.248393) (width 0.09) (layer "In7.Cu") (net 491))
  (arc (start 184.448844 99.161606) (mid 184.219035 99.066415) (end 183.989225 99.161605) (width 0.09) (layer "In7.Cu") (net 491))
  (arc (start 183.069989 98.38379) (mid 182.981599 98.420401) (end 182.893209 98.383788) (width 0.09) (layer "In7.Cu") (net 491))
  (arc (start 183.299797 99.851034) (mid 183.158376 99.909613) (end 183.016954 99.851035) (width 0.09) (layer "In7.Cu") (net 491))
  (arc (start 184.289744 100.558139) (mid 184.148323 100.616718) (end 184.006901 100.55814) (width 0.09) (layer "In7.Cu") (net 491))
  (arc (start 184.55491 99.727291) (mid 184.650101 99.497482) (end 184.554911 99.267672) (width 0.09) (layer "In7.Cu") (net 491))
  (arc (start 183.016954 99.851035) (mid 182.958376 99.709614) (end 183.016954 99.568193) (width 0.09) (layer "In7.Cu") (net 491))
  (arc (start 182.828525 98.319105) (mid 182.56336 98.209271) (end 182.298196 98.319106) (width 0.09) (layer "In7.Cu") (net 491))
  (arc (start 186.063209 101.553789) (mid 186.011953 101.430044) (end 186.06321 101.3063) (width 0.09) (layer "In7.Cu") (net 491))
  (arc (start 186.441327 100.397853) (mid 186.176163 100.288018) (end 185.910998 100.397852) (width 0.09) (layer "In7.Cu") (net 491))
  (arc (start 183.706383 98.878764) (mid 183.801574 98.648955) (end 183.706384 98.419145) (width 0.09) (layer "In7.Cu") (net 491))
  (arc (start 182.121422 98.495881) (mid 181.997678 98.547138) (end 181.873933 98.495882) (width 0.09) (layer "In7.Cu") (net 491))
  (arc (start 198.175778 101.281222) (mid 198.143336 101.3029) (end 198.105067 101.310512) (width 0.09) (layer "In7.Cu") (net 491))
  (arc (start 186.441327 100.928181) (mid 186.551162 100.663017) (end 186.441327 100.397853) (width 0.09) (layer "In7.Cu") (net 491))
  (arc (start 184.0069 100.55814) (mid 183.948322 100.416718) (end 184.006901 100.275297) (width 0.09) (layer "In7.Cu") (net 491))
  (arc (start 182.050709 98.071618) (mid 182.160544 97.806454) (end 182.050709 97.54129) (width 0.09) (layer "In7.Cu") (net 491))
  (arc (start 185.532879 100.775972) (mid 185.409134 100.827229) (end 185.285389 100.775972) (width 0.09) (layer "In7.Cu") (net 491))
  (arc (start 183.600318 98.313079) (mid 183.370508 98.217889) (end 183.140698 98.313079) (width 0.09) (layer "In7.Cu") (net 491))
  (arc (start 184.961494 100.452074) (mid 184.678652 100.334916) (end 184.395809 100.452073) (width 0.09) (layer "In7.Cu") (net 491))
  (segment (start 244.65 97.79) (end 244.831999 97.608001) (width 0.1) (layer "B.Cu") (net 491))
  (segment (start 244.831999 97.608001) (end 245.213001 97.608001) (width 0.1) (layer "B.Cu") (net 491))
  (segment (start 245.285 97.68) (end 245.285 98.095) (width 0.1) (layer "B.Cu") (net 491))
  (segment (start 245.213001 97.608001) (end 245.285 97.68) (width 0.1) (layer "B.Cu") (net 491))
  (segment (start 178.136328 96.560008) (end 177.636328 97.060008) (width 0.1) (layer "F.Cu") (net 492))
  (via (at 244.65 116.84) (size 0.5) (drill 0.2) (layers "F.Cu" "B.Cu") (net 492))
  (via (at 177.636328 97.060008) (size 0.5) (drill 0.2) (layers "F.Cu" "B.Cu") (net 492))
  (segment (start 236.610581 102.448447) (end 235.860581 102.448447) (width 0.1) (layer "In9.Cu") (net 492))
  (segment (start 241.55 112.087866) (end 239.65 110.187866) (width 0.1) (layer "In9.Cu") (net 492))
  (segment (start 242.45 114.637866) (end 242.45 113.837866) (width 0.1) (layer "In9.Cu") (net 492))
  (segment (start 243.212134 115.4) (end 242.45 114.637866) (width 0.1) (layer "In9.Cu") (net 492))
  (segment (start 177.636328 97.060008) (end 177.259992 97.060008) (width 0.09) (layer "In9.Cu") (net 492))
  (segment (start 245.212134 115.4) (end 243.212134 115.4) (width 0.1) (layer "In9.Cu") (net 492))
  (segment (start 235.860581 102.448447) (end 233.042134 99.63) (width 0.1) (layer "In9.Cu") (net 492))
  (segment (start 244.65 116.84) (end 244.831999 116.658001) (width 0.1) (layer "In9.Cu") (net 492))
  (segment (start 191.058578 96.4) (end 193.084268 96.4) (width 0.09) (layer "In9.Cu") (net 492))
  (segment (start 241.55 112.937866) (end 241.55 112.087866) (width 0.1) (layer "In9.Cu") (net 492))
  (segment (start 233.042134 99.63) (end 198.692134 99.63) (width 0.1) (layer "In9.Cu") (net 492))
  (segment (start 177.305027 97.465027) (end 180.293551 97.465027) (width 0.09) (layer "In9.Cu") (net 492))
  (segment (start 177.17 97.33) (end 177.305027 97.465027) (width 0.09) (layer "In9.Cu") (net 492))
  (segment (start 177.259992 97.060008) (end 177.17 97.15) (width 0.09) (layer "In9.Cu") (net 492))
  (segment (start 242.45 113.837866) (end 241.55 112.937866) (width 0.1) (layer "In9.Cu") (net 492))
  (segment (start 183.789 97.17) (end 190.288578 97.17) (width 0.09) (layer "In9.Cu") (net 492))
  (segment (start 245.55 116.262134) (end 245.55 115.737866) (width 0.1) (layer "In9.Cu") (net 492))
  (segment (start 180.293551 97.465027) (end 180.588578 97.17) (width 0.09) (layer "In9.Cu") (net 492))
  (segment (start 238.15 107.437866) (end 238.15 103.987866) (width 0.1) (layer "In9.Cu") (net 492))
  (segment (start 239.65 110.187866) (end 239.65 108.937866) (width 0.1) (layer "In9.Cu") (net 492))
  (segment (start 190.288578 97.17) (end 191.058578 96.4) (width 0.09) (layer "In9.Cu") (net 492))
  (segment (start 239.65 108.937866) (end 238.15 107.437866) (width 0.1) (layer "In9.Cu") (net 492))
  (segment (start 183.389 97.971124) (end 183.389 97.57) (width 0.09) (layer "In9.Cu") (net 492))
  (segment (start 180.588578 97.17) (end 182.589 97.17) (width 0.09) (layer "In9.Cu") (net 492))
  (segment (start 196.682134 97.62) (end 194.382134 97.62) (width 0.1) (layer "In9.Cu") (net 492))
  (segment (start 198.692134 99.63) (end 196.682134 97.62) (width 0.1) (layer "In9.Cu") (net 492))
  (segment (start 177.17 97.15) (end 177.17 97.33) (width 0.09) (layer "In9.Cu") (net 492))
  (segment (start 244.831999 116.658001) (end 245.154133 116.658001) (width 0.1) (layer "In9.Cu") (net 492))
  (segment (start 193.084268 96.4) (end 193.714267 97.029999) (width 0.09) (layer "In9.Cu") (net 492))
  (segment (start 182.989 97.57) (end 182.989 97.971124) (width 0.09) (layer "In9.Cu") (net 492))
  (segment (start 245.154133 116.658001) (end 245.55 116.262134) (width 0.1) (layer "In9.Cu") (net 492))
  (segment (start 194.382134 97.62) (end 193.836067 97.073933) (width 0.1) (layer "In9.Cu") (net 492))
  (segment (start 245.55 115.737866) (end 245.212134 115.4) (width 0.1) (layer "In9.Cu") (net 492))
  (segment (start 238.15 103.987866) (end 236.610581 102.448447) (width 0.1) (layer "In9.Cu") (net 492))
  (segment (start 193.820333 97.073933) (end 193.836067 97.073933) (width 0.09) (layer "In9.Cu") (net 492))
  (arc (start 183.389 97.57) (mid 183.506157 97.287157) (end 183.789 97.17) (width 0.09) (layer "In9.Cu") (net 492))
  (arc (start 182.989 97.971124) (mid 183.047579 98.112545) (end 183.189 98.171124) (width 0.09) (layer "In9.Cu") (net 492))
  (arc (start 183.189 98.171124) (mid 183.330421 98.112545) (end 183.389 97.971124) (width 0.09) (layer "In9.Cu") (net 492))
  (arc (start 182.589 97.17) (mid 182.871843 97.287157) (end 182.989 97.57) (width 0.09) (layer "In9.Cu") (net 492))
  (arc (start 193.714267 97.029999) (mid 193.76293 97.062515) (end 193.820333 97.073933) (width 0.09) (layer "In9.Cu") (net 492))
  (segment (start 245.213001 116.658001) (end 245.285 116.73) (width 0.1) (layer "B.Cu") (net 492))
  (segment (start 245.285 116.73) (end 245.285 117.145) (width 0.1) (layer "B.Cu") (net 492))
  (segment (start 244.831999 116.658001) (end 245.213001 116.658001) (width 0.1) (layer "B.Cu") (net 492))
  (segment (start 244.65 116.84) (end 244.831999 116.658001) (width 0.1) (layer "B.Cu") (net 492))
  (segment (start 176.636328 97.060008) (end 177.136328 96.560008) (width 0.1) (layer "F.Cu") (net 493))
  (via (at 176.636328 97.060008) (size 0.5) (drill 0.2) (layers "F.Cu" "B.Cu") (net 493))
  (via (at 245.92 113.636) (size 0.5) (drill 0.2) (layers "F.Cu" "B.Cu") (net 493))
  (segment (start 245.187866 114.7) (end 243.987866 114.7) (width 0.1) (layer "In9.Cu") (net 493))
  (segment (start 240.85 108.312134) (end 239.35 106.812134) (width 0.1) (layer "In9.Cu") (net 493))
  (segment (start 193.840807 95.339509) (end 193.850999 95.349701) (width 0.09) (layer "In9.Cu") (net 493))
  (segment (start 239.35 103.312134) (end 234.387866 98.35) (width 0.1) (layer "In9.Cu") (net 493))
  (segment (start 245.637866 115.15) (end 245.187866 114.7) (width 0.1) (layer "In9.Cu") (net 493))
  (segment (start 242.35 111.312134) (end 240.85 109.812134) (width 0.1) (layer "In9.Cu") (net 493))
  (segment (start 186.748578 96.27) (end 187.143586 96.665008) (width 0.09) (layer "In9.Cu") (net 493))
  (segment (start 246.434133 113.817999) (end 246.87 114.253866) (width 0.1) (layer "In9.Cu") (net 493))
  (segment (start 193.216422 95.66) (end 193.580847 95.295575) (width 0.09) (layer "In9.Cu") (net 493))
  (segment (start 187.143586 96.665008) (end 188.296414 96.665008) (width 0.09) (layer "In9.Cu") (net 493))
  (segment (start 198.737866 98.35) (end 196.997866 96.61) (width 0.1) (layer "In9.Cu") (net 493))
  (segment (start 196.467866 96.61) (end 195.207567 95.349701) (width 0.1) (layer "In9.Cu") (net 493))
  (segment (start 196.997866 96.61) (end 196.467866 96.61) (width 0.1) (layer "In9.Cu") (net 493))
  (segment (start 188.296414 96.665008) (end 189.301422 95.66) (width 0.09) (layer "In9.Cu") (net 493))
  (segment (start 246.87 114.799607) (end 246.519607 115.15) (width 0.1) (layer "In9.Cu") (net 493))
  (segment (start 176.636328 97.060008) (end 177.031328 96.665008) (width 0.09) (layer "In9.Cu") (net 493))
  (segment (start 243.987866 114.7) (end 242.35 113.062134) (width 0.1) (layer "In9.Cu") (net 493))
  (segment (start 182.066414 96.665008) (end 182.461422 96.27) (width 0.09) (layer "In9.Cu") (net 493))
  (segment (start 234.387866 98.35) (end 198.737866 98.35) (width 0.1) (layer "In9.Cu") (net 493))
  (segment (start 242.35 113.062134) (end 242.35 111.312134) (width 0.1) (layer "In9.Cu") (net 493))
  (segment (start 195.207567 95.349701) (end 193.850999 95.349701) (width 0.1) (layer "In9.Cu") (net 493))
  (segment (start 245.92 113.636) (end 246.101999 113.817999) (width 0.1) (layer "In9.Cu") (net 493))
  (segment (start 246.101999 113.817999) (end 246.434133 113.817999) (width 0.1) (layer "In9.Cu") (net 493))
  (segment (start 193.580847 95.295575) (end 193.734741 95.295575) (width 0.09) (layer "In9.Cu") (net 493))
  (segment (start 246.519607 115.15) (end 245.637866 115.15) (width 0.1) (layer "In9.Cu") (net 493))
  (segment (start 246.87 114.253866) (end 246.87 114.799607) (width 0.1) (layer "In9.Cu") (net 493))
  (segment (start 182.461422 96.27) (end 186.748578 96.27) (width 0.09) (layer "In9.Cu") (net 493))
  (segment (start 240.85 109.812134) (end 240.85 108.312134) (width 0.1) (layer "In9.Cu") (net 493))
  (segment (start 189.301422 95.66) (end 193.216422 95.66) (width 0.09) (layer "In9.Cu") (net 493))
  (segment (start 177.031328 96.665008) (end 182.066414 96.665008) (width 0.09) (layer "In9.Cu") (net 493))
  (segment (start 239.35 106.812134) (end 239.35 103.312134) (width 0.1) (layer "In9.Cu") (net 493))
  (arc (start 193.840807 95.339509) (mid 193.792144 95.306993) (end 193.734741 95.295575) (width 0.09) (layer "In9.Cu") (net 493))
  (segment (start 246.452001 113.817999) (end 246.555 113.715) (width 0.1) (layer "B.Cu") (net 493))
  (segment (start 246.555 113.715) (end 246.555 113.335) (width 0.1) (layer "B.Cu") (net 493))
  (segment (start 246.101999 113.817999) (end 246.452001 113.817999) (width 0.1) (layer "B.Cu") (net 493))
  (segment (start 245.92 113.636) (end 246.101999 113.817999) (width 0.1) (layer "B.Cu") (net 493))
  (segment (start 249.575 122.475) (end 248.45 123.6) (width 0.3) (layer "F.Cu") (net 496))
  (segment (start 250.7 122.475) (end 249.575 122.475) (width 0.3) (layer "F.Cu") (net 496))
  (segment (start 248.45 123.6) (end 248.45 124.15) (width 0.3) (layer "F.Cu") (net 496))
  (via (at 248.45 124.15) (size 0.5) (drill 0.2) (layers "F.Cu" "B.Cu") (net 496))
  (segment (start 247.825 124.765) (end 247.835 124.765) (width 0.127) (layer "B.Cu") (net 496))
  (segment (start 247.835 124.765) (end 248.45 124.15) (width 0.127) (layer "B.Cu") (net 496))
  (segment (start 254.936921 79.883079) (end 254.81 80.01) (width 0.122) (layer "F.Cu") (net 497))
  (segment (start 255.695 80.181) (end 255.397078 79.883078) (width 0.122) (layer "F.Cu") (net 497))
  (segment (start 255.255657 79.8245) (end 255.078343 79.8245) (width 0.122) (layer "F.Cu") (net 497))
  (via (at 254.81 80.01) (size 0.5) (drill 0.2) (layers "F.Cu" "B.Cu") (net 497))
  (arc (start 254.936921 79.883079) (mid 255.001806 79.839724) (end 255.078343 79.8245) (width 0.122) (layer "F.Cu") (net 497))
  (arc (start 255.397078 79.883078) (mid 255.332193 79.839724) (end 255.255657 79.8245) (width 0.122) (layer "F.Cu") (net 497))
  (segment (start 255.415079 79.880079) (end 255.415711 79.880711) (width 0.122) (layer "B.Cu") (net 497))
  (segment (start 254.81 80.01) (end 254.939922 79.880078) (width 0.122) (layer "B.Cu") (net 497))
  (segment (start 255.081343 79.8215) (end 255.273657 79.8215) (width 0.122) (layer "B.Cu") (net 497))
  (segment (start 255.445 79.951421) (end 255.445 80.315) (width 0.122) (layer "B.Cu") (net 497))
  (arc (start 255.445 79.951421) (mid 255.437388 79.913153) (end 255.415711 79.880711) (width 0.122) (layer "B.Cu") (net 497))
  (arc (start 255.273657 79.8215) (mid 255.350194 79.836724) (end 255.415079 79.880079) (width 0.122) (layer "B.Cu") (net 497))
  (arc (start 255.081343 79.8215) (mid 255.004807 79.836724) (end 254.939922 79.880078) (width 0.122) (layer "B.Cu") (net 497))
  (segment (start 256.962922 79.883078) (end 256.665 80.181) (width 0.122) (layer "F.Cu") (net 498))
  (segment (start 244.933763 88.293297) (end 245.087922 88.139138) (width 0.122) (layer "F.Cu") (net 498))
  (segment (start 195.541328 91.393251) (end 195.541328 91.268021) (width 0.1) (layer "F.Cu") (net 498))
  (segment (start 244.236372 88.351876) (end 244.792341 88.351876) (width 0.122) (layer "F.Cu") (net 498))
  (segment (start 195.445282 91.530718) (end 195.512039 91.463961) (width 0.1) (layer "F.Cu") (net 498))
  (segment (start 245.1465 87.997717) (end 245.1465 80.416948) (width 0.122) (layer "F.Cu") (net 498))
  (segment (start 198.138933 91.572567) (end 198.145 91.5665) (width 0.1) (layer "F.Cu") (net 498))
  (segment (start 198.145 91.5665) (end 198.277717 91.5665) (width 0.122) (layer "F.Cu") (net 498))
  (segment (start 196.751291 91.046939) (end 197.26159 91.557238) (width 0.1) (layer "F.Cu") (net 498))
  (segment (start 195.847349 90.962) (end 196.54623 90.962) (width 0.1) (layer "F.Cu") (net 498))
  (segment (start 240.233453 90.693607) (end 241.703654 89.223406) (width 0.122) (layer "F.Cu") (net 498))
  (segment (start 256.576346 75.203406) (end 257.616594 76.243654) (width 0.122) (layer "F.Cu") (net 498))
  (segment (start 243.379139 89.057921) (end 243.978278 88.458782) (width 0.122) (layer "F.Cu") (net 498))
  (segment (start 195.596978 91.13367) (end 195.712999 91.017649) (width 0.1) (layer "F.Cu") (net 498))
  (segment (start 257.338673 79.8245) (end 257.104343 79.8245) (width 0.122) (layer "F.Cu") (net 498))
  (segment (start 241.961748 89.1165) (end 243.237717 89.1165) (width 0.122) (layer "F.Cu") (net 498))
  (segment (start 245.253406 80.158854) (end 250.208854 75.203406) (width 0.122) (layer "F.Cu") (net 498))
  (segment (start 197.403011 91.615816) (end 198.062569 91.615816) (width 0.1) (layer "F.Cu") (net 498))
  (segment (start 198.419139 91.507921) (end 198.745786 91.181274) (width 0.122) (layer "F.Cu") (net 498))
  (segment (start 195.136328 91.560008) (end 195.374571 91.560008) (width 0.1) (layer "F.Cu") (net 498))
  (segment (start 257.7235 76.501748) (end 257.7235 79.439673) (width 0.122) (layer "F.Cu") (net 498))
  (segment (start 257.645884 79.627056) (end 257.526057 79.746883) (width 0.122) (layer "F.Cu") (net 498))
  (segment (start 199.216012 90.9865) (end 239.526346 90.9865) (width 0.122) (layer "F.Cu") (net 498))
  (segment (start 250.466948 75.0965) (end 256.318252 75.0965) (width 0.122) (layer "F.Cu") (net 498))
  (arc (start 198.419139 91.507921) (mid 198.354254 91.551276) (end 198.277717 91.5665) (width 0.122) (layer "F.Cu") (net 498))
  (arc (start 256.318252 75.0965) (mid 256.457931 75.124284) (end 256.576346 75.203406) (width 0.122) (layer "F.Cu") (net 498))
  (arc (start 199.216012 90.9865) (mid 198.961528 91.03712) (end 198.745786 91.181274) (width 0.122) (layer "F.Cu") (net 498))
  (arc (start 241.703654 89.223406) (mid 241.822069 89.144284) (end 241.961748 89.1165) (width 0.122) (layer "F.Cu") (net 498))
  (arc (start 195.712999 91.017649) (mid 195.774639 90.976463) (end 195.847349 90.962) (width 0.1) (layer "F.Cu") (net 498))
  (arc (start 195.512039 91.463961) (mid 195.533716 91.431519) (end 195.541328 91.393251) (width 0.1) (layer "F.Cu") (net 498))
  (arc (start 195.374571 91.560008) (mid 195.41284 91.552396) (end 195.445282 91.530718) (width 0.1) (layer "F.Cu") (net 498))
  (arc (start 245.087922 88.139138) (mid 245.131276 88.074253) (end 245.1465 87.997717) (width 0.122) (layer "F.Cu") (net 498))
  (arc (start 257.7235 79.439673) (mid 257.703328 79.541084) (end 257.645884 79.627056) (width 0.122) (layer "F.Cu") (net 498))
  (arc (start 195.541328 91.268021) (mid 195.555791 91.195311) (end 195.596978 91.13367) (width 0.1) (layer "F.Cu") (net 498))
  (arc (start 197.403011 91.615816) (mid 197.326475 91.600592) (end 197.26159 91.557238) (width 0.1) (layer "F.Cu") (net 498))
  (arc (start 243.978278 88.458782) (mid 244.096693 88.37966) (end 244.236372 88.351876) (width 0.122) (layer "F.Cu") (net 498))
  (arc (start 245.253406 80.158854) (mid 245.174284 80.277269) (end 245.1465 80.416948) (width 0.122) (layer "F.Cu") (net 498))
  (arc (start 244.792341 88.351876) (mid 244.868878 88.336652) (end 244.933763 88.293297) (width 0.122) (layer "F.Cu") (net 498))
  (arc (start 198.062569 91.615816) (mid 198.103575 91.598781) (end 198.138933 91.572567) (width 0.1) (layer "F.Cu") (net 498))
  (arc (start 239.526346 90.9865) (mid 239.909029 90.91038) (end 240.233453 90.693607) (width 0.122) (layer "F.Cu") (net 498))
  (arc (start 196.54623 90.962) (mid 196.657208 90.984075) (end 196.751291 91.046939) (width 0.1) (layer "F.Cu") (net 498))
  (arc (start 257.104343 79.8245) (mid 257.027807 79.839724) (end 256.962922 79.883078) (width 0.122) (layer "F.Cu") (net 498))
  (arc (start 257.616594 76.243654) (mid 257.695716 76.362069) (end 257.7235 76.501748) (width 0.122) (layer "F.Cu") (net 498))
  (arc (start 257.526057 79.746883) (mid 257.440085 79.804328) (end 257.338673 79.8245) (width 0.122) (layer "F.Cu") (net 498))
  (arc (start 243.237717 89.1165) (mid 243.314254 89.101276) (end 243.379139 89.057921) (width 0.122) (layer "F.Cu") (net 498))
  (arc (start 250.208854 75.203406) (mid 250.327269 75.124284) (end 250.466948 75.0965) (width 0.122) (layer "F.Cu") (net 498))
  (segment (start 255.695 79.181) (end 255.397078 79.478922) (width 0.122) (layer "F.Cu") (net 499))
  (segment (start 254.942921 79.478921) (end 254.81 79.346) (width 0.122) (layer "F.Cu") (net 499))
  (segment (start 255.255657 79.5375) (end 255.084343 79.5375) (width 0.122) (layer "F.Cu") (net 499))
  (via (at 254.81 79.346) (size 0.5) (drill 0.2) (layers "F.Cu" "B.Cu") (net 499))
  (arc (start 254.942921 79.478921) (mid 255.007806 79.522276) (end 255.084343 79.5375) (width 0.122) (layer "F.Cu") (net 499))
  (arc (start 255.397078 79.478922) (mid 255.332193 79.522276) (end 255.255657 79.5375) (width 0.122) (layer "F.Cu") (net 499))
  (segment (start 255.081343 79.5345) (end 255.257657 79.5345) (width 0.122) (layer "B.Cu") (net 499))
  (segment (start 254.81 79.346) (end 254.939922 79.475922) (width 0.122) (layer "B.Cu") (net 499))
  (segment (start 255.399079 79.475921) (end 255.415711 79.459289) (width 0.122) (layer "B.Cu") (net 499))
  (segment (start 255.445 79.388579) (end 255.445 79.045) (width 0.122) (layer "B.Cu") (net 499))
  (arc (start 255.081343 79.5345) (mid 255.004807 79.519276) (end 254.939922 79.475922) (width 0.122) (layer "B.Cu") (net 499))
  (arc (start 255.257657 79.5345) (mid 255.334194 79.519276) (end 255.399079 79.475921) (width 0.122) (layer "B.Cu") (net 499))
  (arc (start 255.415711 79.459289) (mid 255.437388 79.426847) (end 255.445 79.388579) (width 0.122) (layer "B.Cu") (net 499))
  (segment (start 181.136328 95.560008) (end 180.636328 96.060008) (width 0.1) (layer "F.Cu") (net 505))
  (via (at 247.19 90.17) (size 0.5) (drill 0.2) (layers "F.Cu" "B.Cu") (net 505))
  (via blind (at 180.636328 96.060008) (size 0.5) (drill 0.2) (layers "F.Cu" "In5.Cu") (net 505))
  (segment (start 184.913 96.387) (end 184.913 96.83) (width 0.09) (layer "In5.Cu") (net 505))
  (segment (start 190.031422 98.46) (end 191.017422 99.446) (width 0.09) (layer "In5.Cu") (net 505))
  (segment (start 193.797866 98.77) (end 193.413933 99.153933) (width 0.1) (layer "In5.Cu") (net 505))
  (segment (start 246.737866 88.7) (end 246.337866 89.1) (width 0.1) (layer "In5.Cu") (net 505))
  (segment (start 248.2 88.987866) (end 247.912134 88.7) (width 0.1) (layer "In5.Cu") (net 505))
  (segment (start 243.897048 89.860818) (end 243.897048 90.190818) (width 0.1) (layer "In5.Cu") (net 505))
  (segment (start 181.92857 96.460008) (end 182.378578 96.01) (width 0.09) (layer "In5.Cu") (net 505))
  (segment (start 183.815 96.385) (end 183.815 96.465) (width 0.09) (layer "In5.Cu") (net 505))
  (segment (start 180.636328 96.416328) (end 180.680008 96.460008) (width 0.09) (layer "In5.Cu") (net 505))
  (segment (start 183.49 96.79) (end 183.39 96.79) (width 0.09) (layer "In5.Cu") (net 505))
  (segment (start 246.337866 89.1) (end 244.657866 89.1) (width 0.1) (layer "In5.Cu") (net 505))
  (segment (start 204.937866 93.1) (end 199.267866 98.77) (width 0.1) (layer "In5.Cu") (net 505))
  (segment (start 247.912134 88.7) (end 246.737866 88.7) (width 0.1) (layer "In5.Cu") (net 505))
  (segment (start 239.987866 93.1) (end 204.937866 93.1) (width 0.1) (layer "In5.Cu") (net 505))
  (segment (start 199.267866 98.77) (end 193.797866 98.77) (width 0.1) (layer "In5.Cu") (net 505))
  (segment (start 186.051469 97.093222) (end 186.051289 97.093222) (width 0.09) (layer "In5.Cu") (net 505))
  (segment (start 184.165 97.435) (end 184.165 96.385) (width 0.09) (layer "In5.Cu") (net 505))
  (segment (start 187.24 97.468578) (end 187.24 98.278578) (width 0.09) (layer "In5.Cu") (net 505))
  (segment (start 185.263 96.83) (end 185.265 96.828) (width 0.09) (layer "In5.Cu") (net 505))
  (segment (start 248.03 89.682134) (end 248.03 89.67603) (width 0.1) (layer "In5.Cu") (net 505))
  (segment (start 247.724133 89.988001) (end 248.03 89.682134) (width 0.1) (layer "In5.Cu") (net 505))
  (segment (start 188.905 99.235) (end 188.905 98.885) (width 0.09) (layer "In5.Cu") (net 505))
  (segment (start 183.815 97.365) (end 183.815 97.435) (width 0.09) (layer "In5.Cu") (net 505))
  (segment (start 243.587866 90.5) (end 242.587866 90.5) (width 0.1) (layer "In5.Cu") (net 505))
  (segment (start 185.546757 98.09291) (end 186.440379 97.199288) (width 0.09) (layer "In5.Cu") (net 505))
  (segment (start 185.297422 98.094909) (end 185.297422 98.09491) (width 0.09) (layer "In5.Cu") (net 505))
  (segment (start 180.680008 96.460008) (end 181.92857 96.460008) (width 0.09) (layer "In5.Cu") (net 505))
  (segment (start 185.297421 97.845422) (end 185.297421 97.847422) (width 0.09) (layer "In5.Cu") (net 505))
  (segment (start 185.51542 97.629091) (end 185.513752 97.629091) (width 0.09) (layer "In5.Cu") (net 505))
  (segment (start 180.636328 96.060008) (end 180.636328 96.416328) (width 0.09) (layer "In5.Cu") (net 505))
  (segment (start 182.378578 96.01) (end 183.44 96.01) (width 0.09) (layer "In5.Cu") (net 505))
  (segment (start 185.513752 97.629091) (end 185.297421 97.845422) (width 0.09) (layer "In5.Cu") (net 505))
  (segment (start 186.192892 96.9518) (end 186.051469 97.093222) (width 0.09) (layer "In5.Cu") (net 505))
  (segment (start 247.19 90.17) (end 247.371999 89.988001) (width 0.1) (layer "In5.Cu") (net 505))
  (segment (start 191.017422 99.446) (end 193.174453 99.446) (width 0.09) (layer "In5.Cu") (net 505))
  (segment (start 185.54491 98.09291) (end 185.546757 98.09291) (width 0.09) (layer "In5.Cu") (net 505))
  (segment (start 185.265 96.828) (end 185.265 96.385) (width 0.09) (layer "In5.Cu") (net 505))
  (segment (start 185.64 96.01) (end 185.781422 96.01) (width 0.09) (layer "In5.Cu") (net 505))
  (segment (start 248.03 89.67603) (end 248.2 89.50603) (width 0.1) (layer "In5.Cu") (net 505))
  (segment (start 183.39 97.04) (end 183.49 97.04) (width 0.09) (layer "In5.Cu") (net 505))
  (segment (start 193.174453 99.446) (end 193.384644 99.235809) (width 0.09) (layer "In5.Cu") (net 505))
  (segment (start 187.421422 98.46) (end 188.03 98.46) (width 0.09) (layer "In5.Cu") (net 505))
  (segment (start 248.2 89.50603) (end 248.2 88.987866) (width 0.1) (layer "In5.Cu") (net 505))
  (segment (start 185.54491 98.09491) (end 185.54491 98.09291) (width 0.09) (layer "In5.Cu") (net 505))
  (segment (start 186.051289 97.093222) (end 185.51542 97.629091) (width 0.09) (layer "In5.Cu") (net 505))
  (segment (start 243.897048 90.190818) (end 243.587866 90.5) (width 0.1) (layer "In5.Cu") (net 505))
  (segment (start 193.413933 99.165099) (end 193.413933 99.153933) (width 0.09) (layer "In5.Cu") (net 505))
  (segment (start 185.781422 96.01) (end 186.192892 96.42147) (width 0.09) (layer "In5.Cu") (net 505))
  (segment (start 247.371999 89.988001) (end 247.724133 89.988001) (width 0.1) (layer "In5.Cu") (net 505))
  (segment (start 242.587866 90.5) (end 239.987866 93.1) (width 0.1) (layer "In5.Cu") (net 505))
  (segment (start 186.970709 97.199288) (end 187.24 97.468578) (width 0.09) (layer "In5.Cu") (net 505))
  (segment (start 188.455 98.885) (end 188.455 99.235) (width 0.09) (layer "In5.Cu") (net 505))
  (segment (start 189.33 98.46) (end 190.031422 98.46) (width 0.09) (layer "In5.Cu") (net 505))
  (segment (start 244.657866 89.1) (end 243.897048 89.860818) (width 0.1) (layer "In5.Cu") (net 505))
  (segment (start 187.24 98.278578) (end 187.421422 98.46) (width 0.09) (layer "In5.Cu") (net 505))
  (segment (start 184.915 96.385) (end 184.913 96.387) (width 0.09) (layer "In5.Cu") (net 505))
  (arc (start 184.913 96.83) (mid 184.964256 96.953744) (end 185.088 97.005) (width 0.09) (layer "In5.Cu") (net 505))
  (arc (start 183.49 97.04) (mid 183.71981 97.13519) (end 183.815 97.365) (width 0.09) (layer "In5.Cu") (net 505))
  (arc (start 183.815 97.435) (mid 183.866256 97.558744) (end 183.99 97.61) (width 0.09) (layer "In5.Cu") (net 505))
  (arc (start 185.265 96.385) (mid 185.374835 96.119835) (end 185.64 96.01) (width 0.09) (layer "In5.Cu") (net 505))
  (arc (start 185.088 97.005) (mid 185.211744 96.953744) (end 185.263 96.83) (width 0.09) (layer "In5.Cu") (net 505))
  (arc (start 188.03 98.46) (mid 188.33052 98.58448) (end 188.455 98.885) (width 0.09) (layer "In5.Cu") (net 505))
  (arc (start 188.455 99.235) (mid 188.520901 99.394099) (end 188.68 99.46) (width 0.09) (layer "In5.Cu") (net 505))
  (arc (start 193.384644 99.235809) (mid 193.406321 99.203367) (end 193.413933 99.165099) (width 0.09) (layer "In5.Cu") (net 505))
  (arc (start 183.99 97.61) (mid 184.113744 97.558744) (end 184.165 97.435) (width 0.09) (layer "In5.Cu") (net 505))
  (arc (start 186.192892 96.42147) (mid 186.302727 96.686635) (end 186.192892 96.9518) (width 0.09) (layer "In5.Cu") (net 505))
  (arc (start 185.297421 97.847422) (mid 185.246165 97.971166) (end 185.297422 98.094909) (width 0.09) (layer "In5.Cu") (net 505))
  (arc (start 184.165 96.385) (mid 184.274835 96.119835) (end 184.54 96.01) (width 0.09) (layer "In5.Cu") (net 505))
  (arc (start 186.440379 97.199288) (mid 186.705544 97.089453) (end 186.970709 97.199288) (width 0.09) (layer "In5.Cu") (net 505))
  (arc (start 188.68 99.46) (mid 188.839099 99.394099) (end 188.905 99.235) (width 0.09) (layer "In5.Cu") (net 505))
  (arc (start 183.265 96.915) (mid 183.301612 97.003388) (end 183.39 97.04) (width 0.09) (layer "In5.Cu") (net 505))
  (arc (start 188.905 98.885) (mid 189.02948 98.58448) (end 189.33 98.46) (width 0.09) (layer "In5.Cu") (net 505))
  (arc (start 183.44 96.01) (mid 183.705165 96.119835) (end 183.815 96.385) (width 0.09) (layer "In5.Cu") (net 505))
  (arc (start 184.54 96.01) (mid 184.805165 96.119835) (end 184.915 96.385) (width 0.09) (layer "In5.Cu") (net 505))
  (arc (start 183.39 96.79) (mid 183.301612 96.826612) (end 183.265 96.915) (width 0.09) (layer "In5.Cu") (net 505))
  (arc (start 183.815 96.465) (mid 183.71981 96.69481) (end 183.49 96.79) (width 0.09) (layer "In5.Cu") (net 505))
  (arc (start 185.297422 98.09491) (mid 185.421166 98.146166) (end 185.54491 98.09491) (width 0.09) (layer "In5.Cu") (net 505))
  (segment (start 247.825 90.06) (end 247.825 90.475) (width 0.1) (layer "B.Cu") (net 505))
  (segment (start 247.753001 89.988001) (end 247.825 90.06) (width 0.1) (layer "B.Cu") (net 505))
  (segment (start 247.371999 89.988001) (end 247.753001 89.988001) (width 0.1) (layer "B.Cu") (net 505))
  (segment (start 247.19 90.17) (end 247.371999 89.988001) (width 0.1) (layer "B.Cu") (net 505))
  (segment (start 180.136328 95.560008) (end 179.636328 96.060008) (width 0.1) (layer "F.Cu") (net 506))
  (via (at 179.636328 96.060008) (size 0.5) (drill 0.2) (layers "F.Cu" "B.Cu") (net 506))
  (via (at 245.92 95.25) (size 0.5) (drill 0.2) (layers "F.Cu" "B.Cu") (net 506))
  (segment (start 186.881529 100.250106) (end 186.881527 100.250105) (width 0.09) (layer "In7.Cu") (net 506))
  (segment (start 179.25 96.14) (end 179.25 96.354578) (width 0.09) (layer "In7.Cu") (net 506))
  (segment (start 246.301796 95.66) (end 245.62 95.66) (width 0.1) (layer "In7.Cu") (net 506))
  (segment (start 242.927 94.741765) (end 242.927 94.87) (width 0.1) (layer "In7.Cu") (net 506))
  (segment (start 189.941422 100.3) (end 190.341422 100.7) (width 0.09) (layer "In7.Cu") (net 506))
  (segment (start 182.334449 96.465027) (end 182.596209 96.726788) (width 0.09) (layer "In7.Cu") (net 506))
  (segment (start 193.909422 100.718) (end 194.861578 100.718) (width 0.09) (layer "In7.Cu") (net 506))
  (segment (start 242.727 95.07) (end 242.677 95.07) (width 0.1) (layer "In7.Cu") (net 506))
  (segment (start 244.082134 95.07) (end 243.527 95.07) (width 0.1) (layer "In7.Cu") (net 506))
  (segment (start 246.335867 95.068001) (end 246.51 95.242134) (width 0.1) (layer "In7.Cu") (net 506))
  (segment (start 246.51 95.451796) (end 246.301796 95.66) (width 0.1) (layer "In7.Cu") (net 506))
  (segment (start 190.341422 100.7) (end 191.658578 100.7) (width 0.09) (layer "In7.Cu") (net 506))
  (segment (start 243.327 94.87) (end 243.327 94.741765) (width 0.1) (layer "In7.Cu") (net 506))
  (segment (start 186.881527 100.250105) (end 186.931422 100.3) (width 0.09) (layer "In7.Cu") (net 506))
  (segment (start 191.901578 100.457) (end 193.648422 100.457) (width 0.09) (layer "In7.Cu") (net 506))
  (segment (start 242.567366 95.07) (end 241.037366 96.6) (width 0.1) (layer "In7.Cu") (net 506))
  (segment (start 245.02 95.41) (end 245.02 95.46) (width 0.1) (layer "In7.Cu") (net 506))
  (segment (start 183.409381 97.115697) (end 182.879052 97.646027) (width 0.09) (layer "In7.Cu") (net 506))
  (segment (start 182.808343 96.72679) (end 182.914408 96.620722) (width 0.09) (layer "In7.Cu") (net 506))
  (segment (start 195.442578 100.137) (end 198.112716 100.137) (width 0.09) (layer "In7.Cu") (net 506))
  (segment (start 179.636328 96.060008) (end 179.329992 96.060008) (width 0.09) (layer "In7.Cu") (net 506))
  (segment (start 198.183427 100.10771) (end 198.216048 100.075089) (width 0.09) (layer "In7.Cu") (net 506))
  (segment (start 204.148866 96.6) (end 200.673777 100.075089) (width 0.1) (layer "In7.Cu") (net 506))
  (segment (start 186.987593 99.896553) (end 186.881528 100.002619) (width 0.09) (layer "In7.Cu") (net 506))
  (segment (start 194.861578 100.718) (end 195.442578 100.137) (width 0.09) (layer "In7.Cu") (net 506))
  (segment (start 245.42 95.46) (end 245.42 95.41) (width 0.1) (layer "In7.Cu") (net 506))
  (segment (start 184.010422 98.141001) (end 185.251422 99.382) (width 0.09) (layer "In7.Cu") (net 506))
  (segment (start 179.360449 96.465027) (end 182.334449 96.465027) (width 0.09) (layer "In7.Cu") (net 506))
  (segment (start 186.013422 99.382) (end 186.103709 99.472288) (width 0.09) (layer "In7.Cu") (net 506))
  (segment (start 200.673777 100.075089) (end 198.216048 100.075089) (width 0.1) (layer "In7.Cu") (net 506))
  (segment (start 188.628 100.95) (end 188.628 100.7) (width 0.09) (layer "In7.Cu") (net 506))
  (segment (start 242.677 95.07) (end 242.567366 95.07) (width 0.1) (layer "In7.Cu") (net 506))
  (segment (start 193.648422 100.457) (end 193.909422 100.718) (width 0.09) (layer "In7.Cu") (net 506))
  (segment (start 241.037366 96.6) (end 204.148866 96.6) (width 0.1) (layer "In7.Cu") (net 506))
  (segment (start 246.101999 95.068001) (end 246.335867 95.068001) (width 0.1) (layer "In7.Cu") (net 506))
  (segment (start 189.028 100.3) (end 189.941422 100.3) (width 0.09) (layer "In7.Cu") (net 506))
  (segment (start 186.987595 99.366223) (end 186.987594 99.366222) (width 0.09) (layer "In7.Cu") (net 506))
  (segment (start 244.82 95.66) (end 244.672134 95.66) (width 0.1) (layer "In7.Cu") (net 506))
  (segment (start 186.351199 99.47229) (end 186.457264 99.366222) (width 0.09) (layer "In7.Cu") (net 506))
  (segment (start 183.091185 97.858158) (end 183.091184 97.858159) (width 0.09) (layer "In7.Cu") (net 506))
  (segment (start 179.25 96.354578) (end 179.360449 96.465027) (width 0.09) (layer "In7.Cu") (net 506))
  (segment (start 188.228 99.4) (end 188.228 100.95) (width 0.09) (layer "In7.Cu") (net 506))
  (segment (start 186.931422 100.3) (end 187.228 100.3) (width 0.09) (layer "In7.Cu") (net 506))
  (segment (start 245.92 95.25) (end 246.101999 95.068001) (width 0.1) (layer "In7.Cu") (net 506))
  (segment (start 244.672134 95.66) (end 244.082134 95.07) (width 0.1) (layer "In7.Cu") (net 506))
  (segment (start 183.091184 97.858159) (end 183.621513 97.327827) (width 0.09) (layer "In7.Cu") (net 506))
  (segment (start 183.409383 96.620723) (end 183.409382 96.620722) (width 0.09) (layer "In7.Cu") (net 506))
  (segment (start 179.329992 96.060008) (end 179.25 96.14) (width 0.09) (layer "In7.Cu") (net 506))
  (segment (start 191.658578 100.7) (end 191.901578 100.457) (width 0.09) (layer "In7.Cu") (net 506))
  (segment (start 184.116486 97.822802) (end 184.010421 97.928868) (width 0.09) (layer "In7.Cu") (net 506))
  (segment (start 185.251422 99.382) (end 186.013422 99.382) (width 0.09) (layer "In7.Cu") (net 506))
  (segment (start 246.51 95.242134) (end 246.51 95.451796) (width 0.1) (layer "In7.Cu") (net 506))
  (segment (start 187.428 100.1) (end 187.428 99.4) (width 0.09) (layer "In7.Cu") (net 506))
  (arc (start 245.42 95.41) (mid 245.361421 95.268579) (end 245.22 95.21) (width 0.1) (layer "In7.Cu") (net 506))
  (arc (start 242.927 94.87) (mid 242.868421 95.011421) (end 242.727 95.07) (width 0.1) (layer "In7.Cu") (net 506))
  (arc (start 183.409382 96.620722) (mid 183.511894 96.86821) (end 183.409381 97.115697) (width 0.09) (layer "In7.Cu") (net 506))
  (arc (start 243.527 95.07) (mid 243.385579 95.011421) (end 243.327 94.87) (width 0.1) (layer "In7.Cu") (net 506))
  (arc (start 186.987594 99.366222) (mid 187.09743 99.631389) (end 186.987593 99.896553) (width 0.09) (layer "In7.Cu") (net 506))
  (arc (start 186.457264 99.366222) (mid 186.722431 99.256388) (end 186.987595 99.366223) (width 0.09) (layer "In7.Cu") (net 506))
  (arc (start 198.112716 100.137) (mid 198.150985 100.129388) (end 198.183427 100.10771) (width 0.09) (layer "In7.Cu") (net 506))
  (arc (start 183.621513 97.327827) (mid 183.869001 97.225316) (end 184.116487 97.327827) (width 0.09) (layer "In7.Cu") (net 506))
  (arc (start 186.881528 100.002619) (mid 186.830272 100.126363) (end 186.881529 100.250106) (width 0.09) (layer "In7.Cu") (net 506))
  (arc (start 186.103709 99.472288) (mid 186.227455 99.523546) (end 186.351199 99.47229) (width 0.09) (layer "In7.Cu") (net 506))
  (arc (start 187.428 99.4) (mid 187.545157 99.117157) (end 187.828 99) (width 0.09) (layer "In7.Cu") (net 506))
  (arc (start 243.127 94.541765) (mid 242.985579 94.600344) (end 242.927 94.741765) (width 0.1) (layer "In7.Cu") (net 506))
  (arc (start 245.22 95.21) (mid 245.078579 95.268579) (end 245.02 95.41) (width 0.1) (layer "In7.Cu") (net 506))
  (arc (start 187.228 100.3) (mid 187.369421 100.241421) (end 187.428 100.1) (width 0.09) (layer "In7.Cu") (net 506))
  (arc (start 182.879052 97.858159) (mid 182.985119 97.902093) (end 183.091185 97.858158) (width 0.09) (layer "In7.Cu") (net 506))
  (arc (start 184.010421 97.928868) (mid 183.966486 98.034934) (end 184.010422 98.141001) (width 0.09) (layer "In7.Cu") (net 506))
  (arc (start 184.116487 97.327827) (mid 184.218999 97.575315) (end 184.116486 97.822802) (width 0.09) (layer "In7.Cu") (net 506))
  (arc (start 182.596209 96.726788) (mid 182.702277 96.770724) (end 182.808343 96.72679) (width 0.09) (layer "In7.Cu") (net 506))
  (arc (start 245.62 95.66) (mid 245.478579 95.601421) (end 245.42 95.46) (width 0.1) (layer "In7.Cu") (net 506))
  (arc (start 188.428 101.15) (mid 188.569421 101.091421) (end 188.628 100.95) (width 0.09) (layer "In7.Cu") (net 506))
  (arc (start 187.828 99) (mid 188.110843 99.117157) (end 188.228 99.4) (width 0.09) (layer "In7.Cu") (net 506))
  (arc (start 182.879052 97.646027) (mid 182.835118 97.752093) (end 182.879052 97.858159) (width 0.09) (layer "In7.Cu") (net 506))
  (arc (start 245.02 95.46) (mid 244.961421 95.601421) (end 244.82 95.66) (width 0.1) (layer "In7.Cu") (net 506))
  (arc (start 182.914408 96.620722) (mid 183.161896 96.51821) (end 183.409383 96.620723) (width 0.09) (layer "In7.Cu") (net 506))
  (arc (start 188.228 100.95) (mid 188.286579 101.091421) (end 188.428 101.15) (width 0.09) (layer "In7.Cu") (net 506))
  (arc (start 243.327 94.741765) (mid 243.268421 94.600344) (end 243.127 94.541765) (width 0.1) (layer "In7.Cu") (net 506))
  (arc (start 188.628 100.7) (mid 188.745157 100.417157) (end 189.028 100.3) (width 0.09) (layer "In7.Cu") (net 506))
  (segment (start 245.92 95.25) (end 246.101999 95.068001) (width 0.1) (layer "B.Cu") (net 506))
  (segment (start 246.101999 95.068001) (end 246.483001 95.068001) (width 0.1) (layer "B.Cu") (net 506))
  (segment (start 246.555 95.14) (end 246.555 95.555) (width 0.1) (layer "B.Cu") (net 506))
  (segment (start 246.483001 95.068001) (end 246.555 95.14) (width 0.1) (layer "B.Cu") (net 506))
  (segment (start 179.136328 95.560008) (end 178.636328 96.060008) (width 0.1) (layer "F.Cu") (net 507))
  (via (at 178.636328 96.060008) (size 0.5) (drill 0.2) (layers "F.Cu" "B.Cu") (net 507))
  (via (at 245.92 94.586) (size 0.5) (drill 0.2) (layers "F.Cu" "B.Cu") (net 507))
  (segment (start 246.460133 94.767999) (end 246.81 95.117866) (width 0.1) (layer "In7.Cu") (net 507))
  (segment (start 185.930578 99.582) (end 185.962288 99.613709) (width 0.09) (layer "In7.Cu") (net 507))
  (segment (start 243.957866 95.37) (end 242.691634 95.37) (width 0.1) (layer "In7.Cu") (net 507))
  (segment (start 244.547866 95.96) (end 243.957866 95.37) (width 0.1) (layer "In7.Cu") (net 507))
  (segment (start 188.028 99.4) (end 188.028 100.95) (width 0.09) (layer "In7.Cu") (net 507))
  (segment (start 185.168578 99.582) (end 185.930578 99.582) (width 0.09) (layer "In7.Cu") (net 507))
  (segment (start 188.828 100.95) (end 188.828 100.7) (width 0.09) (layer "In7.Cu") (net 507))
  (segment (start 183.267964 96.762145) (end 183.267963 96.762144) (width 0.09) (layer "In7.Cu") (net 507))
  (segment (start 245.92 94.586) (end 246.101999 94.767999) (width 0.1) (layer "In7.Cu") (net 507))
  (segment (start 186.846172 99.507644) (end 186.846173 99.507644) (width 0.09) (layer "In7.Cu") (net 507))
  (segment (start 189.858578 100.5) (end 190.258578 100.9) (width 0.09) (layer "In7.Cu") (net 507))
  (segment (start 178.979008 96.060008) (end 179.05 96.131) (width 0.09) (layer "In7.Cu") (net 507))
  (segment (start 178.636328 96.060008) (end 178.979008 96.060008) (width 0.09) (layer "In7.Cu") (net 507))
  (segment (start 241.161634 96.9) (end 204.273134 96.9) (width 0.1) (layer "In7.Cu") (net 507))
  (segment (start 182.73763 97.999581) (end 182.73763 97.99958) (width 0.09) (layer "In7.Cu") (net 507))
  (segment (start 179.05 96.437422) (end 179.277586 96.665008) (width 0.09) (layer "In7.Cu") (net 507))
  (segment (start 187.628 100.1) (end 187.628 99.4) (width 0.09) (layer "In7.Cu") (net 507))
  (segment (start 200.798045 100.375089) (end 198.216048 100.375089) (width 0.1) (layer "In7.Cu") (net 507))
  (segment (start 246.426064 95.96) (end 244.547866 95.96) (width 0.1) (layer "In7.Cu") (net 507))
  (segment (start 182.251586 96.665008) (end 182.454788 96.868209) (width 0.09) (layer "In7.Cu") (net 507))
  (segment (start 193.565578 100.657) (end 193.826578 100.918) (width 0.09) (layer "In7.Cu") (net 507))
  (segment (start 179.05 96.131) (end 179.05 96.437422) (width 0.09) (layer "In7.Cu") (net 507))
  (segment (start 193.826578 100.918) (end 194.944422 100.918) (width 0.09) (layer "In7.Cu") (net 507))
  (segment (start 190.258578 100.9) (end 191.741422 100.9) (width 0.09) (layer "In7.Cu") (net 507))
  (segment (start 183.232605 97.999579) (end 183.232604 97.99958) (width 0.09) (layer "In7.Cu") (net 507))
  (segment (start 195.525422 100.337) (end 198.136538 100.337) (width 0.09) (layer "In7.Cu") (net 507))
  (segment (start 182.949764 96.868211) (end 182.949764 96.86821) (width 0.09) (layer "In7.Cu") (net 507))
  (segment (start 246.81 95.117866) (end 246.81 95.576064) (width 0.1) (layer "In7.Cu") (net 507))
  (segment (start 183.975065 97.681381) (end 183.869 97.787447) (width 0.09) (layer "In7.Cu") (net 507))
  (segment (start 186.846172 99.755131) (end 186.846172 99.75513) (width 0.09) (layer "In7.Cu") (net 507))
  (segment (start 183.267962 96.974277) (end 183.267963 96.974276) (width 0.09) (layer "In7.Cu") (net 507))
  (segment (start 183.232604 97.99958) (end 183.762934 97.469248) (width 0.09) (layer "In7.Cu") (net 507))
  (segment (start 186.846172 99.75513) (end 186.740106 99.861197) (width 0.09) (layer "In7.Cu") (net 507))
  (segment (start 183.267963 96.974276) (end 182.73763 97.504605) (width 0.09) (layer "In7.Cu") (net 507))
  (segment (start 246.101999 94.767999) (end 246.460133 94.767999) (width 0.1) (layer "In7.Cu") (net 507))
  (segment (start 242.691634 95.37) (end 241.161634 96.9) (width 0.1) (layer "In7.Cu") (net 507))
  (segment (start 186.49262 99.613711) (end 186.598685 99.507643) (width 0.09) (layer "In7.Cu") (net 507))
  (segment (start 198.207249 100.36629) (end 198.216048 100.375089) (width 0.09) (layer "In7.Cu") (net 507))
  (segment (start 186.740107 100.391528) (end 186.848578 100.5) (width 0.09) (layer "In7.Cu") (net 507))
  (segment (start 189.028 100.5) (end 189.858578 100.5) (width 0.09) (layer "In7.Cu") (net 507))
  (segment (start 192.863615 100.655) (end 192.865615 100.657) (width 0.09) (layer "In7.Cu") (net 507))
  (segment (start 191.986422 100.655) (end 192.863615 100.655) (width 0.09) (layer "In7.Cu") (net 507))
  (segment (start 179.277586 96.665008) (end 182.251586 96.665008) (width 0.09) (layer "In7.Cu") (net 507))
  (segment (start 204.273134 96.9) (end 200.798045 100.375089) (width 0.1) (layer "In7.Cu") (net 507))
  (segment (start 191.741422 100.9) (end 191.986422 100.655) (width 0.09) (layer "In7.Cu") (net 507))
  (segment (start 186.848578 100.5) (end 187.228 100.5) (width 0.09) (layer "In7.Cu") (net 507))
  (segment (start 183.869001 98.282422) (end 185.168578 99.582) (width 0.09) (layer "In7.Cu") (net 507))
  (segment (start 194.944422 100.918) (end 195.525422 100.337) (width 0.09) (layer "In7.Cu") (net 507))
  (segment (start 246.81 95.576064) (end 246.426064 95.96) (width 0.1) (layer "In7.Cu") (net 507))
  (segment (start 192.865615 100.657) (end 193.565578 100.657) (width 0.09) (layer "In7.Cu") (net 507))
  (segment (start 182.949764 96.86821) (end 183.055831 96.762144) (width 0.09) (layer "In7.Cu") (net 507))
  (arc (start 186.740106 99.861197) (mid 186.63027 100.126362) (end 186.740107 100.391528) (width 0.09) (layer "In7.Cu") (net 507))
  (arc (start 188.028 100.95) (mid 188.145157 101.232843) (end 188.428 101.35) (width 0.09) (layer "In7.Cu") (net 507))
  (arc (start 182.73763 97.99958) (mid 182.985118 98.102092) (end 183.232605 97.999579) (width 0.09) (layer "In7.Cu") (net 507))
  (arc (start 183.975066 97.469248) (mid 184.019001 97.575316) (end 183.975065 97.681381) (width 0.09) (layer "In7.Cu") (net 507))
  (arc (start 182.454788 96.868209) (mid 182.702276 96.970722) (end 182.949764 96.868211) (width 0.09) (layer "In7.Cu") (net 507))
  (arc (start 183.869 97.787447) (mid 183.766488 98.034935) (end 183.869001 98.282422) (width 0.09) (layer "In7.Cu") (net 507))
  (arc (start 187.828 99.2) (mid 187.969421 99.258579) (end 188.028 99.4) (width 0.09) (layer "In7.Cu") (net 507))
  (arc (start 188.828 100.7) (mid 188.886579 100.558579) (end 189.028 100.5) (width 0.09) (layer "In7.Cu") (net 507))
  (arc (start 183.762934 97.469248) (mid 183.869 97.425314) (end 183.975066 97.469248) (width 0.09) (layer "In7.Cu") (net 507))
  (arc (start 186.846173 99.507644) (mid 186.897429 99.631388) (end 186.846172 99.755131) (width 0.09) (layer "In7.Cu") (net 507))
  (arc (start 183.055831 96.762144) (mid 183.161897 96.718209) (end 183.267964 96.762145) (width 0.09) (layer "In7.Cu") (net 507))
  (arc (start 187.228 100.5) (mid 187.510843 100.382843) (end 187.628 100.1) (width 0.09) (layer "In7.Cu") (net 507))
  (arc (start 182.73763 97.504605) (mid 182.635117 97.752093) (end 182.73763 97.999581) (width 0.09) (layer "In7.Cu") (net 507))
  (arc (start 188.428 101.35) (mid 188.710843 101.232843) (end 188.828 100.95) (width 0.09) (layer "In7.Cu") (net 507))
  (arc (start 183.267963 96.762144) (mid 183.311896 96.86821) (end 183.267962 96.974277) (width 0.09) (layer "In7.Cu") (net 507))
  (arc (start 198.136538 100.337) (mid 198.174807 100.344612) (end 198.207249 100.36629) (width 0.09) (layer "In7.Cu") (net 507))
  (arc (start 186.598685 99.507643) (mid 186.722429 99.456387) (end 186.846172 99.507644) (width 0.09) (layer "In7.Cu") (net 507))
  (arc (start 187.628 99.4) (mid 187.686579 99.258579) (end 187.828 99.2) (width 0.09) (layer "In7.Cu") (net 507))
  (arc (start 185.962288 99.613709) (mid 186.227455 99.723546) (end 186.49262 99.613711) (width 0.09) (layer "In7.Cu") (net 507))
  (segment (start 245.92 94.586) (end 246.101999 94.767999) (width 0.1) (layer "B.Cu") (net 507))
  (segment (start 246.101999 94.767999) (end 246.452001 94.767999) (width 0.1) (layer "B.Cu") (net 507))
  (segment (start 246.555 94.665) (end 246.555 94.285) (width 0.1) (layer "B.Cu") (net 507))
  (segment (start 246.452001 94.767999) (end 246.555 94.665) (width 0.1) (layer "B.Cu") (net 507))
  (segment (start 248.704044 77.114093) (end 250.376062 75.442078) (width 0.122) (layer "F.Cu") (net 512))
  (segment (start 256.889705 76.15669) (end 256.900661 76.145733) (width 0.122) (layer "F.Cu") (net 512))
  (segment (start 199.266547 91.2735) (end 239.576881 91.2735) (width 0.122) (layer "F.Cu") (net 512))
  (segment (start 257.4365 77.9935) (end 257.4365 78.0435) (width 0.122) (layer "F.Cu") (net 512))
  (segment (start 257.4365 76.552283) (end 257.4365 77.9935) (width 0.122) (layer "F.Cu") (net 512))
  (segment (start 196.646227 91.210579) (end 196.702824 91.267176) (width 0.1) (layer "F.Cu") (net 512))
  (segment (start 198.145 91.8535) (end 198.328252 91.8535) (width 0.122) (layer "F.Cu") (net 512))
  (segment (start 256.889706 76.156689) (end 256.889705 76.15669) (width 0.122) (layer "F.Cu") (net 512))
  (segment (start 250.517483 75.3835) (end 256.267717 75.3835) (width 0.122) (layer "F.Cu") (net 512))
  (segment (start 195.760618 91.238734) (end 195.818063 91.181289) (width 0.1) (layer "F.Cu") (net 512))
  (segment (start 248.710082 77.367619) (end 248.704044 77.361581) (width 0.122) (layer "F.Cu") (net 512))
  (segment (start 196.702823 91.443953) (end 196.702824 91.443952) (width 0.1) (layer "F.Cu") (net 512))
  (segment (start 198.141935 91.850435) (end 198.145 91.8535) (width 0.1) (layer "F.Cu") (net 512))
  (segment (start 196.136328 91.560008) (end 195.885429 91.560008) (width 0.1) (layer "F.Cu") (net 512))
  (segment (start 242.012283 89.4035) (end 243.288252 89.4035) (width 0.122) (layer "F.Cu") (net 512))
  (segment (start 196.879601 91.620727) (end 196.8796 91.620728) (width 0.1) (layer "F.Cu") (net 512))
  (segment (start 243.546346 89.296594) (end 244.145486 88.697454) (width 0.122) (layer "F.Cu") (net 512))
  (segment (start 257.4365 78.6435) (end 257.4365 79.389139) (width 0.122) (layer "F.Cu") (net 512))
  (segment (start 257.40721 79.45985) (end 257.358849 79.508211) (width 0.122) (layer "F.Cu") (net 512))
  (segment (start 257.112793 76.145733) (end 257.112794 76.145734) (width 0.122) (layer "F.Cu") (net 512))
  (segment (start 256.409139 75.442079) (end 256.68853 75.72147) (width 0.122) (layer "F.Cu") (net 512))
  (segment (start 197.056377 91.620729) (end 197.157895 91.722247) (width 0.1) (layer "F.Cu") (net 512))
  (segment (start 245.4335 88.048252) (end 245.4335 80.467483) (width 0.122) (layer "F.Cu") (net 512))
  (segment (start 248.456557 77.60907) (end 248.462594 77.615107) (width 0.122) (layer "F.Cu") (net 512))
  (segment (start 256.962921 79.478921) (end 256.665 79.181) (width 0.122) (layer "F.Cu") (net 512))
  (segment (start 256.688529 75.933603) (end 256.68853 75.933602) (width 0.122) (layer "F.Cu") (net 512))
  (segment (start 244.286907 88.638876) (end 244.842876 88.638876) (width 0.122) (layer "F.Cu") (net 512))
  (segment (start 245.10097 88.53197) (end 245.326594 88.306346) (width 0.122) (layer "F.Cu") (net 512))
  (segment (start 195.888773 91.152) (end 196.504805 91.152) (width 0.1) (layer "F.Cu") (net 512))
  (segment (start 257.288139 79.5375) (end 257.104343 79.5375) (width 0.122) (layer "F.Cu") (net 512))
  (segment (start 245.492079 80.326061) (end 248.20907 77.60907) (width 0.122) (layer "F.Cu") (net 512))
  (segment (start 198.586346 91.746594) (end 198.912994 91.419946) (width 0.122) (layer "F.Cu") (net 512))
  (segment (start 248.710081 77.615108) (end 248.710082 77.615107) (width 0.122) (layer "F.Cu") (net 512))
  (segment (start 248.456556 77.60907) (end 248.456557 77.60907) (width 0.122) (layer "F.Cu") (net 512))
  (segment (start 240.40066 90.93228) (end 241.870862 89.462078) (width 0.122) (layer "F.Cu") (net 512))
  (segment (start 195.814718 91.530718) (end 195.760617 91.476617) (width 0.1) (layer "F.Cu") (net 512))
  (segment (start 248.704043 77.114094) (end 248.704044 77.114093) (width 0.122) (layer "F.Cu") (net 512))
  (segment (start 195.731328 91.405907) (end 195.731328 91.309445) (width 0.1) (layer "F.Cu") (net 512))
  (segment (start 197.362956 91.807186) (end 198.065571 91.807186) (width 0.1) (layer "F.Cu") (net 512))
  (segment (start 197.056376 91.620728) (end 197.056377 91.620729) (width 0.1) (layer "F.Cu") (net 512))
  (segment (start 256.68853 75.933602) (end 256.677573 75.944558) (width 0.122) (layer "F.Cu") (net 512))
  (segment (start 257.112794 76.145734) (end 257.377922 76.410862) (width 0.122) (layer "F.Cu") (net 512))
  (arc (start 257.377922 76.410862) (mid 257.421276 76.475747) (end 257.4365 76.552283) (width 0.122) (layer "F.Cu") (net 512))
  (arc (start 239.576881 91.2735) (mid 240.022707 91.18482) (end 240.40066 90.93228) (width 0.122) (layer "F.Cu") (net 512))
  (arc (start 256.900661 76.145733) (mid 257.006727 76.101799) (end 257.112793 76.145733) (width 0.122) (layer "F.Cu") (net 512))
  (arc (start 257.104343 79.5375) (mid 257.027806 79.522276) (end 256.962921 79.478921) (width 0.122) (layer "F.Cu") (net 512))
  (arc (start 250.376062 75.442078) (mid 250.440947 75.398724) (end 250.517483 75.3835) (width 0.122) (layer "F.Cu") (net 512))
  (arc (start 257.4365 78.0435) (mid 257.392566 78.149566) (end 257.2865 78.1935) (width 0.122) (layer "F.Cu") (net 512))
  (arc (start 248.710082 77.615107) (mid 248.761338 77.491363) (end 248.710082 77.367619) (width 0.122) (layer "F.Cu") (net 512))
  (arc (start 195.760617 91.476617) (mid 195.73894 91.444175) (end 195.731328 91.405907) (width 0.1) (layer "F.Cu") (net 512))
  (arc (start 257.358849 79.508211) (mid 257.326407 79.529888) (end 257.288139 79.5375) (width 0.122) (layer "F.Cu") (net 512))
  (arc (start 196.702824 91.620728) (mid 196.791213 91.657339) (end 196.879601 91.620727) (width 0.1) (layer "F.Cu") (net 512))
  (arc (start 196.702824 91.443952) (mid 196.666212 91.53234) (end 196.702824 91.620728) (width 0.1) (layer "F.Cu") (net 512))
  (arc (start 198.065571 91.807186) (mid 198.106577 91.82422) (end 198.141935 91.850435) (width 0.1) (layer "F.Cu") (net 512))
  (arc (start 198.328252 91.8535) (mid 198.467931 91.825716) (end 198.586346 91.746594) (width 0.122) (layer "F.Cu") (net 512))
  (arc (start 248.704044 77.361581) (mid 248.652787 77.237838) (end 248.704043 77.114094) (width 0.122) (layer "F.Cu") (net 512))
  (arc (start 245.4335 80.467483) (mid 245.448724 80.390946) (end 245.492079 80.326061) (width 0.122) (layer "F.Cu") (net 512))
  (arc (start 244.145486 88.697454) (mid 244.210371 88.6541) (end 244.286907 88.638876) (width 0.122) (layer "F.Cu") (net 512))
  (arc (start 196.702824 91.267176) (mid 196.739435 91.355565) (end 196.702823 91.443953) (width 0.1) (layer "F.Cu") (net 512))
  (arc (start 257.1365 78.3435) (mid 257.180434 78.449566) (end 257.2865 78.4935) (width 0.122) (layer "F.Cu") (net 512))
  (arc (start 257.4365 79.389139) (mid 257.428888 79.427408) (end 257.40721 79.45985) (width 0.122) (layer "F.Cu") (net 512))
  (arc (start 197.157895 91.722247) (mid 197.251978 91.785111) (end 197.362956 91.807186) (width 0.1) (layer "F.Cu") (net 512))
  (arc (start 256.267717 75.3835) (mid 256.344254 75.398724) (end 256.409139 75.442079) (width 0.122) (layer "F.Cu") (net 512))
  (arc (start 241.870862 89.462078) (mid 241.935747 89.418724) (end 242.012283 89.4035) (width 0.122) (layer "F.Cu") (net 512))
  (arc (start 198.912994 91.419946) (mid 199.075206 91.31156) (end 199.266547 91.2735) (width 0.122) (layer "F.Cu") (net 512))
  (arc (start 256.677573 75.944558) (mid 256.633639 76.050624) (end 256.677573 76.15669) (width 0.122) (layer "F.Cu") (net 512))
  (arc (start 256.68853 75.72147) (mid 256.732464 75.827537) (end 256.688529 75.933603) (width 0.122) (layer "F.Cu") (net 512))
  (arc (start 257.2865 78.4935) (mid 257.392566 78.537434) (end 257.4365 78.6435) (width 0.122) (layer "F.Cu") (net 512))
  (arc (start 243.288252 89.4035) (mid 243.427931 89.375716) (end 243.546346 89.296594) (width 0.122) (layer "F.Cu") (net 512))
  (arc (start 248.462594 77.615107) (mid 248.586337 77.666364) (end 248.710081 77.615108) (width 0.122) (layer "F.Cu") (net 512))
  (arc (start 248.20907 77.60907) (mid 248.332813 77.557814) (end 248.456556 77.60907) (width 0.122) (layer "F.Cu") (net 512))
  (arc (start 257.2865 78.1935) (mid 257.180434 78.237434) (end 257.1365 78.3435) (width 0.122) (layer "F.Cu") (net 512))
  (arc (start 196.8796 91.620728) (mid 196.967988 91.584116) (end 197.056376 91.620728) (width 0.1) (layer "F.Cu") (net 512))
  (arc (start 196.504805 91.152) (mid 196.581342 91.167224) (end 196.646227 91.210579) (width 0.1) (layer "F.Cu") (net 512))
  (arc (start 195.818063 91.181289) (mid 195.850505 91.159612) (end 195.888773 91.152) (width 0.1) (layer "F.Cu") (net 512))
  (arc (start 195.731328 91.309445) (mid 195.73894 91.271176) (end 195.760618 91.238734) (width 0.1) (layer "F.Cu") (net 512))
  (arc (start 256.677573 76.15669) (mid 256.78364 76.200624) (end 256.889706 76.156689) (width 0.122) (layer "F.Cu") (net 512))
  (arc (start 195.885429 91.560008) (mid 195.84716 91.552396) (end 195.814718 91.530718) (width 0.1) (layer "F.Cu") (net 512))
  (arc (start 244.842876 88.638876) (mid 244.982555 88.611092) (end 245.10097 88.53197) (width 0.122) (layer "F.Cu") (net 512))
  (arc (start 245.326594 88.306346) (mid 245.405716 88.187931) (end 245.4335 88.048252) (width 0.122) (layer "F.Cu") (net 512))
  (segment (start 255.394079 84.960079) (end 255.695 85.261) (width 0.122) (layer "F.Cu") (net 513))
  (segment (start 254.81 85.09) (end 254.939922 84.960078) (width 0.122) (layer "F.Cu") (net 513))
  (segment (start 255.081343 84.9015) (end 255.252657 84.9015) (width 0.122) (layer "F.Cu") (net 513))
  (via (at 254.81 85.09) (size 0.5) (drill 0.2) (layers "F.Cu" "B.Cu") (net 513))
  (arc (start 255.394079 84.960079) (mid 255.329194 84.916724) (end 255.252657 84.9015) (width 0.122) (layer "F.Cu") (net 513))
  (arc (start 254.939922 84.960078) (mid 255.004807 84.916724) (end 255.081343 84.9015) (width 0.122) (layer "F.Cu") (net 513))
  (segment (start 255.415079 84.960079) (end 255.415711 84.960711) (width 0.122) (layer "B.Cu") (net 513))
  (segment (start 255.081343 84.9015) (end 255.273657 84.9015) (width 0.122) (layer "B.Cu") (net 513))
  (segment (start 255.445 85.031421) (end 255.445 85.395) (width 0.122) (layer "B.Cu") (net 513))
  (segment (start 254.81 85.09) (end 254.939922 84.960078) (width 0.122) (layer "B.Cu") (net 513))
  (arc (start 255.081343 84.9015) (mid 255.004807 84.916724) (end 254.939922 84.960078) (width 0.122) (layer "B.Cu") (net 513))
  (arc (start 255.273657 84.9015) (mid 255.350194 84.916724) (end 255.415079 84.960079) (width 0.122) (layer "B.Cu") (net 513))
  (arc (start 255.445 85.031421) (mid 255.437388 84.993153) (end 255.415711 84.960711) (width 0.122) (layer "B.Cu") (net 513))
  (segment (start 177.636328 96.060008) (end 178.136328 95.560008) (width 0.1) (layer "F.Cu") (net 514))
  (via (at 245.92 114.3) (size 0.5) (drill 0.2) (layers "F.Cu" "B.Cu") (net 514))
  (via (at 177.636328 96.060008) (size 0.5) (drill 0.2) (layers "F.Cu" "B.Cu") (net 514))
  (segment (start 182.378578 96.07) (end 186.831422 96.07) (width 0.09) (layer "In9.Cu") (net 514))
  (segment (start 177.199992 96.060008) (end 177.04 96.22) (width 0.09) (layer "In9.Cu") (net 514))
  (segment (start 177.636328 96.060008) (end 177.199992 96.060008) (width 0.09) (layer "In9.Cu") (net 514))
  (segment (start 189.218578 95.46) (end 193.133578 95.46) (width 0.09) (layer "In9.Cu") (net 514))
  (segment (start 245.312134 114.4) (end 244.112134 114.4) (width 0.1) (layer "In9.Cu") (net 514))
  (segment (start 239.65 106.687866) (end 239.65 103.187866) (width 0.1) (layer "In9.Cu") (net 514))
  (segment (start 197.122134 96.31) (end 196.592134 96.31) (width 0.1) (layer "In9.Cu") (net 514))
  (segment (start 186.831422 96.07) (end 187.226449 96.465027) (width 0.09) (layer "In9.Cu") (net 514))
  (segment (start 245.92 114.3) (end 246.101999 114.118001) (width 0.1) (layer "In9.Cu") (net 514))
  (segment (start 242.65 112.937866) (end 242.65 111.187866) (width 0.1) (layer "In9.Cu") (net 514))
  (segment (start 177.04 96.22) (end 177.04 96.38) (width 0.09) (layer "In9.Cu") (net 514))
  (segment (start 177.04 96.38) (end 177.125027 96.465027) (width 0.09) (layer "In9.Cu") (net 514))
  (segment (start 246.57 114.675339) (end 246.395339 114.85) (width 0.1) (layer "In9.Cu") (net 514))
  (segment (start 187.226449 96.465027) (end 188.213551 96.465027) (width 0.09) (layer "In9.Cu") (net 514))
  (segment (start 241.15 109.687866) (end 241.15 108.187866) (width 0.1) (layer "In9.Cu") (net 514))
  (segment (start 243.840185 113.848415) (end 243.840185 113.848416) (width 0.1) (layer "In9.Cu") (net 514))
  (segment (start 246.395339 114.85) (end 245.762134 114.85) (width 0.1) (layer "In9.Cu") (net 514))
  (segment (start 195.331835 95.049701) (end 193.850999 95.049701) (width 0.1) (layer "In9.Cu") (net 514))
  (segment (start 246.57 114.378134) (end 246.57 114.675339) (width 0.1) (layer "In9.Cu") (net 514))
  (segment (start 245.762134 114.85) (end 245.312134 114.4) (width 0.1) (layer "In9.Cu") (net 514))
  (segment (start 244.018566 114.0943) (end 244.018567 114.0943) (width 0.1) (layer "In9.Cu") (net 514))
  (segment (start 243.840185 113.848416) (end 243.806433 113.882167) (width 0.1) (layer "In9.Cu") (net 514))
  (segment (start 177.125027 96.465027) (end 181.983551 96.465027) (width 0.09) (layer "In9.Cu") (net 514))
  (segment (start 246.101999 114.118001) (end 246.309867 114.118001) (width 0.1) (layer "In9.Cu") (net 514))
  (segment (start 234.512134 98.05) (end 198.862134 98.05) (width 0.1) (layer "In9.Cu") (net 514))
  (segment (start 196.592134 96.31) (end 195.331835 95.049701) (width 0.1) (layer "In9.Cu") (net 514))
  (segment (start 193.133578 95.46) (end 193.498003 95.095575) (width 0.09) (layer "In9.Cu") (net 514))
  (segment (start 198.862134 98.05) (end 197.122134 96.31) (width 0.1) (layer "In9.Cu") (net 514))
  (segment (start 244.112134 114.4) (end 244.018567 114.306433) (width 0.1) (layer "In9.Cu") (net 514))
  (segment (start 188.213551 96.465027) (end 189.218578 95.46) (width 0.09) (layer "In9.Cu") (net 514))
  (segment (start 246.309867 114.118001) (end 246.57 114.378134) (width 0.1) (layer "In9.Cu") (net 514))
  (segment (start 193.849059 95.051641) (end 193.850999 95.049701) (width 0.09) (layer "In9.Cu") (net 514))
  (segment (start 193.498003 95.095575) (end 193.742993 95.095575) (width 0.09) (layer "In9.Cu") (net 514))
  (segment (start 242.65 111.187866) (end 241.15 109.687866) (width 0.1) (layer "In9.Cu") (net 514))
  (segment (start 181.983551 96.465027) (end 182.378578 96.07) (width 0.09) (layer "In9.Cu") (net 514))
  (segment (start 243.594302 113.882168) (end 242.65 112.937866) (width 0.1) (layer "In9.Cu") (net 514))
  (segment (start 244.018567 114.0943) (end 244.052318 114.060548) (width 0.1) (layer "In9.Cu") (net 514))
  (segment (start 239.65 103.187866) (end 234.512134 98.05) (width 0.1) (layer "In9.Cu") (net 514))
  (segment (start 241.15 108.187866) (end 239.65 106.687866) (width 0.1) (layer "In9.Cu") (net 514))
  (segment (start 243.594301 113.882167) (end 243.594302 113.882168) (width 0.1) (layer "In9.Cu") (net 514))
  (arc (start 243.806433 113.882167) (mid 243.700367 113.926101) (end 243.594301 113.882167) (width 0.1) (layer "In9.Cu") (net 514))
  (arc (start 193.742993 95.095575) (mid 193.800396 95.084157) (end 193.849059 95.051641) (width 0.09) (layer "In9.Cu") (net 514))
  (arc (start 244.052318 113.848416) (mid 243.946252 113.804481) (end 243.840185 113.848415) (width 0.1) (layer "In9.Cu") (net 514))
  (arc (start 244.052318 114.060548) (mid 244.096252 113.954482) (end 244.052318 113.848416) (width 0.1) (layer "In9.Cu") (net 514))
  (arc (start 244.018567 114.306433) (mid 243.974632 114.200367) (end 244.018566 114.0943) (width 0.1) (layer "In9.Cu") (net 514))
  (segment (start 246.555 114.19) (end 246.555 114.605) (width 0.1) (layer "B.Cu") (net 514))
  (segment (start 245.92 114.3) (end 246.101999 114.118001) (width 0.1) (layer "B.Cu") (net 514))
  (segment (start 246.101999 114.118001) (end 246.483001 114.118001) (width 0.1) (layer "B.Cu") (net 514))
  (segment (start 246.483001 114.118001) (end 246.555 114.19) (width 0.1) (layer "B.Cu") (net 514))
  (segment (start 182.136328 94.560008) (end 181.636328 95.060008) (width 0.1) (layer "F.Cu") (net 515))
  (via blind (at 181.636328 95.060008) (size 0.5) (drill 0.2) (layers "F.Cu" "In5.Cu") (net 515))
  (via (at 248.46 87.63) (size 0.5) (drill 0.2) (layers "F.Cu" "B.Cu") (net 515))
  (segment (start 239.512134 92.15) (end 204.562134 92.15) (width 0.1) (layer "In5.Cu") (net 515))
  (segment (start 244.662134 88.45) (end 243.712134 89.4) (width 0.1) (layer "In5.Cu") (net 515))
  (segment (start 182.22 94.792242) (end 182.22 95.341422) (width 0.09) (layer "In5.Cu") (net 515))
  (segment (start 242.262134 89.4) (end 239.512134 92.15) (width 0.1) (layer "In5.Cu") (net 515))
  (segment (start 181.62632 95.05) (end 181.3 95.05) (width 0.09) (layer "In5.Cu") (net 515))
  (segment (start 186.836607 96.518028) (end 187.868578 97.55) (width 0.09) (layer "In5.Cu") (net 515))
  (segment (start 189.42 97.2) (end 189.42 96.85) (width 0.09) (layer "In5.Cu") (net 515))
  (segment (start 198.712132 98) (end 194.537866 98) (width 0.1) (layer "In5.Cu") (net 515))
  (segment (start 182.087758 94.66) (end 182.22 94.792242) (width 0.09) (layer "In5.Cu") (net 515))
  (segment (start 181.401422 94.66) (end 182.087758 94.66) (width 0.09) (layer "In5.Cu") (net 515))
  (segment (start 185.479501 95.269501) (end 185.479501 95.369501) (width 0.09) (layer "In5.Cu") (net 515))
  (segment (start 189.72 96.85) (end 189.72 97.2) (width 0.09) (layer "In5.Cu") (net 515))
  (segment (start 187.868578 97.55) (end 188.02 97.55) (width 0.09) (layer "In5.Cu") (net 515))
  (segment (start 182.548079 95.669501) (end 182.700499 95.669501) (width 0.09) (layer "In5.Cu") (net 515))
  (segment (start 184.279501 95.169501) (end 184.379501 95.169501) (width 0.09) (layer "In5.Cu") (net 515))
  (segment (start 188.67 95.4) (end 188.67 97.2) (width 0.09) (layer "In5.Cu") (net 515))
  (segment (start 248.278001 87.448001) (end 248.064133 87.448001) (width 0.1) (layer "In5.Cu") (net 515))
  (segment (start 190.07 97.55) (end 190.198535 97.55) (width 0.09) (layer "In5.Cu") (net 515))
  (segment (start 183.350499 95.069501) (end 183.350499 95.319501) (width 0.09) (layer "In5.Cu") (net 515))
  (segment (start 183.351 95.069) (end 183.350499 95.069501) (width 0.09) (layer "In5.Cu") (net 515))
  (segment (start 191.262134 96.56) (end 190.802134 97.02) (width 0.1) (layer "In5.Cu") (net 515))
  (segment (start 188.37 97.2) (end 188.37 95.4) (width 0.09) (layer "In5.Cu") (net 515))
  (segment (start 187.287661 95.501287) (end 186.836607 95.952342) (width 0.09) (layer "In5.Cu") (net 515))
  (segment (start 245.462134 88.45) (end 244.662134 88.45) (width 0.1) (layer "In5.Cu") (net 515))
  (segment (start 190.769956 97.02) (end 190.802134 97.02) (width 0.09) (layer "In5.Cu") (net 515))
  (segment (start 243.712134 89.4) (end 242.262134 89.4) (width 0.1) (layer "In5.Cu") (net 515))
  (segment (start 185.179501 95.369501) (end 185.179501 95.269501) (width 0.09) (layer "In5.Cu") (net 515))
  (segment (start 183.050499 95.319501) (end 183.050499 95.068501) (width 0.09) (layer "In5.Cu") (net 515))
  (segment (start 185.779501 95.669501) (end 185.988079 95.669501) (width 0.09) (layer "In5.Cu") (net 515))
  (segment (start 181.3 95.05) (end 181.24 94.99) (width 0.09) (layer "In5.Cu") (net 515))
  (segment (start 183.050499 95.068501) (end 183.051 95.068) (width 0.09) (layer "In5.Cu") (net 515))
  (segment (start 186.553766 95.669501) (end 186.553764 95.6695) (width 0.09) (layer "In5.Cu") (net 515))
  (segment (start 181.636328 95.060008) (end 181.62632 95.05) (width 0.09) (layer "In5.Cu") (net 515))
  (segment (start 248.46 87.63) (end 248.278001 87.448001) (width 0.1) (layer "In5.Cu") (net 515))
  (segment (start 194.537866 98) (end 193.097866 96.56) (width 0.1) (layer "In5.Cu") (net 515))
  (segment (start 184.479501 95.269501) (end 184.479501 95.369501) (width 0.09) (layer "In5.Cu") (net 515))
  (segment (start 193.097866 96.56) (end 191.262134 96.56) (width 0.1) (layer "In5.Cu") (net 515))
  (segment (start 181.24 94.99) (end 181.24 94.821422) (width 0.09) (layer "In5.Cu") (net 515))
  (segment (start 183.051 95.068) (end 183.051 94.914998) (width 0.09) (layer "In5.Cu") (net 515))
  (segment (start 247.462134 88.05) (end 245.862134 88.05) (width 0.1) (layer "In5.Cu") (net 515))
  (segment (start 190.198535 97.55) (end 190.699246 97.049289) (width 0.09) (layer "In5.Cu") (net 515))
  (segment (start 185.988079 95.669501) (end 185.988078 95.669499) (width 0.09) (layer "In5.Cu") (net 515))
  (segment (start 182.22 95.341422) (end 182.548079 95.669501) (width 0.09) (layer "In5.Cu") (net 515))
  (segment (start 185.279501 95.169501) (end 185.379501 95.169501) (width 0.09) (layer "In5.Cu") (net 515))
  (segment (start 187.287662 95.218445) (end 187.287662 95.218444) (width 0.09) (layer "In5.Cu") (net 515))
  (segment (start 181.24 94.821422) (end 181.401422 94.66) (width 0.09) (layer "In5.Cu") (net 515))
  (segment (start 183.351 94.914998) (end 183.351 95.069) (width 0.09) (layer "In5.Cu") (net 515))
  (segment (start 204.562134 92.15) (end 198.712132 98) (width 0.1) (layer "In5.Cu") (net 515))
  (segment (start 184.179501 95.369501) (end 184.179501 95.269501) (width 0.09) (layer "In5.Cu") (net 515))
  (segment (start 245.862134 88.05) (end 245.462134 88.45) (width 0.1) (layer "In5.Cu") (net 515))
  (segment (start 183.700499 95.669501) (end 183.879501 95.669501) (width 0.09) (layer "In5.Cu") (net 515))
  (segment (start 186.553764 95.6695) (end 187.00482 95.218445) (width 0.09) (layer "In5.Cu") (net 515))
  (segment (start 189.02 97.55) (end 189.07 97.55) (width 0.09) (layer "In5.Cu") (net 515))
  (segment (start 184.779501 95.669501) (end 184.879501 95.669501) (width 0.09) (layer "In5.Cu") (net 515))
  (segment (start 248.064133 87.448001) (end 247.462134 88.05) (width 0.1) (layer "In5.Cu") (net 515))
  (arc (start 184.379501 95.169501) (mid 184.450212 95.19879) (end 184.479501 95.269501) (width 0.09) (layer "In5.Cu") (net 515))
  (arc (start 184.179501 95.269501) (mid 184.20879 95.19879) (end 184.279501 95.169501) (width 0.09) (layer "In5.Cu") (net 515))
  (arc (start 189.57 96.7) (mid 189.676066 96.743934) (end 189.72 96.85) (width 0.09) (layer "In5.Cu") (net 515))
  (arc (start 187.287662 95.218444) (mid 187.34624 95.359866) (end 187.287661 95.501287) (width 0.09) (layer "In5.Cu") (net 515))
  (arc (start 188.37 95.4) (mid 188.413934 95.293934) (end 188.52 95.25) (width 0.09) (layer "In5.Cu") (net 515))
  (arc (start 184.879501 95.669501) (mid 185.091633 95.581633) (end 185.179501 95.369501) (width 0.09) (layer "In5.Cu") (net 515))
  (arc (start 188.02 97.55) (mid 188.267487 97.447487) (end 188.37 97.2) (width 0.09) (layer "In5.Cu") (net 515))
  (arc (start 183.879501 95.669501) (mid 184.091633 95.581633) (end 184.179501 95.369501) (width 0.09) (layer "In5.Cu") (net 515))
  (arc (start 189.42 96.85) (mid 189.463934 96.743934) (end 189.57 96.7) (width 0.09) (layer "In5.Cu") (net 515))
  (arc (start 183.051 94.914998) (mid 183.094934 94.808932) (end 183.201 94.764998) (width 0.09) (layer "In5.Cu") (net 515))
  (arc (start 185.988078 95.669499) (mid 186.270923 95.786658) (end 186.553766 95.669501) (width 0.09) (layer "In5.Cu") (net 515))
  (arc (start 185.379501 95.169501) (mid 185.450212 95.19879) (end 185.479501 95.269501) (width 0.09) (layer "In5.Cu") (net 515))
  (arc (start 183.201 94.764998) (mid 183.307066 94.808932) (end 183.351 94.914998) (width 0.09) (layer "In5.Cu") (net 515))
  (arc (start 183.350499 95.319501) (mid 183.453012 95.566988) (end 183.700499 95.669501) (width 0.09) (layer "In5.Cu") (net 515))
  (arc (start 182.700499 95.669501) (mid 182.947986 95.566988) (end 183.050499 95.319501) (width 0.09) (layer "In5.Cu") (net 515))
  (arc (start 185.479501 95.369501) (mid 185.567369 95.581633) (end 185.779501 95.669501) (width 0.09) (layer "In5.Cu") (net 515))
  (arc (start 189.07 97.55) (mid 189.317487 97.447487) (end 189.42 97.2) (width 0.09) (layer "In5.Cu") (net 515))
  (arc (start 190.699246 97.049289) (mid 190.731688 97.027612) (end 190.769956 97.02) (width 0.09) (layer "In5.Cu") (net 515))
  (arc (start 184.479501 95.369501) (mid 184.567369 95.581633) (end 184.779501 95.669501) (width 0.09) (layer "In5.Cu") (net 515))
  (arc (start 188.52 95.25) (mid 188.626066 95.293934) (end 188.67 95.4) (width 0.09) (layer "In5.Cu") (net 515))
  (arc (start 189.72 97.2) (mid 189.822513 97.447487) (end 190.07 97.55) (width 0.09) (layer "In5.Cu") (net 515))
  (arc (start 185.179501 95.269501) (mid 185.20879 95.19879) (end 185.279501 95.169501) (width 0.09) (layer "In5.Cu") (net 515))
  (arc (start 188.67 97.2) (mid 188.772513 97.447487) (end 189.02 97.55) (width 0.09) (layer "In5.Cu") (net 515))
  (arc (start 186.836607 95.952342) (mid 186.71945 96.235185) (end 186.836607 96.518028) (width 0.09) (layer "In5.Cu") (net 515))
  (arc (start 187.00482 95.218445) (mid 187.14624 95.159866) (end 187.287662 95.218445) (width 0.09) (layer "In5.Cu") (net 515))
  (segment (start 248.46 87.63) (end 248.641999 87.448001) (width 0.1) (layer "B.Cu") (net 515))
  (segment (start 248.641999 87.448001) (end 249.023001 87.448001) (width 0.1) (layer "B.Cu") (net 515))
  (segment (start 249.095 87.52) (end 249.095 87.935) (width 0.1) (layer "B.Cu") (net 515))
  (segment (start 249.023001 87.448001) (end 249.095 87.52) (width 0.1) (layer "B.Cu") (net 515))
  (segment (start 181.136328 94.560008) (end 180.636328 95.060008) (width 0.1) (layer "F.Cu") (net 516))
  (via (at 248.46 86.966) (size 0.5) (drill 0.2) (layers "F.Cu" "B.Cu") (net 516))
  (via blind (at 180.636328 95.060008) (size 0.5) (drill 0.2) (layers "F.Cu" "In5.Cu") (net 516))
  (segment (start 182.850499 95.319501) (end 182.850499 95.068501) (width 0.09) (layer "In5.Cu") (net 516))
  (segment (start 180.646336 95.05) (end 180.97 95.05) (width 0.09) (layer "In5.Cu") (net 516))
  (segment (start 180.636328 95.060008) (end 180.646336 95.05) (width 0.09) (layer "In5.Cu") (net 516))
  (segment (start 182.170602 94.46) (end 182.42 94.709398) (width 0.09) (layer "In5.Cu") (net 516))
  (segment (start 187.701768 96.802072) (end 187.701769 96.802073) (width 0.09) (layer "In5.Cu") (net 516))
  (segment (start 182.42 94.709398) (end 182.42 95.258578) (width 0.09) (layer "In5.Cu") (net 516))
  (segment (start 190.557866 96.866404) (end 190.557866 96.84) (width 0.09) (layer "In5.Cu") (net 516))
  (segment (start 187.701768 96.943494) (end 187.70177 96.943495) (width 0.09) (layer "In5.Cu") (net 516))
  (segment (start 187.951422 97.35) (end 188.02 97.35) (width 0.09) (layer "In5.Cu") (net 516))
  (segment (start 193.222134 96.26) (end 191.137866 96.26) (width 0.1) (layer "In5.Cu") (net 516))
  (segment (start 191.137866 96.26) (end 190.557866 96.84) (width 0.1) (layer "In5.Cu") (net 516))
  (segment (start 184.979501 95.369501) (end 184.979501 95.269501) (width 0.09) (layer "In5.Cu") (net 516))
  (segment (start 198.587866 97.7) (end 194.662134 97.7) (width 0.1) (layer "In5.Cu") (net 516))
  (segment (start 183.550499 95.069501) (end 183.550499 95.319501) (width 0.09) (layer "In5.Cu") (net 516))
  (segment (start 182.850499 95.068501) (end 182.851 95.068) (width 0.09) (layer "In5.Cu") (net 516))
  (segment (start 186.070923 95.469501) (end 186.129499 95.528078) (width 0.09) (layer "In5.Cu") (net 516))
  (segment (start 183.700499 95.469501) (end 183.879501 95.469501) (width 0.09) (layer "In5.Cu") (net 516))
  (segment (start 181.04 94.98) (end 181.04 94.738578) (width 0.09) (layer "In5.Cu") (net 516))
  (segment (start 189.22 97.2) (end 189.22 96.85) (width 0.09) (layer "In5.Cu") (net 516))
  (segment (start 184.279501 94.969501) (end 184.379501 94.969501) (width 0.09) (layer "In5.Cu") (net 516))
  (segment (start 185.779501 95.469501) (end 186.070923 95.469501) (width 0.09) (layer "In5.Cu") (net 516))
  (segment (start 189.02 97.35) (end 189.07 97.35) (width 0.09) (layer "In5.Cu") (net 516))
  (segment (start 187.429084 95.642708) (end 186.978029 96.093764) (width 0.09) (layer "In5.Cu") (net 516))
  (segment (start 187.70177 96.943495) (end 187.694053 96.951209) (width 0.09) (layer "In5.Cu") (net 516))
  (segment (start 183.979501 95.369501) (end 183.979501 95.269501) (width 0.09) (layer "In5.Cu") (net 516))
  (segment (start 189.92 96.85) (end 189.92 97.2) (width 0.09) (layer "In5.Cu") (net 516))
  (segment (start 183.551 95.069) (end 183.550499 95.069501) (width 0.09) (layer "In5.Cu") (net 516))
  (segment (start 187.429084 95.642709) (end 187.429084 95.642708) (width 0.09) (layer "In5.Cu") (net 516))
  (segment (start 245.337866 88.15) (end 244.537866 88.15) (width 0.1) (layer "In5.Cu") (net 516))
  (segment (start 185.279501 94.969501) (end 185.379501 94.969501) (width 0.09) (layer "In5.Cu") (net 516))
  (segment (start 204.437866 91.85) (end 198.587866 97.7) (width 0.1) (layer "In5.Cu") (net 516))
  (segment (start 247.337866 87.75) (end 245.737866 87.75) (width 0.1) (layer "In5.Cu") (net 516))
  (segment (start 186.412345 95.52808) (end 186.412343 95.528079) (width 0.09) (layer "In5.Cu") (net 516))
  (segment (start 185.679501 95.269501) (end 185.679501 95.369501) (width 0.09) (layer "In5.Cu") (net 516))
  (segment (start 242.137866 89.1) (end 239.387866 91.85) (width 0.1) (layer "In5.Cu") (net 516))
  (segment (start 243.587866 89.1) (end 242.137866 89.1) (width 0.1) (layer "In5.Cu") (net 516))
  (segment (start 248.46 86.966) (end 248.278001 87.147999) (width 0.1) (layer "In5.Cu") (net 516))
  (segment (start 186.978029 96.376606) (end 187.411211 96.809789) (width 0.09) (layer "In5.Cu") (net 516))
  (segment (start 190.115691 97.35) (end 190.528577 96.937114) (width 0.09) (layer "In5.Cu") (net 516))
  (segment (start 180.97 95.05) (end 181.04 94.98) (width 0.09) (layer "In5.Cu") (net 516))
  (segment (start 245.737866 87.75) (end 245.337866 88.15) (width 0.1) (layer "In5.Cu") (net 516))
  (segment (start 182.851 95.068) (end 182.851 94.914998) (width 0.09) (layer "In5.Cu") (net 516))
  (segment (start 184.679501 95.269501) (end 184.679501 95.369501) (width 0.09) (layer "In5.Cu") (net 516))
  (segment (start 183.551 94.914998) (end 183.551 95.069) (width 0.09) (layer "In5.Cu") (net 516))
  (segment (start 181.318578 94.46) (end 182.170602 94.46) (width 0.09) (layer "In5.Cu") (net 516))
  (segment (start 239.387866 91.85) (end 204.437866 91.85) (width 0.1) (layer "In5.Cu") (net 516))
  (segment (start 186.412343 95.528079) (end 186.863399 95.077024) (width 0.09) (layer "In5.Cu") (net 516))
  (segment (start 248.278001 87.147999) (end 247.939867 87.147999) (width 0.1) (layer "In5.Cu") (net 516))
  (segment (start 182.630923 95.469501) (end 182.700499 95.469501) (width 0.09) (layer "In5.Cu") (net 516))
  (segment (start 244.537866 88.15) (end 243.587866 89.1) (width 0.1) (layer "In5.Cu") (net 516))
  (segment (start 190.07 97.35) (end 190.115691 97.35) (width 0.09) (layer "In5.Cu") (net 516))
  (segment (start 188.17 97.2) (end 188.17 95.4) (width 0.09) (layer "In5.Cu") (net 516))
  (segment (start 187.552633 96.80979) (end 187.560347 96.802073) (width 0.09) (layer "In5.Cu") (net 516))
  (segment (start 181.04 94.738578) (end 181.318578 94.46) (width 0.09) (layer "In5.Cu") (net 516))
  (segment (start 187.694053 97.092631) (end 187.951422 97.35) (width 0.09) (layer "In5.Cu") (net 516))
  (segment (start 187.552632 96.809788) (end 187.552633 96.80979) (width 0.09) (layer "In5.Cu") (net 516))
  (segment (start 187.694052 97.09263) (end 187.694053 97.092631) (width 0.09) (layer "In5.Cu") (net 516))
  (segment (start 194.662134 97.7) (end 193.222134 96.26) (width 0.1) (layer "In5.Cu") (net 516))
  (segment (start 184.779501 95.469501) (end 184.879501 95.469501) (width 0.09) (layer "In5.Cu") (net 516))
  (segment (start 247.939867 87.147999) (end 247.337866 87.75) (width 0.1) (layer "In5.Cu") (net 516))
  (segment (start 182.42 95.258578) (end 182.630923 95.469501) (width 0.09) (layer "In5.Cu") (net 516))
  (segment (start 188.87 95.4) (end 188.87 97.2) (width 0.09) (layer "In5.Cu") (net 516))
  (arc (start 190.528577 96.937114) (mid 190.550254 96.904672) (end 190.557866 96.866404) (width 0.09) (layer "In5.Cu") (net 516))
  (arc (start 189.57 96.5) (mid 189.817487 96.602513) (end 189.92 96.85) (width 0.09) (layer "In5.Cu") (net 516))
  (arc (start 183.979501 95.269501) (mid 184.067369 95.057369) (end 184.279501 94.969501) (width 0.09) (layer "In5.Cu") (net 516))
  (arc (start 185.379501 94.969501) (mid 185.591633 95.057369) (end 185.679501 95.269501) (width 0.09) (layer "In5.Cu") (net 516))
  (arc (start 184.679501 95.369501) (mid 184.70879 95.440212) (end 184.779501 95.469501) (width 0.09) (layer "In5.Cu") (net 516))
  (arc (start 189.07 97.35) (mid 189.176066 97.306066) (end 189.22 97.2) (width 0.09) (layer "In5.Cu") (net 516))
  (arc (start 188.87 97.2) (mid 188.913934 97.306066) (end 189.02 97.35) (width 0.09) (layer "In5.Cu") (net 516))
  (arc (start 186.863399 95.077024) (mid 187.146242 94.959867) (end 187.429085 95.077024) (width 0.09) (layer "In5.Cu") (net 516))
  (arc (start 184.379501 94.969501) (mid 184.591633 95.057369) (end 184.679501 95.269501) (width 0.09) (layer "In5.Cu") (net 516))
  (arc (start 185.679501 95.369501) (mid 185.70879 95.440212) (end 185.779501 95.469501) (width 0.09) (layer "In5.Cu") (net 516))
  (arc (start 187.701769 96.802073) (mid 187.731058 96.872784) (end 187.701768 96.943494) (width 0.09) (layer "In5.Cu") (net 516))
  (arc (start 188.02 97.35) (mid 188.126066 97.306066) (end 188.17 97.2) (width 0.09) (layer "In5.Cu") (net 516))
  (arc (start 183.879501 95.469501) (mid 183.950212 95.440212) (end 183.979501 95.369501) (width 0.09) (layer "In5.Cu") (net 516))
  (arc (start 189.22 96.85) (mid 189.322513 96.602513) (end 189.57 96.5) (width 0.09) (layer "In5.Cu") (net 516))
  (arc (start 188.52 95.05) (mid 188.767487 95.152513) (end 188.87 95.4) (width 0.09) (layer "In5.Cu") (net 516))
  (arc (start 184.979501 95.269501) (mid 185.067369 95.057369) (end 185.279501 94.969501) (width 0.09) (layer "In5.Cu") (net 516))
  (arc (start 186.978029 96.093764) (mid 186.91945 96.235184) (end 186.978029 96.376606) (width 0.09) (layer "In5.Cu") (net 516))
  (arc (start 188.17 95.4) (mid 188.272513 95.152513) (end 188.52 95.05) (width 0.09) (layer "In5.Cu") (net 516))
  (arc (start 182.851 94.914998) (mid 182.953513 94.667511) (end 183.201 94.564998) (width 0.09) (layer "In5.Cu") (net 516))
  (arc (start 183.550499 95.319501) (mid 183.594433 95.425567) (end 183.700499 95.469501) (width 0.09) (layer "In5.Cu") (net 516))
  (arc (start 189.92 97.2) (mid 189.963934 97.306066) (end 190.07 97.35) (width 0.09) (layer "In5.Cu") (net 516))
  (arc (start 187.411211 96.809789) (mid 187.481922 96.839078) (end 187.552632 96.809788) (width 0.09) (layer "In5.Cu") (net 516))
  (arc (start 184.879501 95.469501) (mid 184.950212 95.440212) (end 184.979501 95.369501) (width 0.09) (layer "In5.Cu") (net 516))
  (arc (start 183.201 94.564998) (mid 183.448487 94.667511) (end 183.551 94.914998) (width 0.09) (layer "In5.Cu") (net 516))
  (arc (start 182.700499 95.469501) (mid 182.806565 95.425567) (end 182.850499 95.319501) (width 0.09) (layer "In5.Cu") (net 516))
  (arc (start 187.560347 96.802073) (mid 187.631057 96.772783) (end 187.701768 96.802072) (width 0.09) (layer "In5.Cu") (net 516))
  (arc (start 186.129499 95.528078) (mid 186.270922 95.586658) (end 186.412345 95.52808) (width 0.09) (layer "In5.Cu") (net 516))
  (arc (start 187.694053 96.951209) (mid 187.664763 97.021919) (end 187.694052 97.09263) (width 0.09) (layer "In5.Cu") (net 516))
  (arc (start 187.429085 95.077024) (mid 187.546242 95.359867) (end 187.429084 95.642709) (width 0.09) (layer "In5.Cu") (net 516))
  (segment (start 248.641999 87.147999) (end 248.992001 87.147999) (width 0.1) (layer "B.Cu") (net 516))
  (segment (start 248.992001 87.147999) (end 249.095 87.045) (width 0.1) (layer "B.Cu") (net 516))
  (segment (start 248.46 86.966) (end 248.641999 87.147999) (width 0.1) (layer "B.Cu") (net 516))
  (segment (start 249.095 87.045) (end 249.095 86.665) (width 0.1) (layer "B.Cu") (net 516))
  (segment (start 179.136328 94.560008) (end 178.636328 95.060008) (width 0.1) (layer "F.Cu") (net 517))
  (via (at 178.636328 95.060008) (size 0.5) (drill 0.2) (layers "F.Cu" "B.Cu") (net 517))
  (via (at 244.65 93.98) (size 0.5) (drill 0.2) (layers "F.Cu" "B.Cu") (net 517))
  (segment (start 193.063578 99.422) (end 191.163422 99.422) (width 0.09) (layer "In7.Cu") (net 517))
  (segment (start 190.332602 98.59118) (end 190.141422 98.4) (width 0.09) (layer "In7.Cu") (net 517))
  (segment (start 198.101871 99.085) (end 197.583 99.085) (width 0.09) (layer "In7.Cu") (net 517))
  (segment (start 190.141422 98.4) (end 188.958578 98.4) (width 0.09) (layer "In7.Cu") (net 517))
  (segment (start 194.458 98.36) (end 194.458 98.91) (width 0.09) (layer "In7.Cu") (net 517))
  (segment (start 190.332602 98.591179) (end 190.332602 98.59118) (width 0.09) (layer "In7.Cu") (net 517))
  (segment (start 196.658 98.71) (end 196.658 99.56) (width 0.09) (layer "In7.Cu") (net 517))
  (segment (start 239.977866 95.56) (end 203.484866 95.56) (width 0.1) (layer "In7.Cu") (net 517))
  (segment (start 190.261892 99.156866) (end 190.332601 99.086154) (width 0.09) (layer "In7.Cu") (net 517))
  (segment (start 191.163422 99.422) (end 191.039709 99.298288) (width 0.09) (layer "In7.Cu") (net 517))
  (segment (start 200.004138 99.040728) (end 198.187564 99.040728) (width 0.1) (layer "In7.Cu") (net 517))
  (segment (start 178.360449 95.465027) (end 178.25 95.354578) (width 0.09) (layer "In7.Cu") (net 517))
  (segment (start 178.25 95.166) (end 178.353992 95.062008) (width 0.09) (layer "In7.Cu") (net 517))
  (segment (start 245.040064 92.51) (end 243.027866 92.51) (width 0.1) (layer "In7.Cu") (net 517))
  (segment (start 196.308 99.56) (end 196.308 98.71) (width 0.09) (layer "In7.Cu") (net 517))
  (segment (start 190.26189 99.156865) (end 190.261892 99.156866) (width 0.09) (layer "In7.Cu") (net 517))
  (segment (start 178.25 95.354578) (end 178.25 95.166) (width 0.09) (layer "In7.Cu") (net 517))
  (segment (start 243.027866 92.51) (end 239.977866 95.56) (width 0.1) (layer "In7.Cu") (net 517))
  (segment (start 244.811999 93.798001) (end 245.170133 93.798001) (width 0.1) (layer "In7.Cu") (net 517))
  (segment (start 178.353992 95.062008) (end 178.353992 95.060008) (width 0.09) (layer "In7.Cu") (net 517))
  (segment (start 245.52 92.989936) (end 245.040064 92.51) (width 0.1) (layer "In7.Cu") (net 517))
  (segment (start 244.65 93.96) (end 244.811999 93.798001) (width 0.1) (layer "In7.Cu") (net 517))
  (segment (start 190.544735 99.298288) (end 190.544735 99.298289) (width 0.09) (layer "In7.Cu") (net 517))
  (segment (start 195.208 99.56) (end 195.208 98.36) (width 0.09) (layer "In7.Cu") (net 517))
  (segment (start 194.283 99.085) (end 193.400578 99.085) (width 0.09) (layer "In7.Cu") (net 517))
  (segment (start 245.170133 93.798001) (end 245.52 93.448134) (width 0.1) (layer "In7.Cu") (net 517))
  (segment (start 180.606449 95.465027) (end 178.360449 95.465027) (width 0.09) (layer "In7.Cu") (net 517))
  (segment (start 193.400578 99.085) (end 193.063578 99.422) (width 0.09) (layer "In7.Cu") (net 517))
  (segment (start 198.187564 99.040728) (end 198.172582 99.05571) (width 0.09) (layer "In7.Cu") (net 517))
  (segment (start 245.52 93.448134) (end 245.52 92.989936) (width 0.1) (layer "In7.Cu") (net 517))
  (segment (start 188.758578 98.6) (end 186.041422 98.6) (width 0.09) (layer "In7.Cu") (net 517))
  (segment (start 178.353992 95.060008) (end 178.636328 95.060008) (width 0.09) (layer "In7.Cu") (net 517))
  (segment (start 186.041422 98.6) (end 182.906439 95.465017) (width 0.09) (layer "In7.Cu") (net 517))
  (segment (start 190.544735 99.298289) (end 190.474023 99.368998) (width 0.09) (layer "In7.Cu") (net 517))
  (segment (start 195.558 98.71) (end 195.558 99.56) (width 0.09) (layer "In7.Cu") (net 517))
  (segment (start 180.606459 95.465017) (end 180.606449 95.465027) (width 0.09) (layer "In7.Cu") (net 517))
  (segment (start 197.408 98.91) (end 197.408 98.71) (width 0.09) (layer "In7.Cu") (net 517))
  (segment (start 188.958578 98.4) (end 188.758578 98.6) (width 0.09) (layer "In7.Cu") (net 517))
  (segment (start 182.906439 95.465017) (end 180.606459 95.465017) (width 0.09) (layer "In7.Cu") (net 517))
  (segment (start 203.484866 95.56) (end 200.004138 99.040728) (width 0.1) (layer "In7.Cu") (net 517))
  (segment (start 244.65 93.98) (end 244.65 93.96) (width 0.1) (layer "In7.Cu") (net 517))
  (arc (start 195.558 99.56) (mid 195.506744 99.683744) (end 195.383 99.735) (width 0.09) (layer "In7.Cu") (net 517))
  (arc (start 195.208 98.36) (mid 195.098165 98.094835) (end 194.833 97.985) (width 0.09) (layer "In7.Cu") (net 517))
  (arc (start 197.033 98.335) (mid 196.767835 98.444835) (end 196.658 98.71) (width 0.09) (layer "In7.Cu") (net 517))
  (arc (start 198.172582 99.05571) (mid 198.14014 99.077388) (end 198.101871 99.085) (width 0.09) (layer "In7.Cu") (net 517))
  (arc (start 195.383 99.735) (mid 195.259256 99.683744) (end 195.208 99.56) (width 0.09) (layer "In7.Cu") (net 517))
  (arc (start 194.833 97.985) (mid 194.567835 98.094835) (end 194.458 98.36) (width 0.09) (layer "In7.Cu") (net 517))
  (arc (start 195.933 98.335) (mid 195.667835 98.444835) (end 195.558 98.71) (width 0.09) (layer "In7.Cu") (net 517))
  (arc (start 191.039709 99.298288) (mid 190.792223 99.195777) (end 190.544735 99.298288) (width 0.09) (layer "In7.Cu") (net 517))
  (arc (start 190.474023 99.368998) (mid 190.367957 99.412932) (end 190.261891 99.368998) (width 0.09) (layer "In7.Cu") (net 517))
  (arc (start 190.261891 99.368998) (mid 190.217957 99.262933) (end 190.26189 99.156865) (width 0.09) (layer "In7.Cu") (net 517))
  (arc (start 190.332601 99.086154) (mid 190.435114 98.838667) (end 190.332602 98.591179) (width 0.09) (layer "In7.Cu") (net 517))
  (arc (start 196.308 98.71) (mid 196.198165 98.444835) (end 195.933 98.335) (width 0.09) (layer "In7.Cu") (net 517))
  (arc (start 196.483 99.735) (mid 196.359256 99.683744) (end 196.308 99.56) (width 0.09) (layer "In7.Cu") (net 517))
  (arc (start 194.458 98.91) (mid 194.406744 99.033744) (end 194.283 99.085) (width 0.09) (layer "In7.Cu") (net 517))
  (arc (start 197.583 99.085) (mid 197.459256 99.033744) (end 197.408 98.91) (width 0.09) (layer "In7.Cu") (net 517))
  (arc (start 196.658 99.56) (mid 196.606744 99.683744) (end 196.483 99.735) (width 0.09) (layer "In7.Cu") (net 517))
  (arc (start 197.408 98.71) (mid 197.298165 98.444835) (end 197.033 98.335) (width 0.09) (layer "In7.Cu") (net 517))
  (segment (start 244.65 93.98) (end 244.831999 93.798001) (width 0.1) (layer "B.Cu") (net 517))
  (segment (start 245.285 93.87) (end 245.285 94.285) (width 0.1) (layer "B.Cu") (net 517))
  (segment (start 245.213001 93.798001) (end 245.285 93.87) (width 0.1) (layer "B.Cu") (net 517))
  (segment (start 244.831999 93.798001) (end 245.213001 93.798001) (width 0.1) (layer "B.Cu") (net 517))
  (segment (start 178.136328 94.560008) (end 177.636328 95.060008) (width 0.1) (layer "F.Cu") (net 518))
  (via (at 177.636328 95.060008) (size 0.5) (drill 0.2) (layers "F.Cu" "B.Cu") (net 518))
  (via (at 244.65 93.316) (size 0.5) (drill 0.2) (layers "F.Cu" "B.Cu") (net 518))
  (segment (start 179.923586 95.665008) (end 179.873586 95.665008) (width 0.09) (layer "In7.Cu") (net 518))
  (segment (start 193.146422 99.622) (end 191.080578 99.622) (width 0.09) (layer "In7.Cu") (net 518))
  (segment (start 195.008 99.56) (end 195.008 98.36) (width 0.09) (layer "In7.Cu") (net 518))
  (segment (start 196.108 99.56) (end 196.108 98.71) (width 0.09) (layer "In7.Cu") (net 518))
  (segment (start 198.187564 99.340728) (end 200.128406 99.340728) (width 0.1) (layer "In7.Cu") (net 518))
  (segment (start 190.686156 99.439709) (end 190.615446 99.51042) (width 0.09) (layer "In7.Cu") (net 518))
  (segment (start 190.19118 98.732601) (end 190.191181 98.732602) (width 0.09) (layer "In7.Cu") (net 518))
  (segment (start 198.090415 99.285) (end 197.583 99.285) (width 0.09) (layer "In7.Cu") (net 518))
  (segment (start 196.858 98.71) (end 196.858 99.56) (width 0.09) (layer "In7.Cu") (net 518))
  (segment (start 180.848983 95.665017) (end 180.798983 95.665017) (width 0.09) (layer "In7.Cu") (net 518))
  (segment (start 203.609134 95.86) (end 240.102134 95.86) (width 0.1) (layer "In7.Cu") (net 518))
  (segment (start 182.823595 95.665017) (end 181.348983 95.665017) (width 0.09) (layer "In7.Cu") (net 518))
  (segment (start 244.811999 93.497999) (end 244.65 93.336) (width 0.1) (layer "In7.Cu") (net 518))
  (segment (start 245.045867 93.497999) (end 244.811999 93.497999) (width 0.1) (layer "In7.Cu") (net 518))
  (segment (start 243.408 92.96) (end 243.408 93.01) (width 0.1) (layer "In7.Cu") (net 518))
  (segment (start 240.102134 95.86) (end 243.152134 92.81) (width 0.1) (layer "In7.Cu") (net 518))
  (segment (start 190.191181 98.732602) (end 190.058578 98.6) (width 0.09) (layer "In7.Cu") (net 518))
  (segment (start 243.708 93.01) (end 243.708 92.96) (width 0.1) (layer "In7.Cu") (net 518))
  (segment (start 195.758 98.71) (end 195.758 99.56) (width 0.09) (layer "In7.Cu") (net 518))
  (segment (start 244.458 92.81) (end 244.508 92.81) (width 0.1) (layer "In7.Cu") (net 518))
  (segment (start 180.798983 95.665017) (end 180.523595 95.665017) (width 0.09) (layer "In7.Cu") (net 518))
  (segment (start 198.187564 99.340728) (end 198.161126 99.31429) (width 0.09) (layer "In7.Cu") (net 518))
  (segment (start 190.120469 99.015444) (end 190.120471 99.015445) (width 0.09) (layer "In7.Cu") (net 518))
  (segment (start 200.128406 99.340728) (end 203.609134 95.86) (width 0.1) (layer "In7.Cu") (net 518))
  (segment (start 244.915796 92.81) (end 245.22 93.114204) (width 0.1) (layer "In7.Cu") (net 518))
  (segment (start 245.22 93.114204) (end 245.22 93.323866) (width 0.1) (layer "In7.Cu") (net 518))
  (segment (start 193.483422 99.285) (end 193.146422 99.622) (width 0.09) (layer "In7.Cu") (net 518))
  (segment (start 179.873586 95.665008) (end 178.277586 95.665008) (width 0.09) (layer "In7.Cu") (net 518))
  (segment (start 180.523595 95.665017) (end 180.523586 95.665008) (width 0.09) (layer "In7.Cu") (net 518))
  (segment (start 180.073586 95.872357) (end 180.073586 95.815008) (width 0.09) (layer "In7.Cu") (net 518))
  (segment (start 178.277586 95.665008) (end 178.05 95.437422) (width 0.09) (layer "In7.Cu") (net 518))
  (segment (start 180.373586 95.815008) (end 180.373586 95.872357) (width 0.09) (layer "In7.Cu") (net 518))
  (segment (start 245.22 93.323866) (end 245.045867 93.497999) (width 0.1) (layer "In7.Cu") (net 518))
  (segment (start 178.05 95.153) (end 177.957008 95.060008) (width 0.09) (layer "In7.Cu") (net 518))
  (segment (start 243.152134 92.81) (end 243.258 92.81) (width 0.1) (layer "In7.Cu") (net 518))
  (segment (start 194.283 99.285) (end 193.483422 99.285) (width 0.09) (layer "In7.Cu") (net 518))
  (segment (start 191.080578 99.622) (end 190.898288 99.439709) (width 0.09) (layer "In7.Cu") (net 518))
  (segment (start 190.120471 99.510421) (end 190.12047 99.510419) (width 0.09) (layer "In7.Cu") (net 518))
  (segment (start 188.841422 98.8) (end 185.958578 98.8) (width 0.09) (layer "In7.Cu") (net 518))
  (segment (start 185.958578 98.8) (end 182.823595 95.665017) (width 0.09) (layer "In7.Cu") (net 518))
  (segment (start 177.957008 95.060008) (end 177.636328 95.060008) (width 0.09) (layer "In7.Cu") (net 518))
  (segment (start 197.208 98.91) (end 197.208 98.71) (width 0.09) (layer "In7.Cu") (net 518))
  (segment (start 244.508 92.81) (end 244.915796 92.81) (width 0.1) (layer "In7.Cu") (net 518))
  (segment (start 190.058578 98.6) (end 189.041422 98.6) (width 0.09) (layer "In7.Cu") (net 518))
  (segment (start 190.120471 99.015445) (end 190.19118 98.944733) (width 0.09) (layer "In7.Cu") (net 518))
  (segment (start 178.05 95.437422) (end 178.05 95.153) (width 0.09) (layer "In7.Cu") (net 518))
  (segment (start 189.041422 98.6) (end 188.841422 98.8) (width 0.09) (layer "In7.Cu") (net 518))
  (segment (start 194.658 98.36) (end 194.658 98.91) (width 0.09) (layer "In7.Cu") (net 518))
  (segment (start 244.65 93.336) (end 244.65 93.316) (width 0.1) (layer "In7.Cu") (net 518))
  (arc (start 180.973983 95.790017) (mid 180.937371 95.701629) (end 180.848983 95.665017) (width 0.09) (layer "In7.Cu") (net 518))
  (arc (start 243.408 93.01) (mid 243.451934 93.116066) (end 243.558 93.16) (width 0.1) (layer "In7.Cu") (net 518))
  (arc (start 181.223983 95.790017) (mid 181.187371 95.878405) (end 181.098983 95.915017) (width 0.09) (layer "In7.Cu") (net 518))
  (arc (start 180.073586 95.815008) (mid 180.029652 95.708942) (end 179.923586 95.665008) (width 0.09) (layer "In7.Cu") (net 518))
  (arc (start 195.383 99.935) (mid 195.117835 99.825165) (end 195.008 99.56) (width 0.09) (layer "In7.Cu") (net 518))
  (arc (start 195.933 98.535) (mid 195.809256 98.586256) (end 195.758 98.71) (width 0.09) (layer "In7.Cu") (net 518))
  (arc (start 244.008 92.96) (mid 244.051934 93.066066) (end 244.158 93.11) (width 0.1) (layer "In7.Cu") (net 518))
  (arc (start 243.258 92.81) (mid 243.364066 92.853934) (end 243.408 92.96) (width 0.1) (layer "In7.Cu") (net 518))
  (arc (start 181.348983 95.665017) (mid 181.260595 95.701629) (end 181.223983 95.790017) (width 0.09) (layer "In7.Cu") (net 518))
  (arc (start 197.033 98.535) (mid 196.909256 98.586256) (end 196.858 98.71) (width 0.09) (layer "In7.Cu") (net 518))
  (arc (start 190.898288 99.439709) (mid 190.792222 99.395775) (end 190.686156 99.439709) (width 0.09) (layer "In7.Cu") (net 518))
  (arc (start 196.483 99.935) (mid 196.217835 99.825165) (end 196.108 99.56) (width 0.09) (layer "In7.Cu") (net 518))
  (arc (start 244.308 92.96) (mid 244.351934 92.853934) (end 244.458 92.81) (width 0.1) (layer "In7.Cu") (net 518))
  (arc (start 180.223586 96.022357) (mid 180.11752 95.978423) (end 180.073586 95.872357) (width 0.09) (layer "In7.Cu") (net 518))
  (arc (start 243.858 92.81) (mid 243.964066 92.853934) (end 244.008 92.96) (width 0.1) (layer "In7.Cu") (net 518))
  (arc (start 195.758 99.56) (mid 195.648165 99.825165) (end 195.383 99.935) (width 0.09) (layer "In7.Cu") (net 518))
  (arc (start 190.615446 99.51042) (mid 190.367959 99.612933) (end 190.120471 99.510421) (width 0.09) (layer "In7.Cu") (net 518))
  (arc (start 190.12047 99.510419) (mid 190.017957 99.262932) (end 190.120469 99.015444) (width 0.09) (layer "In7.Cu") (net 518))
  (arc (start 243.708 92.96) (mid 243.751934 92.853934) (end 243.858 92.81) (width 0.1) (layer "In7.Cu") (net 518))
  (arc (start 180.373586 95.872357) (mid 180.329652 95.978423) (end 180.223586 96.022357) (width 0.09) (layer "In7.Cu") (net 518))
  (arc (start 197.208 98.71) (mid 197.156744 98.586256) (end 197.033 98.535) (width 0.09) (layer "In7.Cu") (net 518))
  (arc (start 181.098983 95.915017) (mid 181.010595 95.878405) (end 180.973983 95.790017) (width 0.09) (layer "In7.Cu") (net 518))
  (arc (start 196.858 99.56) (mid 196.748165 99.825165) (end 196.483 99.935) (width 0.09) (layer "In7.Cu") (net 518))
  (arc (start 244.158 93.11) (mid 244.264066 93.066066) (end 244.308 92.96) (width 0.1) (layer "In7.Cu") (net 518))
  (arc (start 243.558 93.16) (mid 243.664066 93.116066) (end 243.708 93.01) (width 0.1) (layer "In7.Cu") (net 518))
  (arc (start 196.108 98.71) (mid 196.056744 98.586256) (end 195.933 98.535) (width 0.09) (layer "In7.Cu") (net 518))
  (arc (start 194.833 98.185) (mid 194.709256 98.236256) (end 194.658 98.36) (width 0.09) (layer "In7.Cu") (net 518))
  (arc (start 180.523586 95.665008) (mid 180.41752 95.708942) (end 180.373586 95.815008) (width 0.09) (layer "In7.Cu") (net 518))
  (arc (start 198.161126 99.31429) (mid 198.128684 99.292612) (end 198.090415 99.285) (width 0.09) (layer "In7.Cu") (net 518))
  (arc (start 195.008 98.36) (mid 194.956744 98.236256) (end 194.833 98.185) (width 0.09) (layer "In7.Cu") (net 518))
  (arc (start 190.19118 98.944733) (mid 190.235114 98.838667) (end 190.19118 98.732601) (width 0.09) (layer "In7.Cu") (net 518))
  (arc (start 194.658 98.91) (mid 194.548165 99.175165) (end 194.283 99.285) (width 0.09) (layer "In7.Cu") (net 518))
  (arc (start 197.583 99.285) (mid 197.317835 99.175165) (end 197.208 98.91) (width 0.09) (layer "In7.Cu") (net 518))
  (segment (start 244.831999 93.497999) (end 245.182001 93.497999) (width 0.1) (layer "B.Cu") (net 518))
  (segment (start 245.182001 93.497999) (end 245.285 93.395) (width 0.1) (layer "B.Cu") (net 518))
  (segment (start 245.285 93.395) (end 245.285 93.015) (width 0.1) (layer "B.Cu") (net 518))
  (segment (start 244.65 93.316) (end 244.831999 93.497999) (width 0.1) (layer "B.Cu") (net 518))
  (segment (start 239.888962 89.438098) (end 241.003654 88.323406) (width 0.122) (layer "F.Cu") (net 524))
  (segment (start 241.261748 88.2165) (end 242.927717 88.2165) (width 0.122) (layer "F.Cu") (net 524))
  (segment (start 195.596978 89.13367) (end 195.712999 89.017649) (width 0.1) (layer "F.Cu") (net 524))
  (segment (start 198.143353 89.730991) (end 239.181855 89.730991) (width 0.122) (layer "F.Cu") (net 524))
  (segment (start 198.13457 89.739774) (end 198.143353 89.730991) (width 0.1) (layer "F.Cu") (net 524))
  (segment (start 195.847349 88.962) (end 196.536387 88.962) (width 0.1) (layer "F.Cu") (net 524))
  (segment (start 257.176346 74.123406) (end 258.566594 75.513654) (width 0.122) (layer "F.Cu") (net 524))
  (segment (start 195.136328 89.560008) (end 195.374571 89.560008) (width 0.1) (layer "F.Cu") (net 524))
  (segment (start 195.541328 89.393251) (end 195.541328 89.268021) (width 0.1) (layer "F.Cu") (net 524))
  (segment (start 256.962921 84.963079) (end 256.665 85.261) (width 0.122) (layer "F.Cu") (net 524))
  (segment (start 197.726745 89.783708) (end 198.028504 89.783708) (width 0.1) (layer "F.Cu") (net 524))
  (segment (start 243.6265 87.517717) (end 243.6265 78.251748) (width 0.122) (layer "F.Cu") (net 524))
  (segment (start 258.6735 75.771748) (end 258.6735 83.668252) (width 0.122) (layer "F.Cu") (net 524))
  (segment (start 257.437252 84.9045) (end 257.104343 84.9045) (width 0.122) (layer "F.Cu") (net 524))
  (segment (start 258.566594 83.926346) (end 257.695346 84.797594) (width 0.122) (layer "F.Cu") (net 524))
  (segment (start 243.069139 88.157921) (end 243.567922 87.659138) (width 0.122) (layer "F.Cu") (net 524))
  (segment (start 243.733406 77.993654) (end 247.603654 74.123406) (width 0.122) (layer "F.Cu") (net 524))
  (segment (start 196.88287 89.105518) (end 197.443902 89.66655) (width 0.1) (layer "F.Cu") (net 524))
  (segment (start 195.445282 89.530718) (end 195.512039 89.463961) (width 0.1) (layer "F.Cu") (net 524))
  (segment (start 247.861748 74.0165) (end 256.918252 74.0165) (width 0.122) (layer "F.Cu") (net 524))
  (arc (start 195.374571 89.560008) (mid 195.41284 89.552396) (end 195.445282 89.530718) (width 0.1) (layer "F.Cu") (net 524))
  (arc (start 239.888962 89.438098) (mid 239.564539 89.654871) (end 239.181855 89.730991) (width 0.122) (layer "F.Cu") (net 524))
  (arc (start 196.88287 89.105518) (mid 196.723902 88.999299) (end 196.536387 88.962) (width 0.1) (layer "F.Cu") (net 524))
  (arc (start 242.927717 88.2165) (mid 243.004254 88.201276) (end 243.069139 88.157921) (width 0.122) (layer "F.Cu") (net 524))
  (arc (start 195.541328 89.268021) (mid 195.555791 89.195311) (end 195.596978 89.13367) (width 0.1) (layer "F.Cu") (net 524))
  (arc (start 195.712999 89.017649) (mid 195.774639 88.976462) (end 195.847349 88.962) (width 0.1) (layer "F.Cu") (net 524))
  (arc (start 198.028504 89.783708) (mid 198.085907 89.77229) (end 198.13457 89.739774) (width 0.1) (layer "F.Cu") (net 524))
  (arc (start 256.918252 74.0165) (mid 257.057931 74.044284) (end 257.176346 74.123406) (width 0.122) (layer "F.Cu") (net 524))
  (arc (start 241.003654 88.323406) (mid 241.122069 88.244284) (end 241.261748 88.2165) (width 0.122) (layer "F.Cu") (net 524))
  (arc (start 258.566594 75.513654) (mid 258.645716 75.632069) (end 258.6735 75.771748) (width 0.122) (layer "F.Cu") (net 524))
  (arc (start 247.603654 74.123406) (mid 247.722069 74.044284) (end 247.861748 74.0165) (width 0.122) (layer "F.Cu") (net 524))
  (arc (start 243.6265 78.251748) (mid 243.654284 78.112069) (end 243.733406 77.993654) (width 0.122) (layer "F.Cu") (net 524))
  (arc (start 197.443902 89.66655) (mid 197.573671 89.753259) (end 197.726745 89.783708) (width 0.1) (layer "F.Cu") (net 524))
  (arc (start 257.104343 84.9045) (mid 257.027806 84.919724) (end 256.962921 84.963079) (width 0.122) (layer "F.Cu") (net 524))
  (arc (start 258.6735 83.668252) (mid 258.645716 83.807931) (end 258.566594 83.926346) (width 0.122) (layer "F.Cu") (net 524))
  (arc (start 195.512039 89.463961) (mid 195.533716 89.431519) (end 195.541328 89.393251) (width 0.1) (layer "F.Cu") (net 524))
  (arc (start 257.695346 84.797594) (mid 257.576931 84.876716) (end 257.437252 84.9045) (width 0.122) (layer "F.Cu") (net 524))
  (arc (start 243.567922 87.659138) (mid 243.611276 87.594253) (end 243.6265 87.517717) (width 0.122) (layer "F.Cu") (net 524))
  (segment (start 255.081343 84.6145) (end 255.258657 84.6145) (width 0.122) (layer "F.Cu") (net 525))
  (segment (start 255.400079 84.555921) (end 255.695 84.261) (width 0.122) (layer "F.Cu") (net 525))
  (segment (start 254.81 84.426) (end 254.939922 84.555922) (width 0.122) (layer "F.Cu") (net 525))
  (via (at 254.81 84.426) (size 0.5) (drill 0.2) (layers "F.Cu" "B.Cu") (net 525))
  (arc (start 255.081343 84.6145) (mid 255.004807 84.599276) (end 254.939922 84.555922) (width 0.122) (layer "F.Cu") (net 525))
  (arc (start 255.258657 84.6145) (mid 255.335194 84.599276) (end 255.400079 84.555921) (width 0.122) (layer "F.Cu") (net 525))
  (segment (start 255.445 84.468579) (end 255.445 84.125) (width 0.122) (layer "B.Cu") (net 525))
  (segment (start 255.081343 84.6145) (end 255.257657 84.6145) (width 0.122) (layer "B.Cu") (net 525))
  (segment (start 254.81 84.426) (end 254.939922 84.555922) (width 0.122) (layer "B.Cu") (net 525))
  (segment (start 255.399079 84.555921) (end 255.415711 84.539289) (width 0.122) (layer "B.Cu") (net 525))
  (arc (start 255.081343 84.6145) (mid 255.004807 84.599276) (end 254.939922 84.555922) (width 0.122) (layer "B.Cu") (net 525))
  (arc (start 255.257657 84.6145) (mid 255.334194 84.599276) (end 255.399079 84.555921) (width 0.122) (layer "B.Cu") (net 525))
  (arc (start 255.415711 84.539289) (mid 255.437388 84.506847) (end 255.445 84.468579) (width 0.122) (layer "B.Cu") (net 525))
  (segment (start 258.134767 83.952296) (end 258.134768 83.952295) (width 0.122) (layer "F.Cu") (net 526))
  (segment (start 258.3865 83.617717) (end 258.3865 75.822283) (width 0.122) (layer "F.Cu") (net 526))
  (segment (start 258.327922 75.680862) (end 257.878504 75.231444) (width 0.122) (layer "F.Cu") (net 526))
  (segment (start 257.910939 83.949084) (end 257.91415 83.952295) (width 0.122) (layer "F.Cu") (net 526))
  (segment (start 242.978252 88.5035) (end 241.312283 88.5035) (width 0.122) (layer "F.Cu") (net 526))
  (segment (start 195.731328 89.405907) (end 195.731328 89.309445) (width 0.1) (layer "F.Cu") (net 526))
  (segment (start 243.9135 78.302283) (end 243.9135 87.568252) (width 0.122) (layer "F.Cu") (net 526))
  (segment (start 247.770862 74.362078) (end 246.226445 75.906495) (width 0.122) (layer "F.Cu") (net 526))
  (segment (start 195.760618 89.238734) (end 195.818063 89.181289) (width 0.1) (layer "F.Cu") (net 526))
  (segment (start 197.685321 89.973708) (end 198.036938 89.973708) (width 0.1) (layer "F.Cu") (net 526))
  (segment (start 257.38353 74.948602) (end 257.383529 74.948603) (width 0.122) (layer "F.Cu") (net 526))
  (segment (start 197.227876 89.719228) (end 197.227877 89.719229) (width 0.1) (layer "F.Cu") (net 526))
  (segment (start 257.418885 75.196089) (end 257.38353 75.160734) (width 0.122) (layer "F.Cu") (net 526))
  (segment (start 245.978958 76.40147) (end 245.978957 76.401471) (width 0.122) (layer "F.Cu") (net 526))
  (segment (start 195.888773 89.152) (end 196.494963 89.152) (width 0.1) (layer "F.Cu") (net 526))
  (segment (start 256.867717 74.3035) (end 247.912283 74.3035) (width 0.122) (layer "F.Cu") (net 526))
  (segment (start 196.874323 89.542453) (end 196.874324 89.542452) (width 0.1) (layer "F.Cu") (net 526))
  (segment (start 198.143004 90.017642) (end 198.143353 90.017991) (width 0.1) (layer "F.Cu") (net 526))
  (segment (start 197.051101 89.719227) (end 197.0511 89.719228) (width 0.1) (layer "F.Cu") (net 526))
  (segment (start 257.878504 75.231444) (end 257.843149 75.196089) (width 0.122) (layer "F.Cu") (net 526))
  (segment (start 246.226444 76.153981) (end 246.226445 76.153981) (width 0.122) (layer "F.Cu") (net 526))
  (segment (start 257.69353 84.172914) (end 257.693531 84.172912) (width 0.122) (layer "F.Cu") (net 526))
  (segment (start 257.528138 84.558922) (end 257.69353 84.39353) (width 0.122) (layer "F.Cu") (net 526))
  (segment (start 243.806594 87.826346) (end 243.236346 88.396594) (width 0.122) (layer "F.Cu") (net 526))
  (segment (start 241.170862 88.562078) (end 240.05617 89.67677) (width 0.122) (layer "F.Cu") (net 526))
  (segment (start 196.777806 89.269158) (end 196.874324 89.365676) (width 0.1) (layer "F.Cu") (net 526))
  (segment (start 258.134768 83.952295) (end 258.327921 83.759139) (width 0.122) (layer "F.Cu") (net 526))
  (segment (start 239.23239 90.017991) (end 198.143353 90.017991) (width 0.122) (layer "F.Cu") (net 526))
  (segment (start 195.814718 89.530718) (end 195.760617 89.476617) (width 0.1) (layer "F.Cu") (net 526))
  (segment (start 246.226445 75.906495) (end 246.226443 75.906494) (width 0.122) (layer "F.Cu") (net 526))
  (segment (start 256.665 84.261) (end 256.962921 84.558921) (width 0.122) (layer "F.Cu") (net 526))
  (segment (start 257.104343 84.6175) (end 257.386717 84.6175) (width 0.122) (layer "F.Cu") (net 526))
  (segment (start 257.69032 83.949085) (end 257.690321 83.949084) (width 0.122) (layer "F.Cu") (net 526))
  (segment (start 245.731471 76.401471) (end 243.972079 78.160861) (width 0.122) (layer "F.Cu") (net 526))
  (segment (start 257.38353 74.73647) (end 257.009139 74.362079) (width 0.122) (layer "F.Cu") (net 526))
  (segment (start 197.227877 89.719229) (end 197.338839 89.830191) (width 0.1) (layer "F.Cu") (net 526))
  (segment (start 257.693531 84.172912) (end 257.690321 84.169702) (width 0.122) (layer "F.Cu") (net 526))
  (segment (start 196.136328 89.560008) (end 195.885429 89.560008) (width 0.1) (layer "F.Cu") (net 526))
  (arc (start 246.226445 76.401469) (mid 246.102702 76.452726) (end 245.978958 76.40147) (width 0.122) (layer "F.Cu") (net 526))
  (arc (start 245.978957 76.401471) (mid 245.855214 76.350215) (end 245.731471 76.401471) (width 0.122) (layer "F.Cu") (net 526))
  (arc (start 195.760617 89.476617) (mid 195.73894 89.444175) (end 195.731328 89.405907) (width 0.1) (layer "F.Cu") (net 526))
  (arc (start 246.226445 76.153981) (mid 246.277701 76.277725) (end 246.226445 76.401469) (width 0.122) (layer "F.Cu") (net 526))
  (arc (start 197.338839 89.830191) (mid 197.497806 89.936409) (end 197.685321 89.973708) (width 0.1) (layer "F.Cu") (net 526))
  (arc (start 257.690321 83.949084) (mid 257.80063 83.903393) (end 257.910939 83.949084) (width 0.122) (layer "F.Cu") (net 526))
  (arc (start 198.036938 89.973708) (mid 198.094341 89.985126) (end 198.143004 90.017642) (width 0.1) (layer "F.Cu") (net 526))
  (arc (start 243.9135 87.568252) (mid 243.885716 87.707931) (end 243.806594 87.826346) (width 0.122) (layer "F.Cu") (net 526))
  (arc (start 240.05617 89.67677) (mid 239.678217 89.929311) (end 239.23239 90.017991) (width 0.122) (layer "F.Cu") (net 526))
  (arc (start 257.91415 83.952295) (mid 258.024458 83.997987) (end 258.134767 83.952296) (width 0.122) (layer "F.Cu") (net 526))
  (arc (start 196.494963 89.152) (mid 196.648037 89.182449) (end 196.777806 89.269158) (width 0.1) (layer "F.Cu") (net 526))
  (arc (start 258.3865 75.822283) (mid 258.371276 75.745747) (end 258.327922 75.680862) (width 0.122) (layer "F.Cu") (net 526))
  (arc (start 258.327921 83.759139) (mid 258.371276 83.694254) (end 258.3865 83.617717) (width 0.122) (layer "F.Cu") (net 526))
  (arc (start 246.226443 75.906494) (mid 246.175187 76.030238) (end 246.226444 76.153981) (width 0.122) (layer "F.Cu") (net 526))
  (arc (start 197.0511 89.719228) (mid 197.139488 89.682616) (end 197.227876 89.719228) (width 0.1) (layer "F.Cu") (net 526))
  (arc (start 196.874324 89.542452) (mid 196.837712 89.63084) (end 196.874324 89.719228) (width 0.1) (layer "F.Cu") (net 526))
  (arc (start 196.874324 89.365676) (mid 196.910935 89.454065) (end 196.874323 89.542453) (width 0.1) (layer "F.Cu") (net 526))
  (arc (start 257.843149 75.196089) (mid 257.737083 75.152155) (end 257.631017 75.196089) (width 0.122) (layer "F.Cu") (net 526))
  (arc (start 257.386717 84.6175) (mid 257.463253 84.602276) (end 257.528138 84.558922) (width 0.122) (layer "F.Cu") (net 526))
  (arc (start 257.69353 84.39353) (mid 257.739222 84.283221) (end 257.69353 84.172914) (width 0.122) (layer "F.Cu") (net 526))
  (arc (start 195.885429 89.560008) (mid 195.84716 89.552396) (end 195.814718 89.530718) (width 0.1) (layer "F.Cu") (net 526))
  (arc (start 196.874324 89.719228) (mid 196.962713 89.755839) (end 197.051101 89.719227) (width 0.1) (layer "F.Cu") (net 526))
  (arc (start 247.912283 74.3035) (mid 247.835747 74.318724) (end 247.770862 74.362078) (width 0.122) (layer "F.Cu") (net 526))
  (arc (start 257.383529 74.948603) (mid 257.427464 74.842537) (end 257.38353 74.73647) (width 0.122) (layer "F.Cu") (net 526))
  (arc (start 257.690321 84.169702) (mid 257.644629 84.059394) (end 257.69032 83.949085) (width 0.122) (layer "F.Cu") (net 526))
  (arc (start 243.236346 88.396594) (mid 243.117931 88.475716) (end 242.978252 88.5035) (width 0.122) (layer "F.Cu") (net 526))
  (arc (start 256.962921 84.558921) (mid 257.027806 84.602276) (end 257.104343 84.6175) (width 0.122) (layer "F.Cu") (net 526))
  (arc (start 195.731328 89.309445) (mid 195.73894 89.271176) (end 195.760618 89.238734) (width 0.1) (layer "F.Cu") (net 526))
  (arc (start 243.972079 78.160861) (mid 243.928724 78.225746) (end 243.9135 78.302283) (width 0.122) (layer "F.Cu") (net 526))
  (arc (start 241.312283 88.5035) (mid 241.235747 88.518724) (end 241.170862 88.562078) (width 0.122) (layer "F.Cu") (net 526))
  (arc (start 257.38353 75.160734) (mid 257.339596 75.054668) (end 257.38353 74.948602) (width 0.122) (layer "F.Cu") (net 526))
  (arc (start 257.009139 74.362079) (mid 256.944254 74.318724) (end 256.867717 74.3035) (width 0.122) (layer "F.Cu") (net 526))
  (arc (start 195.818063 89.181289) (mid 195.850505 89.159612) (end 195.888773 89.152) (width 0.1) (layer "F.Cu") (net 526))
  (arc (start 257.631017 75.196089) (mid 257.524951 75.240023) (end 257.418885 75.196089) (width 0.122) (layer "F.Cu") (net 526))
  (segment (start 177.136328 94.560008) (end 176.636328 95.060008) (width 0.1) (layer "F.Cu") (net 528))
  (via (at 247.19 97.126) (size 0.5) (drill 0.2) (layers "F.Cu" "B.Cu") (net 528))
  (via (at 176.636328 95.060008) (size 0.5) (drill 0.2) (layers "F.Cu" "B.Cu") (net 528))
  (segment (start 180.111578 99.663) (end 181.839286 101.390707) (width 0.09) (layer "In5.Cu") (net 528))
  (segment (start 242.427512 97.941067) (end 242.262488 97.941067) (width 0.1) (layer "In5.Cu") (net 528))
  (segment (start 184.545236 104.079246) (end 184.616289 104.008194) (width 0.09) (layer "In5.Cu") (net 528))
  (segment (start 184.802565 104.008194) (end 184.827738 104.033367) (width 0.09) (layer "In5.Cu") (net 528))
  (segment (start 177.864586 94.660008) (end 178.033 94.828422) (width 0.09) (layer "In5.Cu") (net 528))
  (segment (start 184.545238 104.079247) (end 184.545236 104.079246) (width 0.09) (layer "In5.Cu") (net 528))
  (segment (start 243.112134 97.05) (end 242.675357 97.486777) (width 0.1) (layer "In5.Cu") (net 528))
  (segment (start 184.240541 102.693567) (end 184.096626 102.549651) (width 0.09) (layer "In5.Cu") (net 528))
  (segment (start 183.565106 103.116526) (end 183.81 103.361422) (width 0.09) (layer "In5.Cu") (net 528))
  (segment (start 182.617104 102.168526) (end 182.787288 102.338709) (width 0.09) (layer "In5.Cu") (net 528))
  (segment (start 244.82397 96.706) (end 244.47603 96.706) (width 0.1) (layer "In5.Cu") (net 528))
  (segment (start 182.970658 101.037154) (end 182.970658 101.037155) (width 0.09) (layer "In5.Cu") (net 528))
  (segment (start 182.617104 102.168525) (end 182.617104 102.168526) (width 0.09) (layer "In5.Cu") (net 528))
  (segment (start 184.756684 104.761179) (end 184.756684 104.761178) (width 0.09) (layer "In5.Cu") (net 528))
  (segment (start 178.033 94.828422) (end 178.033 99.369422) (width 0.09) (layer "In5.Cu") (net 528))
  (segment (start 244.13203 97.05) (end 243.112134 97.05) (width 0.1) (layer "In5.Cu") (net 528))
  (segment (start 184.308757 102.337517) (end 184.452673 102.481434) (width 0.09) (layer "In5.Cu") (net 528))
  (segment (start 184.096626 102.549651) (end 184.096625 102.549651) (width 0.09) (layer "In5.Cu") (net 528))
  (segment (start 184.827737 104.219641) (end 184.756685 104.290694) (width 0.09) (layer "In5.Cu") (net 528))
  (segment (start 184.378278 101.525536) (end 184.378279 101.525537) (width 0.09) (layer "In5.Cu") (net 528))
  (segment (start 182.970657 101.284642) (end 182.970657 101.284641) (width 0.09) (layer "In5.Cu") (net 528))
  (segment (start 200.512134 105.95) (end 185.887866 105.95) (width 0.1) (layer "In5.Cu") (net 528))
  (segment (start 247.537866 96.7) (end 246.512134 96.7) (width 0.1) (layer "In5.Cu") (net 528))
  (segment (start 247.579867 97.307999) (end 247.8 97.087866) (width 0.1) (layer "In5.Cu") (net 528))
  (segment (start 184.452673 102.481434) (end 184.452674 102.481434) (width 0.09) (layer "In5.Cu") (net 528))
  (segment (start 245.16797 97.05) (end 244.82397 96.706) (width 0.1) (layer "In5.Cu") (net 528))
  (segment (start 246.512134 96.7) (end 246.162134 97.05) (width 0.1) (layer "In5.Cu") (net 528))
  (segment (start 185.887866 105.95) (end 185.473933 105.536067) (width 0.1) (layer "In5.Cu") (net 528))
  (segment (start 183.601651 102.549651) (end 183.565106 102.586196) (width 0.09) (layer "In5.Cu") (net 528))
  (segment (start 176.636328 95.060008) (end 177.036328 94.660008) (width 0.09) (layer "In5.Cu") (net 528))
  (segment (start 182.970657 101.284641) (end 182.617104 101.638195) (width 0.09) (layer "In5.Cu") (net 528))
  (segment (start 247.8 97.087866) (end 247.8 96.962134) (width 0.1) (layer "In5.Cu") (net 528))
  (segment (start 242.646067 97.557488) (end 242.646067 97.722512) (width 0.1) (layer "In5.Cu") (net 528))
  (segment (start 177.036328 94.660008) (end 177.864586 94.660008) (width 0.09) (layer "In5.Cu") (net 528))
  (segment (start 183.81 103.361422) (end 183.81 103.814495) (width 0.09) (layer "In5.Cu") (net 528))
  (segment (start 247.19 97.126) (end 247.371999 97.307999) (width 0.1) (layer "In5.Cu") (net 528))
  (segment (start 184.378278 101.773024) (end 184.37828 101.773025) (width 0.09) (layer "In5.Cu") (net 528))
  (segment (start 183.31762 102.338711) (end 184.130791 101.525537) (width 0.09) (layer "In5.Cu") (net 528))
  (segment (start 242.191778 97.970356) (end 242.012134 98.15) (width 0.1) (layer "In5.Cu") (net 528))
  (segment (start 185.473933 105.519849) (end 185.473933 105.536067) (width 0.09) (layer "In5.Cu") (net 528))
  (segment (start 246.162134 97.05) (end 245.16797 97.05) (width 0.1) (layer "In5.Cu") (net 528))
  (segment (start 184.37828 101.773025) (end 184.308757 101.842543) (width 0.09) (layer "In5.Cu") (net 528))
  (segment (start 178.326578 99.663) (end 180.111578 99.663) (width 0.09) (layer "In5.Cu") (net 528))
  (segment (start 184.756684 104.761178) (end 185.444644 105.449139) (width 0.09) (layer "In5.Cu") (net 528))
  (segment (start 178.033 99.369422) (end 178.326578 99.663) (width 0.09) (layer "In5.Cu") (net 528))
  (segment (start 247.8 96.962134) (end 247.537866 96.7) (width 0.1) (layer "In5.Cu") (net 528))
  (segment (start 182.369618 101.390709) (end 182.72317 101.037154) (width 0.09) (layer "In5.Cu") (net 528))
  (segment (start 208.312134 98.15) (end 200.512134 105.95) (width 0.1) (layer "In5.Cu") (net 528))
  (segment (start 242.616778 97.793222) (end 242.498223 97.911777) (width 0.1) (layer "In5.Cu") (net 528))
  (segment (start 184.827737 104.219642) (end 184.827737 104.219641) (width 0.09) (layer "In5.Cu") (net 528))
  (segment (start 247.371999 97.307999) (end 247.579867 97.307999) (width 0.1) (layer "In5.Cu") (net 528))
  (segment (start 244.47603 96.706) (end 244.13203 97.05) (width 0.1) (layer "In5.Cu") (net 528))
  (segment (start 183.81 103.814495) (end 184.07475 104.079245) (width 0.09) (layer "In5.Cu") (net 528))
  (segment (start 242.012134 98.15) (end 208.312134 98.15) (width 0.1) (layer "In5.Cu") (net 528))
  (segment (start 184.452673 102.693567) (end 184.452674 102.693568) (width 0.09) (layer "In5.Cu") (net 528))
  (arc (start 182.72317 101.037154) (mid 182.846914 100.985898) (end 182.970658 101.037154) (width 0.09) (layer "In5.Cu") (net 528))
  (arc (start 184.378279 101.525537) (mid 184.429535 101.649281) (end 184.378278 101.773024) (width 0.09) (layer "In5.Cu") (net 528))
  (arc (start 182.787288 102.338709) (mid 183.052455 102.448546) (end 183.31762 102.338711) (width 0.09) (layer "In5.Cu") (net 528))
  (arc (start 183.565106 102.586196) (mid 183.455271 102.851361) (end 183.565106 103.116526) (width 0.09) (layer "In5.Cu") (net 528))
  (arc (start 184.452674 102.693568) (mid 184.346607 102.737502) (end 184.240541 102.693567) (width 0.09) (layer "In5.Cu") (net 528))
  (arc (start 242.675357 97.486777) (mid 242.653679 97.519219) (end 242.646067 97.557488) (width 0.1) (layer "In5.Cu") (net 528))
  (arc (start 184.07475 104.079245) (mid 184.309995 104.176688) (end 184.545238 104.079247) (width 0.09) (layer "In5.Cu") (net 528))
  (arc (start 181.839286 101.390707) (mid 182.104453 101.500544) (end 182.369618 101.390709) (width 0.09) (layer "In5.Cu") (net 528))
  (arc (start 184.308757 101.842543) (mid 184.206245 102.09003) (end 184.308757 102.337517) (width 0.09) (layer "In5.Cu") (net 528))
  (arc (start 184.616289 104.008194) (mid 184.709426 103.969614) (end 184.802565 104.008194) (width 0.09) (layer "In5.Cu") (net 528))
  (arc (start 184.827738 104.033367) (mid 184.866316 104.126505) (end 184.827737 104.219642) (width 0.09) (layer "In5.Cu") (net 528))
  (arc (start 242.262488 97.941067) (mid 242.22422 97.948679) (end 242.191778 97.970356) (width 0.1) (layer "In5.Cu") (net 528))
  (arc (start 184.452674 102.481434) (mid 184.496608 102.587501) (end 184.452673 102.693567) (width 0.09) (layer "In5.Cu") (net 528))
  (arc (start 184.096625 102.549651) (mid 183.849138 102.447139) (end 183.601651 102.549651) (width 0.09) (layer "In5.Cu") (net 528))
  (arc (start 242.498223 97.911777) (mid 242.465781 97.933455) (end 242.427512 97.941067) (width 0.1) (layer "In5.Cu") (net 528))
  (arc (start 184.756685 104.290694) (mid 184.659243 104.525935) (end 184.756684 104.761179) (width 0.09) (layer "In5.Cu") (net 528))
  (arc (start 185.444644 105.449139) (mid 185.466321 105.481581) (end 185.473933 105.519849) (width 0.09) (layer "In5.Cu") (net 528))
  (arc (start 182.617104 101.638195) (mid 182.507269 101.90336) (end 182.617104 102.168525) (width 0.09) (layer "In5.Cu") (net 528))
  (arc (start 184.130791 101.525537) (mid 184.254534 101.47428) (end 184.378278 101.525536) (width 0.09) (layer "In5.Cu") (net 528))
  (arc (start 242.646067 97.722512) (mid 242.638455 97.76078) (end 242.616778 97.793222) (width 0.1) (layer "In5.Cu") (net 528))
  (arc (start 182.970658 101.037155) (mid 183.021914 101.160899) (end 182.970657 101.284642) (width 0.09) (layer "In5.Cu") (net 528))
  (segment (start 247.825 97.205) (end 247.825 96.825) (width 0.1) (layer "B.Cu") (net 528))
  (segment (start 247.722001 97.307999) (end 247.825 97.205) (width 0.1) (layer "B.Cu") (net 528))
  (segment (start 247.371999 97.307999) (end 247.722001 97.307999) (width 0.1) (layer "B.Cu") (net 528))
  (segment (start 247.19 97.126) (end 247.371999 97.307999) (width 0.1) (layer "B.Cu") (net 528))
  (segment (start 181.636328 94.060008) (end 182.136328 93.560008) (width 0.1) (layer "F.Cu") (net 529))
  (via (at 249.65 86.05) (size 0.5) (drill 0.2) (layers "F.Cu" "B.Cu") (net 529))
  (via blind (at 181.636328 94.060008) (size 0.5) (drill 0.2) (layers "F.Cu" "In5.Cu") (net 529))
  (segment (start 183.799943 93.665008) (end 182.031328 93.665008) (width 0.09) (layer "In5.Cu") (net 529))
  (segment (start 201.155482 93.166771) (end 201.155482 93.166772) (width 0.1) (layer "In5.Cu") (net 529))
  (segment (start 200.348301 95.081959) (end 199.918042 94.651699) (width 0.1) (layer "In5.Cu") (net 529))
  (segment (start 202.145434 92.176819) (end 202.145434 92.17682) (width 0.1) (layer "In5.Cu") (net 529))
  (segment (start 201.155481 93.414259) (end 201.58574 93.844519) (width 0.1) (layer "In5.Cu") (net 529))
  (segment (start 198.771987 96.4755) (end 198.771986 96.4755) (width 0.1) (layer "In5.Cu") (net 529))
  (segment (start 198.5245 96.4755) (end 198.45 96.55) (width 0.1) (layer "In5.Cu") (net 529))
  (segment (start 199.605836 96.071911) (end 199.605836 96.07191) (width 0.1) (layer "In5.Cu") (net 529))
  (segment (start 248.05 86.45) (end 247.65 86.85) (width 0.1) (layer "In5.Cu") (net 529))
  (segment (start 200.165529 94.404211) (end 200.595788 94.834471) (width 0.1) (layer "In5.Cu") (net 529))
  (segment (start 200.660506 93.661747) (end 200.660506 93.661748) (width 0.1) (layer "In5.Cu") (net 529))
  (segment (start 201.650457 92.919283) (end 202.080716 93.349543) (width 0.1) (layer "In5.Cu") (net 529))
  (segment (start 202.979285 91.77323) (end 202.887898 91.681843) (width 0.1) (layer "In5.Cu") (net 529))
  (segment (start 196.46 96.55) (end 196.34 96.55) (width 0.1) (layer "In5.Cu") (net 529))
  (segment (start 200.843277 94.586983) (end 200.413018 94.156723) (width 0.1) (layer "In5.Cu") (net 529))
  (segment (start 241.75 88.55) (end 239.2 91.1) (width 0.1) (layer "In5.Cu") (net 529))
  (segment (start 201.090764 94.586983) (end 201.090764 94.586982) (width 0.1) (layer "In5.Cu") (net 529))
  (segment (start 202.080716 93.597031) (end 202.080716 93.59703) (width 0.1) (layer "In5.Cu") (net 529))
  (segment (start 197.835 95.875) (end 197.835 97.225) (width 0.1) (layer "In5.Cu") (net 529))
  (segment (start 201.58574 94.092007) (end 201.58574 94.092006) (width 0.1) (layer "In5.Cu") (net 529))
  (segment (start 249.65 86.05) (end 249.25 86.45) (width 0.1) (layer "In5.Cu") (net 529))
  (segment (start 199.670553 94.899187) (end 200.100812 95.329447) (width 0.1) (layer "In5.Cu") (net 529))
  (segment (start 182.031328 93.665008) (end 181.636328 94.060008) (width 0.09) (layer "In5.Cu") (net 529))
  (segment (start 199.358349 96.071911) (end 198.92809 95.641651) (width 0.1) (layer "In5.Cu") (net 529))
  (segment (start 243.3 88.55) (end 241.75 88.55) (width 0.1) (layer "In5.Cu") (net 529))
  (segment (start 200.16553 94.156723) (end 200.16553 94.156724) (width 0.1) (layer "In5.Cu") (net 529))
  (segment (start 184.129 94.321) (end 184.129 93.994065) (width 0.09) (layer "In5.Cu") (net 529))
  (segment (start 202.328205 93.102055) (end 201.897946 92.671795) (width 0.1) (layer "In5.Cu") (net 529))
  (segment (start 201.833229 93.597031) (end 201.40297 93.166771) (width 0.1) (layer "In5.Cu") (net 529))
  (segment (start 198.680602 95.641651) (end 198.680602 95.641652) (width 0.1) (layer "In5.Cu") (net 529))
  (segment (start 244.14 87.71) (end 243.3 88.55) (width 0.1) (layer "In5.Cu") (net 529))
  (segment (start 198.185 96.375) (end 198.185 95.875) (width 0.1) (layer "In5.Cu") (net 529))
  (segment (start 247.02603 86.85) (end 246.62603 87.25) (width 0.1) (layer "In5.Cu") (net 529))
  (segment (start 199.670554 94.651699) (end 199.670554 94.6517) (width 0.1) (layer "In5.Cu") (net 529))
  (segment (start 201.338253 94.092007) (end 200.907994 93.661747) (width 0.1) (layer "In5.Cu") (net 529))
  (segment (start 197.485 97.225) (end 197.485 96.725) (width 0.1) (layer "In5.Cu") (net 529))
  (segment (start 199.11086 96.566886) (end 199.110861 96.566886) (width 0.1) (layer "In5.Cu") (net 529))
  (segment (start 200.100812 95.576935) (end 200.100812 95.576934) (width 0.1) (layer "In5.Cu") (net 529))
  (segment (start 200.660505 93.909235) (end 201.090764 94.339495) (width 0.1) (layer "In5.Cu") (net 529))
  (segment (start 197.11 96.35) (end 197.11 95.903234) (width 0.1) (layer "In5.Cu") (net 529))
  (segment (start 247.65 86.85) (end 247.02603 86.85) (width 0.1) (layer "In5.Cu") (net 529))
  (segment (start 202.823181 92.607079) (end 202.392922 92.176819) (width 0.1) (layer "In5.Cu") (net 529))
  (segment (start 196.71 95.903234) (end 196.71 96.35) (width 0.1) (layer "In5.Cu") (net 529))
  (segment (start 202.575692 93.102055) (end 202.575692 93.102054) (width 0.1) (layer "In5.Cu") (net 529))
  (segment (start 203.070668 92.607079) (end 203.070668 92.607078) (width 0.1) (layer "In5.Cu") (net 529))
  (segment (start 239.2 91.1) (end 203.9 91.1) (width 0.1) (layer "In5.Cu") (net 529))
  (segment (start 196.51 96.55) (end 196.46 96.55) (width 0.1) (layer "In5.Cu") (net 529))
  (segment (start 198.863373 96.566886) (end 198.771987 96.4755) (width 0.1) (layer "In5.Cu") (net 529))
  (segment (start 244.94 87.71) (end 244.14 87.71) (width 0.1) (layer "In5.Cu") (net 529))
  (segment (start 202.64041 91.681843) (end 202.64041 91.681844) (width 0.1) (layer "In5.Cu") (net 529))
  (segment (start 201.650458 92.671795) (end 201.650458 92.671796) (width 0.1) (layer "In5.Cu") (net 529))
  (segment (start 245.4 87.25) (end 244.94 87.71) (width 0.1) (layer "In5.Cu") (net 529))
  (segment (start 188.65 94.75) (end 184.558 94.75) (width 0.09) (layer "In5.Cu") (net 529))
  (segment (start 199.853325 95.576935) (end 199.423066 95.146675) (width 0.1) (layer "In5.Cu") (net 529))
  (segment (start 184.129 93.994065) (end 183.799943 93.665008) (width 0.09) (layer "In5.Cu") (net 529))
  (segment (start 189.37 95.47) (end 188.65 94.75) (width 0.09) (layer "In5.Cu") (net 529))
  (segment (start 199.175577 95.394163) (end 199.605836 95.824423) (width 0.1) (layer "In5.Cu") (net 529))
  (segment (start 202.640409 91.929331) (end 203.070668 92.359591) (width 0.1) (layer "In5.Cu") (net 529))
  (segment (start 203.9 91.1) (end 203.226773 91.77323) (width 0.1) (layer "In5.Cu") (net 529))
  (segment (start 196.34 96.55) (end 195.26 95.47) (width 0.1) (layer "In5.Cu") (net 529))
  (segment (start 202.145433 92.424307) (end 202.575692 92.854567) (width 0.1) (layer "In5.Cu") (net 529))
  (segment (start 249.25 86.45) (end 248.05 86.45) (width 0.1) (layer "In5.Cu") (net 529))
  (segment (start 198.45 96.55) (end 198.36 96.55) (width 0.1) (layer "In5.Cu") (net 529))
  (segment (start 199.175578 95.146675) (end 199.175578 95.146676) (width 0.1) (layer "In5.Cu") (net 529))
  (segment (start 198.680601 95.889139) (end 199.11086 96.319398) (width 0.1) (layer "In5.Cu") (net 529))
  (segment (start 246.62603 87.25) (end 245.4 87.25) (width 0.1) (layer "In5.Cu") (net 529))
  (segment (start 195.26 95.47) (end 189.37 95.47) (width 0.1) (layer "In5.Cu") (net 529))
  (segment (start 184.558 94.75) (end 184.129 94.321) (width 0.09) (layer "In5.Cu") (net 529))
  (segment (start 200.595788 95.081959) (end 200.595788 95.081958) (width 0.1) (layer "In5.Cu") (net 529))
  (arc (start 202.392922 92.176819) (mid 202.269178 92.125563) (end 202.145434 92.176819) (width 0.1) (layer "In5.Cu") (net 529))
  (arc (start 201.58574 94.092006) (mid 201.461997 94.143263) (end 201.338253 94.092007) (width 0.1) (layer "In5.Cu") (net 529))
  (arc (start 200.413018 94.156723) (mid 200.289274 94.105467) (end 200.16553 94.156723) (width 0.1) (layer "In5.Cu") (net 529))
  (arc (start 199.670554 94.6517) (mid 199.619297 94.775443) (end 199.670553 94.899187) (width 0.1) (layer "In5.Cu") (net 529))
  (arc (start 198.01 95.7) (mid 197.886256 95.751256) (end 197.835 95.875) (width 0.1) (layer "In5.Cu") (net 529))
  (arc (start 198.185 95.875) (mid 198.133744 95.751256) (end 198.01 95.7) (width 0.1) (layer "In5.Cu") (net 529))
  (arc (start 199.11086 96.319398) (mid 199.162116 96.443142) (end 199.11086 96.566886) (width 0.1) (layer "In5.Cu") (net 529))
  (arc (start 200.907994 93.661747) (mid 200.78425 93.610491) (end 200.660506 93.661747) (width 0.1) (layer "In5.Cu") (net 529))
  (arc (start 203.070668 92.359591) (mid 203.121924 92.483335) (end 203.070668 92.607079) (width 0.1) (layer "In5.Cu") (net 529))
  (arc (start 202.145434 92.17682) (mid 202.094177 92.300563) (end 202.145433 92.424307) (width 0.1) (layer "In5.Cu") (net 529))
  (arc (start 198.680602 95.641652) (mid 198.629345 95.765395) (end 198.680601 95.889139) (width 0.1) (layer "In5.Cu") (net 529))
  (arc (start 201.58574 93.844519) (mid 201.636996 93.968263) (end 201.58574 94.092007) (width 0.1) (layer "In5.Cu") (net 529))
  (arc (start 201.40297 93.166771) (mid 201.279226 93.115515) (end 201.155482 93.166771) (width 0.1) (layer "In5.Cu") (net 529))
  (arc (start 199.175578 95.146676) (mid 199.124321 95.270419) (end 199.175577 95.394163) (width 0.1) (layer "In5.Cu") (net 529))
  (arc (start 201.155482 93.166772) (mid 201.104225 93.290515) (end 201.155481 93.414259) (width 0.1) (layer "In5.Cu") (net 529))
  (arc (start 198.92809 95.641651) (mid 198.804346 95.590395) (end 198.680602 95.641651) (width 0.1) (layer "In5.Cu") (net 529))
  (arc (start 200.595788 94.834471) (mid 200.647044 94.958215) (end 200.595788 95.081959) (width 0.1) (layer "In5.Cu") (net 529))
  (arc (start 196.91 95.703234) (mid 196.768579 95.761813) (end 196.71 95.903234) (width 0.1) (layer "In5.Cu") (net 529))
  (arc (start 197.835 97.225) (mid 197.783744 97.348744) (end 197.66 97.4) (width 0.1) (layer "In5.Cu") (net 529))
  (arc (start 199.605836 96.07191) (mid 199.482093 96.123167) (end 199.358349 96.071911) (width 0.1) (layer "In5.Cu") (net 529))
  (arc (start 200.595788 95.081958) (mid 200.472045 95.133215) (end 200.348301 95.081959) (width 0.1) (layer "In5.Cu") (net 529))
  (arc (start 201.090764 94.339495) (mid 201.14202 94.463239) (end 201.090764 94.586983) (width 0.1) (layer "In5.Cu") (net 529))
  (arc (start 202.575692 93.102054) (mid 202.451949 93.153311) (end 202.328205 93.102055) (width 0.1) (layer "In5.Cu") (net 529))
  (arc (start 200.100812 95.329447) (mid 200.152068 95.453191) (end 200.100812 95.576935) (width 0.1) (layer "In5.Cu") (net 529))
  (arc (start 202.080716 93.59703) (mid 201.956973 93.648287) (end 201.833229 93.597031) (width 0.1) (layer "In5.Cu") (net 529))
  (arc (start 196.71 96.35) (mid 196.651421 96.491421) (end 196.51 96.55) (width 0.1) (layer "In5.Cu") (net 529))
  (arc (start 203.226773 91.77323) (mid 203.103029 91.824486) (end 202.979285 91.77323) (width 0.1) (layer "In5.Cu") (net 529))
  (arc (start 199.423066 95.146675) (mid 199.299322 95.095419) (end 199.175578 95.146675) (width 0.1) (layer "In5.Cu") (net 529))
  (arc (start 202.575692 92.854567) (mid 202.626948 92.978311) (end 202.575692 93.102055) (width 0.1) (layer "In5.Cu") (net 529))
  (arc (start 202.080716 93.349543) (mid 202.131972 93.473287) (end 202.080716 93.597031) (width 0.1) (layer "In5.Cu") (net 529))
  (arc (start 202.887898 91.681843) (mid 202.764154 91.630587) (end 202.64041 91.681843) (width 0.1) (layer "In5.Cu") (net 529))
  (arc (start 199.605836 95.824423) (mid 199.657092 95.948167) (end 199.605836 96.071911) (width 0.1) (layer "In5.Cu") (net 529))
  (arc (start 200.100812 95.576934) (mid 199.977069 95.628191) (end 199.853325 95.576935) (width 0.1) (layer "In5.Cu") (net 529))
  (arc (start 200.660506 93.661748) (mid 200.609249 93.785491) (end 200.660505 93.909235) (width 0.1) (layer "In5.Cu") (net 529))
  (arc (start 198.771986 96.4755) (mid 198.648243 96.424244) (end 198.5245 96.4755) (width 0.1) (layer "In5.Cu") (net 529))
  (arc (start 197.11 95.903234) (mid 197.051421 95.761813) (end 196.91 95.703234) (width 0.1) (layer "In5.Cu") (net 529))
  (arc (start 197.66 97.4) (mid 197.536256 97.348744) (end 197.485 97.225) (width 0.1) (layer "In5.Cu") (net 529))
  (arc (start 198.36 96.55) (mid 198.236256 96.498744) (end 198.185 96.375) (width 0.1) (layer "In5.Cu") (net 529))
  (arc (start 201.090764 94.586982) (mid 200.967021 94.638239) (end 200.843277 94.586983) (width 0.1) (layer "In5.Cu") (net 529))
  (arc (start 201.897946 92.671795) (mid 201.774202 92.620539) (end 201.650458 92.671795) (width 0.1) (layer "In5.Cu") (net 529))
  (arc (start 197.31 96.55) (mid 197.168579 96.491421) (end 197.11 96.35) (width 0.1) (layer "In5.Cu") (net 529))
  (arc (start 200.16553 94.156724) (mid 200.114273 94.280467) (end 200.165529 94.404211) (width 0.1) (layer "In5.Cu") (net 529))
  (arc (start 203.070668 92.607078) (mid 202.946925 92.658335) (end 202.823181 92.607079) (width 0.1) (layer "In5.Cu") (net 529))
  (arc (start 201.650458 92.671796) (mid 201.599201 92.795539) (end 201.650457 92.919283) (width 0.1) (layer "In5.Cu") (net 529))
  (arc (start 199.110861 96.566886) (mid 198.987117 96.618142) (end 198.863373 96.566886) (width 0.1) (layer "In5.Cu") (net 529))
  (arc (start 197.485 96.725) (mid 197.433744 96.601256) (end 197.31 96.55) (width 0.1) (layer "In5.Cu") (net 529))
  (arc (start 199.918042 94.651699) (mid 199.794298 94.600443) (end 199.670554 94.651699) (width 0.1) (layer "In5.Cu") (net 529))
  (arc (start 202.64041 91.681844) (mid 202.589153 91.805587) (end 202.640409 91.929331) (width 0.1) (layer "In5.Cu") (net 529))
  (segment (start 249.095 84.125) (end 249.65 84.68) (width 0.127) (layer "B.Cu") (net 529))
  (segment (start 249.65 84.68) (end 249.65 86.05) (width 0.127) (layer "B.Cu") (net 529))
  (segment (start 252.85 80.82) (end 253.38 80.82) (width 0.4) (layer "F.Cu") (net 535))
  (segment (start 253.55 80.65) (end 253.59 80.65) (width 0.4) (layer "F.Cu") (net 535))
  (segment (start 253.38 80.82) (end 253.55 80.65) (width 0.4) (layer "F.Cu") (net 535))
  (via (at 250.9 127.5) (size 0.5) (drill 0.2) (layers "F.Cu" "B.Cu") (net 535))
  (via (at 219.05 131.7) (size 0.5) (drill 0.2) (layers "F.Cu" "B.Cu") (net 535))
  (via (at 219.65 133.4) (size 0.5) (drill 0.2) (layers "F.Cu" "B.Cu") (net 535))
  (via (at 219.65 134.75) (size 0.5) (drill 0.2) (layers "F.Cu" "B.Cu") (net 535))
  (via (at 219.05 134.4) (size 0.5) (drill 0.2) (layers "F.Cu" "B.Cu") (net 535))
  (via (at 219.65 132.05) (size 0.5) (drill 0.2) (layers "F.Cu" "B.Cu") (net 535))
  (via (at 251.45 128.1) (size 0.5) (drill 0.2) (layers "F.Cu" "B.Cu") (net 535))
  (via (at 253.55 79.35) (size 0.5) (drill 0.2) (layers "F.Cu" "B.Cu") (net 535))
  (via (at 219.05 131.05) (size 0.5) (drill 0.2) (layers "F.Cu" "B.Cu") (net 535))
  (via (at 219.05 132.4) (size 0.5) (drill 0.2) (layers "F.Cu" "B.Cu") (net 535))
  (via (at 219.05 133.05) (size 0.5) (drill 0.2) (layers "F.Cu" "B.Cu") (net 535))
  (via (at 219.65 132.75) (size 0.5) (drill 0.2) (layers "F.Cu" "B.Cu") (net 535))
  (via (at 219.05 133.7) (size 0.5) (drill 0.2) (layers "F.Cu" "B.Cu") (net 535))
  (via (at 219.65 134.05) (size 0.5) (drill 0.2) (layers "F.Cu" "B.Cu") (net 535))
  (via (at 249.9 127.5) (size 0.5) (drill 0.2) (layers "F.Cu" "B.Cu") (net 535))
  (via (at 219.65 131.4) (size 0.5) (drill 0.2) (layers "F.Cu" "B.Cu") (net 535))
  (via (at 250.4 128) (size 0.5) (drill 0.2) (layers "F.Cu" "B.Cu") (net 535))
  (via (at 253.59 80.65) (size 0.5) (drill 0.2) (layers "F.Cu" "B.Cu") (net 535))
  (via (at 251.45 127.15) (size 0.5) (drill 0.2) (layers "F.Cu" "B.Cu") (net 535))
  (via (at 250.4 127.15) (size 0.5) (drill 0.2) (layers "F.Cu" "B.Cu") (net 535))
  (segment (start 254.175 81.235) (end 254.175 81.585) (width 0.4) (layer "B.Cu") (net 535))
  (segment (start 253.87 79.35) (end 254.175 79.045) (width 0.4) (layer "B.Cu") (net 535))
  (segment (start 253.55 79.35) (end 253.87 79.35) (width 0.4) (layer "B.Cu") (net 535))
  (segment (start 253.59 80.65) (end 254.175 81.235) (width 0.4) (layer "B.Cu") (net 535))
  (segment (start 121.662843 111.335) (end 121.75 111.422157) (width 0.2) (layer "F.Cu") (net 536))
  (segment (start 120.65 111.335) (end 121.662843 111.335) (width 0.2) (layer "F.Cu") (net 536))
  (segment (start 117.111328 112.822157) (end 117.161328 112.872157) (width 0.15) (layer "F.Cu") (net 536))
  (segment (start 116.286328 112.822157) (end 117.111328 112.822157) (width 0.15) (layer "F.Cu") (net 536))
  (via (at 117.161328 112.872157) (size 0.5) (drill 0.2) (layers "F.Cu" "B.Cu") (net 536))
  (via (at 121.75 111.422157) (size 0.5) (drill 0.2) (layers "F.Cu" "B.Cu") (net 536))
  (segment (start 121.127843 112.872157) (end 121.75 112.25) (width 0.2) (layer "B.Cu") (net 536))
  (segment (start 125.975 105.7) (end 125.975 107.825) (width 0.127) (layer "B.Cu") (net 536))
  (segment (start 126.525 105.15) (end 125.975 105.7) (width 0.127) (layer "B.Cu") (net 536))
  (segment (start 127.65 105.15) (end 128.29 104.51) (width 0.127) (layer "B.Cu") (net 536))
  (segment (start 127.425 105.15) (end 127.65 105.15) (width 0.127) (layer "B.Cu") (net 536))
  (segment (start 125.975 107.825) (end 122.377843 111.422157) (width 0.127) (layer "B.Cu") (net 536))
  (segment (start 121.75 112.25) (end 121.75 111.422157) (width 0.2) (layer "B.Cu") (net 536))
  (segment (start 127.425 105.15) (end 126.525 105.15) (width 0.127) (layer "B.Cu") (net 536))
  (segment (start 122.377843 111.422157) (end 121.75 111.422157) (width 0.127) (layer "B.Cu") (net 536))
  (segment (start 128.29 104.51) (end 128.29 102.8) (width 0.127) (layer "B.Cu") (net 536))
  (segment (start 117.161328 112.872157) (end 121.127843 112.872157) (width 0.2) (layer "B.Cu") (net 536))
  (segment (start 164.150531 106.616038) (end 164.150531 104.860531) (width 0.2) (layer "F.Cu") (net 537))
  (segment (start 164.150531 104.860531) (end 163.9 104.61) (width 0.2) (layer "F.Cu") (net 537))
  (segment (start 163.875 106.891569) (end 164.150531 106.616038) (width 0.2) (layer "F.Cu") (net 537))
  (via (at 163.875 106.891569) (size 0.5) (drill 0.2) (layers "F.Cu" "B.Cu") (net 537))
  (segment (start 164.38216 107.4215) (end 163.875 106.91434) (width 0.15) (layer "B.Cu") (net 537))
  (segment (start 170.208058 129.991942) (end 168.891942 129.991942) (width 0.15) (layer "B.Cu") (net 537))
  (segment (start 171.292513 131.076396) (end 170.208058 129.991942) (width 0.15) (layer "B.Cu") (net 537))
  (segment (start 172.475 118.875) (end 172.475 112.975) (width 0.15) (layer "B.Cu") (net 537))
  (segment (start 172.175 121.25) (end 172.175 119.175) (width 0.15) (layer "B.Cu") (net 537))
  (segment (start 172.475 112.975) (end 166.920689 107.420689) (width 0.15) (layer "B.Cu") (net 537))
  (segment (start 166.920689 107.420689) (end 164.6395 107.420689) (width 0.15) (layer "B.Cu") (net 537))
  (segment (start 172.140002 131.076396) (end 171.292513 131.076396) (width 0.15) (layer "B.Cu") (net 537))
  (segment (start 168.891942 129.991942) (end 167.25 128.35) (width 0.15) (layer "B.Cu") (net 537))
  (segment (start 171.55 121.875) (end 172.175 121.25) (width 0.15) (layer "B.Cu") (net 537))
  (segment (start 169.1 121.875) (end 171.55 121.875) (width 0.15) (layer "B.Cu") (net 537))
  (segment (start 167.25 123.725) (end 169.1 121.875) (width 0.15) (layer "B.Cu") (net 537))
  (segment (start 167.25 128.35) (end 167.25 123.725) (width 0.15) (layer "B.Cu") (net 537))
  (segment (start 163.875 106.91434) (end 163.875 106.891569) (width 0.15) (layer "B.Cu") (net 537))
  (segment (start 164.6395 107.4215) (end 164.38216 107.4215) (width 0.15) (layer "B.Cu") (net 537))
  (segment (start 172.175 119.175) (end 172.475 118.875) (width 0.15) (layer "B.Cu") (net 537))
  (segment (start 245.285 125.1642) (end 245.285 124.765) (width 0.127) (layer "B.Cu") (net 542))
  (segment (start 243.5 126.9492) (end 245.285 125.1642) (width 0.127) (layer "B.Cu") (net 542))
  (segment (start 151.35 107.15) (end 151.62 107.42) (width 0.2) (layer "F.Cu") (net 546))
  (segment (start 151.35 107.095) (end 151.35 107.15) (width 0.2) (layer "F.Cu") (net 546))
  (segment (start 151.62 107.42) (end 152.2745 107.42) (width 0.2) (layer "F.Cu") (net 546))
  (via (at 152.2745 107.42) (size 0.5) (drill 0.2) (layers "F.Cu" "B.Cu") (net 546))
  (segment (start 156.87 120.09) (end 155.85 121.11) (width 0.15) (layer "In7.Cu") (net 546))
  (segment (start 160.980443 129.469557) (end 158.669557 129.469557) (width 0.15) (layer "In7.Cu") (net 546))
  (segment (start 161.399998 129.889112) (end 161.399998 131.076396) (width 0.15) (layer "In7.Cu") (net 546))
  (segment (start 158.669557 129.469557) (end 157.2 128) (width 0.15) (layer "In7.Cu") (net 546))
  (segment (start 152.969326 107.42) (end 153.544328 107.995002) (width 0.15) (layer "In7.Cu") (net 546))
  (segment (start 153.544328 114.024328) (end 154.79 115.27) (width 0.15) (layer "In7.Cu") (net 546))
  (segment (start 153.544328 107.995002) (end 153.544328 114.024328) (width 0.15) (layer "In7.Cu") (net 546))
  (segment (start 156.87 116.23) (end 156.87 120.09) (width 0.15) (layer "In7.Cu") (net 546))
  (segment (start 160.980443 129.469557) (end 161.399998 129.889112) (width 0.15) (layer "In7.Cu") (net 546))
  (segment (start 155.91 115.27) (end 156.87 116.23) (width 0.15) (layer "In7.Cu") (net 546))
  (segment (start 155.85 124.339115) (end 157.2 125.689115) (width 0.15) (layer "In7.Cu") (net 546))
  (segment (start 157.2 125.689115) (end 157.2 128) (width 0.15) (layer "In7.Cu") (net 546))
  (segment (start 155.85 121.11) (end 155.85 124.339115) (width 0.15) (layer "In7.Cu") (net 546))
  (segment (start 154.79 115.27) (end 155.91 115.27) (width 0.15) (layer "In7.Cu") (net 546))
  (segment (start 152.2745 107.42) (end 152.969326 107.42) (width 0.15) (layer "In7.Cu") (net 546))
  (segment (start 152.275189 107.420689) (end 152.2745 107.42) (width 0.15) (layer "B.Cu") (net 546))
  (segment (start 153.6895 107.420689) (end 152.275189 107.420689) (width 0.15) (layer "B.Cu") (net 546))
  (segment (start 163.814502 109.73884) (end 163.814501 109.565499) (width 0.1) (layer "F.Cu") (net 547))
  (segment (start 163.814501 109.565499) (end 164.04 109.34) (width 0.1) (layer "F.Cu") (net 547))
  (segment (start 164.014501 109.938839) (end 163.814502 109.73884) (width 0.1) (layer "F.Cu") (net 547))
  (via (at 164.014501 109.938839) (size 0.5) (drill 0.2) (layers "F.Cu" "B.Cu") (net 547))
  (segment (start 163.914501 109.145499) (end 163.914501 109.430499) (width 0.1) (layer "B.Cu") (net 547))
  (segment (start 171.215 120.656397) (end 171.25 120.621397) (width 0.1) (layer "B.Cu") (net 547))
  (segment (start 163.914501 109.430499) (end 163.814501 109.530499) (width 0.1) (layer "B.Cu") (net 547))
  (segment (start 171.25 120.621397) (end 171.25 119.290865) (width 0.1) (layer "B.Cu") (net 547))
  (segment (start 163.814502 109.73884) (end 164.014501 109.938839) (width 0.1) (layer "B.Cu") (net 547))
  (segment (start 163.814501 111.427365) (end 163.814502 110.138838) (width 0.1) (layer "B.Cu") (net 547))
  (segment (start 171.25 119.290865) (end 171.65 118.890865) (width 0.1) (layer "B.Cu") (net 547))
  (segment (start 163.814501 109.530499) (end 163.814502 109.73884) (width 0.1) (layer "B.Cu") (net 547))
  (segment (start 164.037136 111.65) (end 163.814501 111.427365) (width 0.1) (layer "B.Cu") (net 547))
  (segment (start 171.65 118.890865) (end 171.65 115.362866) (width 0.1) (layer "B.Cu") (net 547))
  (segment (start 167.937134 111.65) (end 164.037136 111.65) (width 0.1) (layer "B.Cu") (net 547))
  (segment (start 171.65 115.362866) (end 167.937134 111.65) (width 0.1) (layer "B.Cu") (net 547))
  (segment (start 163.814502 110.138838) (end 164.014501 109.938839) (width 0.1) (layer "B.Cu") (net 547))
  (segment (start 163.314501 109.938839) (end 163.5145 109.73884) (width 0.1) (layer "F.Cu") (net 548))
  (segment (start 163.514501 109.574501) (end 163.28 109.34) (width 0.1) (layer "F.Cu") (net 548))
  (segment (start 163.5145 109.73884) (end 163.514501 109.574501) (width 0.1) (layer "F.Cu") (net 548))
  (via (at 163.314501 109.938839) (size 0.5) (drill 0.2) (layers "F.Cu" "B.Cu") (net 548))
  (segment (start 163.414502 109.430499) (end 163.514502 109.530499) (width 0.1) (layer "B.Cu") (net 548))
  (segment (start 167.812866 111.95) (end 171.35 115.487134) (width 0.1) (layer "B.Cu") (net 548))
  (segment (start 163.912868 111.95) (end 167.812866 111.95) (width 0.1) (layer "B.Cu") (net 548))
  (segment (start 170.58 119.07) (end 169.945 118.435) (width 0.1) (layer "B.Cu") (net 548))
  (segment (start 163.514502 109.738838) (end 163.314501 109.938839) (width 0.1) (layer "B.Cu") (net 548))
  (segment (start 171.35 118.766597) (end 171.046597 119.07) (width 0.1) (layer "B.Cu") (net 548))
  (segment (start 169.945 118.435) (end 169.945 118.116397) (width 0.1) (layer "B.Cu") (net 548))
  (segment (start 163.514501 111.551633) (end 163.912868 111.95) (width 0.1) (layer "B.Cu") (net 548))
  (segment (start 171.046597 119.07) (end 170.58 119.07) (width 0.1) (layer "B.Cu") (net 548))
  (segment (start 163.514502 109.530499) (end 163.514502 109.738838) (width 0.1) (layer "B.Cu") (net 548))
  (segment (start 163.414502 109.145499) (end 163.414502 109.430499) (width 0.1) (layer "B.Cu") (net 548))
  (segment (start 163.5145 110.138838) (end 163.514501 111.551633) (width 0.1) (layer "B.Cu") (net 548))
  (segment (start 171.35 115.487134) (end 171.35 118.766597) (width 0.1) (layer "B.Cu") (net 548))
  (segment (start 163.314501 109.938839) (end 163.5145 110.138838) (width 0.1) (layer "B.Cu") (net 548))
  (segment (start 206.5485 119.16) (end 206.5485 120.4785) (width 0.2) (layer "F.Cu") (net 556))
  (segment (start 206.5485 120.4785) (end 208.1785 122.1085) (width 0.2) (layer "F.Cu") (net 556))
  (segment (start 208.1785 122.1085) (end 208.1785 126.95) (width 0.2) (layer "F.Cu") (net 556))
  (segment (start 161.314499 109.585501) (end 161.55 109.35) (width 0.1) (layer "F.Cu") (net 558))
  (segment (start 161.514499 109.938839) (end 161.3145 109.73884) (width 0.1) (layer "F.Cu") (net 558))
  (segment (start 161.3145 109.73884) (end 161.314499 109.585501) (width 0.1) (layer "F.Cu") (net 558))
  (via (at 161.514499 109.938839) (size 0.5) (drill 0.2) (layers "F.Cu" "B.Cu") (net 558))
  (segment (start 168.775 115.287866) (end 168.775 118.937134) (width 0.1) (layer "B.Cu") (net 558))
  (segment (start 161.414499 109.145499) (end 161.414499 109.430499) (width 0.1) (layer "B.Cu") (net 558))
  (segment (start 168.675 119.037134) (end 168.675 120.656397) (width 0.1) (layer "B.Cu") (net 558))
  (segment (start 161.514499 109.938839) (end 161.3145 110.138838) (width 0.1) (layer "B.Cu") (net 558))
  (segment (start 161.3145 109.73884) (end 161.514499 109.938839) (width 0.1) (layer "B.Cu") (net 558))
  (segment (start 161.314499 112.142365) (end 162.112134 112.94) (width 0.1) (layer "B.Cu") (net 558))
  (segment (start 166.427134 112.94) (end 168.775 115.287866) (width 0.1) (layer "B.Cu") (net 558))
  (segment (start 161.414499 109.430499) (end 161.314499 109.530499) (width 0.1) (layer "B.Cu") (net 558))
  (segment (start 168.775 118.937134) (end 168.675 119.037134) (width 0.1) (layer "B.Cu") (net 558))
  (segment (start 161.3145 110.138838) (end 161.314499 112.142365) (width 0.1) (layer "B.Cu") (net 558))
  (segment (start 162.112134 112.94) (end 166.427134 112.94) (width 0.1) (layer "B.Cu") (net 558))
  (segment (start 161.314499 109.530499) (end 161.3145 109.73884) (width 0.1) (layer "B.Cu") (net 558))
  (segment (start 160.814499 109.938839) (end 161.014498 109.73884) (width 0.1) (layer "F.Cu") (net 559))
  (segment (start 161.014499 109.564499) (end 160.8 109.35) (width 0.1) (layer "F.Cu") (net 559))
  (segment (start 161.014498 109.73884) (end 161.014499 109.564499) (width 0.1) (layer "F.Cu") (net 559))
  (via (at 160.814499 109.938839) (size 0.5) (drill 0.2) (layers "F.Cu" "B.Cu") (net 559))
  (segment (start 166.302866 113.24) (end 161.987866 113.24) (width 0.1) (layer "B.Cu") (net 559))
  (segment (start 168.475 115.412134) (end 166.302866 113.24) (width 0.1) (layer "B.Cu") (net 559))
  (segment (start 168.475 118.812866) (end 168.475 117.525) (width 0.1) (layer "B.Cu") (net 559))
  (segment (start 161.03 110.15434) (end 160.814499 109.938839) (width 0.1) (layer "B.Cu") (net 559))
  (segment (start 160.9145 109.145499) (end 160.9145 109.430499) (width 0.1) (layer "B.Cu") (net 559))
  (segment (start 161.987866 113.24) (end 161.03 112.282134) (width 0.1) (layer "B.Cu") (net 559))
  (segment (start 167.405 118.116397) (end 168.187866 118.899263) (width 0.1) (layer "B.Cu") (net 559))
  (segment (start 168.475 116.825) (end 168.475 115.412134) (width 0.1) (layer "B.Cu") (net 559))
  (segment (start 168.272332 117) (end 168.3 117) (width 0.1) (layer "B.Cu") (net 559))
  (segment (start 168.388603 118.899263) (end 168.475 118.812866) (width 0.1) (layer "B.Cu") (net 559))
  (segment (start 161.0145 109.738838) (end 160.814499 109.938839) (width 0.1) (layer "B.Cu") (net 559))
  (segment (start 168.187866 118.899263) (end 168.388603 118.899263) (width 0.1) (layer "B.Cu") (net 559))
  (segment (start 160.9145 109.430499) (end 161.0145 109.530499) (width 0.1) (layer "B.Cu") (net 559))
  (segment (start 168.3 117.35) (end 168.272332 117.35) (width 0.1) (layer "B.Cu") (net 559))
  (segment (start 161.03 112.282134) (end 161.03 110.15434) (width 0.1) (layer "B.Cu") (net 559))
  (segment (start 161.0145 109.530499) (end 161.0145 109.738838) (width 0.1) (layer "B.Cu") (net 559))
  (arc (start 168.097332 117.175) (mid 168.148588 117.051256) (end 168.272332 117) (width 0.1) (layer "B.Cu") (net 559))
  (arc (start 168.272332 117.35) (mid 168.148588 117.298744) (end 168.097332 117.175) (width 0.1) (layer "B.Cu") (net 559))
  (arc (start 168.3 117) (mid 168.423744 116.948744) (end 168.475 116.825) (width 0.1) (layer "B.Cu") (net 559))
  (arc (start 168.475 117.525) (mid 168.423744 117.401256) (end 168.3 117.35) (width 0.1) (layer "B.Cu") (net 559))
  (segment locked (start 207.1785 124.88) (end 207.1785 122.474899) (width 0.2) (layer "F.Cu") (net 560))
  (segment locked (start 207.1785 122.474899) (end 205.863601 121.16) (width 0.2) (layer "F.Cu") (net 560))
  (segment (start 207.1785 124.88) (end 207.1785 126.95) (width 0.2) (layer "F.Cu") (net 560))
  (segment locked (start 206.6785 123.366) (end 204.9725 121.66) (width 0.2) (layer "F.Cu") (net 561))
  (segment locked (start 206.6785 124.88) (end 206.6785 123.366) (width 0.2) (layer "F.Cu") (net 561))
  (segment locked (start 204.9725 121.66) (end 204.9725 119.3354) (width 0.2) (layer "F.Cu") (net 561))
  (segment (start 206.6785 124.88) (end 206.6785 126.95) (width 0.2) (layer "F.Cu") (net 561))
  (segment locked (start 204.0725 121.46) (end 204.0725 121.16) (width 0.2) (layer "F.Cu") (net 562))
  (segment (start 205.6785 123.35225) (end 205.6785 126.95) (width 0.2) (layer "F.Cu") (net 562))
  (segment (start 204.0725 121.74625) (end 205.6785 123.35225) (width 0.2) (layer "F.Cu") (net 562))
  (segment (start 204.0725 121.74625) (end 204.0725 121.46) (width 0.2) (layer "F.Cu") (net 562))
  (segment locked (start 203.0725 121.419493) (end 203.0725 119.16) (width 0.2) (layer "F.Cu") (net 563))
  (segment (start 203.0725 121.6425) (end 203.0725 121.419493) (width 0.2) (layer "F.Cu") (net 563))
  (segment (start 203.0725 121.6425) (end 205.1785 123.7485) (width 0.2) (layer "F.Cu") (net 563))
  (segment (start 205.1785 123.7485) (end 205.1785 126.95) (width 0.2) (layer "F.Cu") (net 563))
  (segment (start 139.5 119.915) (end 139.765 119.65) (width 0.2) (layer "B.Cu") (net 564))
  (segment (start 139.5 121.45) (end 139.5 119.915) (width 0.2) (layer "B.Cu") (net 564))
  (segment (start 147.6 128.685) (end 146.9 127.985) (width 0.1) (layer "F.Cu") (net 565))
  (segment (start 147.6 129.41) (end 147.6 128.685) (width 0.1) (layer "F.Cu") (net 565))
  (segment (start 158.55 109.36) (end 158.314499 109.595501) (width 0.1) (layer "F.Cu") (net 567))
  (segment (start 158.55 109.355) (end 158.55 109.36) (width 0.1) (layer "F.Cu") (net 567))
  (segment (start 158.314499 109.595501) (end 158.3145 109.73884) (width 0.1) (layer "F.Cu") (net 567))
  (segment (start 158.3145 109.73884) (end 158.514499 109.938839) (width 0.1) (layer "F.Cu") (net 567))
  (via (at 158.514499 109.938839) (size 0.5) (drill 0.2) (layers "F.Cu" "B.Cu") (net 567))
  (segment (start 163.77 119.27) (end 163.985699 119.485699) (width 0.1) (layer "B.Cu") (net 567))
  (segment (start 160.287134 113.9) (end 162.262134 113.9) (width 0.1) (layer "B.Cu") (net 567))
  (segment (start 158.414499 109.145499) (end 158.414499 109.430499) (width 0.1) (layer "B.Cu") (net 567))
  (segment (start 158.3145 110.138838) (end 158.314499 111.927365) (width 0.1) (layer "B.Cu") (net 567))
  (segment (start 158.514499 109.938839) (end 158.3145 110.138838) (width 0.1) (layer "B.Cu") (net 567))
  (segment (start 158.314499 109.530499) (end 158.3145 109.73884) (width 0.1) (layer "B.Cu") (net 567))
  (segment (start 158.414499 109.430499) (end 158.314499 109.530499) (width 0.1) (layer "B.Cu") (net 567))
  (segment (start 164.964301 119.485699) (end 166.135 120.656397) (width 0.1) (layer "B.Cu") (net 567))
  (segment (start 158.314499 111.927365) (end 160.287134 113.9) (width 0.1) (layer "B.Cu") (net 567))
  (segment (start 158.3145 109.73884) (end 158.514499 109.938839) (width 0.1) (layer "B.Cu") (net 567))
  (segment (start 162.262134 113.9) (end 163.77 115.407866) (width 0.1) (layer "B.Cu") (net 567))
  (segment (start 163.77 115.407866) (end 163.77 119.27) (width 0.1) (layer "B.Cu") (net 567))
  (segment (start 163.985699 119.485699) (end 164.964301 119.485699) (width 0.1) (layer "B.Cu") (net 567))
  (segment (start 158.014499 109.564499) (end 158.014498 109.73884) (width 0.1) (layer "F.Cu") (net 568))
  (segment (start 157.8 109.35) (end 158.014499 109.564499) (width 0.1) (layer "F.Cu") (net 568))
  (segment (start 158.014498 109.73884) (end 157.814499 109.938839) (width 0.1) (layer "F.Cu") (net 568))
  (via (at 157.814499 109.938839) (size 0.5) (drill 0.2) (layers "F.Cu" "B.Cu") (net 568))
  (segment (start 162.325 118.116397) (end 162.325 118.975) (width 0.1) (layer "B.Cu") (net 568))
  (segment (start 160.162866 114.2) (end 158.014499 112.051633) (width 0.1) (layer "B.Cu") (net 568))
  (segment (start 158.0145 109.738838) (end 157.814499 109.938839) (width 0.1) (layer "B.Cu") (net 568))
  (segment (start 162.137866 114.2) (end 160.162866 114.2) (width 0.1) (layer "B.Cu") (net 568))
  (segment (start 163.3 119.35) (end 163.47 119.18) (width 0.1) (layer "B.Cu") (net 568))
  (segment (start 163.47 115.532134) (end 162.137866 114.2) (width 0.1) (layer "B.Cu") (net 568))
  (segment (start 157.9145 109.430499) (end 158.0145 109.530499) (width 0.1) (layer "B.Cu") (net 568))
  (segment (start 162.325 118.975) (end 162.7 119.35) (width 0.1) (layer "B.Cu") (net 568))
  (segment (start 158.0145 109.530499) (end 158.0145 109.738838) (width 0.1) (layer "B.Cu") (net 568))
  (segment (start 158.014498 110.138838) (end 157.814499 109.938839) (width 0.1) (layer "B.Cu") (net 568))
  (segment (start 162.7 119.35) (end 163.3 119.35) (width 0.1) (layer "B.Cu") (net 568))
  (segment (start 158.014499 112.051633) (end 158.014498 110.138838) (width 0.1) (layer "B.Cu") (net 568))
  (segment (start 163.1019 116.855) (end 163.245 116.855) (width 0.1) (layer "B.Cu") (net 568))
  (segment (start 163.47 116.63) (end 163.47 115.532134) (width 0.1) (layer "B.Cu") (net 568))
  (segment (start 157.9145 109.145499) (end 157.9145 109.430499) (width 0.1) (layer "B.Cu") (net 568))
  (segment (start 163.245 117.305) (end 163.1019 117.305) (width 0.1) (layer "B.Cu") (net 568))
  (segment (start 163.47 119.18) (end 163.47 117.53) (width 0.1) (layer "B.Cu") (net 568))
  (arc (start 163.1019 117.305) (mid 162.942801 117.239099) (end 162.8769 117.08) (width 0.1) (layer "B.Cu") (net 568))
  (arc (start 163.47 117.53) (mid 163.404099 117.370901) (end 163.245 117.305) (width 0.1) (layer "B.Cu") (net 568))
  (arc (start 163.245 116.855) (mid 163.404099 116.789099) (end 163.47 116.63) (width 0.1) (layer "B.Cu") (net 568))
  (arc (start 162.8769 117.08) (mid 162.942801 116.920901) (end 163.1019 116.855) (width 0.1) (layer "B.Cu") (net 568))
  (segment (start 150.6 127.985) (end 150.6 129.41) (width 0.1) (layer "F.Cu") (net 569))
  (segment (start 240.1 82.5) (end 240.915 82.5) (width 0.2) (layer "B.Cu") (net 573))
  (segment (start 239.85 82.75) (end 240.1 82.5) (width 0.2) (layer "B.Cu") (net 573))
  (segment (start 239.85 83.1) (end 239.85 82.75) (width 0.2) (layer "B.Cu") (net 573))
  (segment (start 241.015 97.315) (end 241.015 97.8) (width 0.2) (layer "B.Cu") (net 574))
  (segment (start 240.25 96.55) (end 241.015 97.315) (width 0.2) (layer "B.Cu") (net 574))
  (segment (start 239.85 96.55) (end 240.25 96.55) (width 0.2) (layer "B.Cu") (net 574))
  (segment (start 241.015 91.965) (end 241.015 92.6) (width 0.2) (layer "B.Cu") (net 575))
  (segment (start 240.25 91.2) (end 241.015 91.965) (width 0.2) (layer "B.Cu") (net 575))
  (segment (start 239.85 91.2) (end 240.25 91.2) (width 0.2) (layer "B.Cu") (net 575))
  (segment (start 241.015 94.64) (end 241.015 95.35) (width 0.2) (layer "B.Cu") (net 576))
  (segment (start 240.275 93.9) (end 241.015 94.64) (width 0.2) (layer "B.Cu") (net 576))
  (segment (start 239.85 93.9) (end 240.275 93.9) (width 0.2) (layer "B.Cu") (net 576))
  (segment (start 240.25 88.5) (end 241.015 89.265) (width 0.2) (layer "B.Cu") (net 577))
  (segment (start 241.015 89.265) (end 241.015 89.9) (width 0.2) (layer "B.Cu") (net 577))
  (segment (start 239.85 88.5) (end 240.25 88.5) (width 0.2) (layer "B.Cu") (net 577))
  (segment (start 240.525 84.5) (end 239.85 85.175) (width 0.2) (layer "B.Cu") (net 578))
  (segment (start 241.015 84.5) (end 240.525 84.5) (width 0.2) (layer "B.Cu") (net 578))
  (segment (start 239.85 85.175) (end 239.85 85.825) (width 0.2) (layer "B.Cu") (net 578))
  (segment (start 241.6 123.115) (end 240.65 123.115) (width 0.2) (layer "B.Cu") (net 579))
  (segment (start 240.635 125.865) (end 240.55 125.865) (width 0.2) (layer "B.Cu") (net 580))
  (segment (start 240.7 125.715) (end 240.55 125.865) (width 0.2) (layer "B.Cu") (net 580))
  (segment (start 241.6 125.715) (end 240.7 125.715) (width 0.2) (layer "B.Cu") (net 580))
  (segment (start 239.85 80.4) (end 240.915 80.4) (width 0.2) (layer "B.Cu") (net 581))
  (segment (start 240.2 78.4) (end 240.915 78.4) (width 0.2) (layer "B.Cu") (net 582))
  (segment (start 239.85 77.7) (end 239.85 78.05) (width 0.2) (layer "B.Cu") (net 582))
  (segment (start 239.85 78.05) (end 240.2 78.4) (width 0.2) (layer "B.Cu") (net 582))
  (segment (start 132.68 108.33) (end 133.65 109.3) (width 0.12) (layer "B.Cu") (net 583))
  (segment (start 132.575 108.33) (end 132.145 107.9) (width 0.127) (layer "B.Cu") (net 583))
  (segment (start 132.145 107.9) (end 131.075 107.9) (width 0.127) (layer "B.Cu") (net 583))
  (segment (start 132.575 108.33) (end 132.68 108.33) (width 0.12) (layer "B.Cu") (net 583))
  (segment (start 224.9 122.6) (end 224.9 122.05) (width 0.2) (layer "F.Cu") (net 584))
  (segment (start 222.75 123.35) (end 223.735 123.35) (width 0.2) (layer "F.Cu") (net 584))
  (segment (start 224.215 123.285) (end 224.9 122.6) (width 0.2) (layer "F.Cu") (net 584))
  (segment (start 223.8 123.285) (end 224.215 123.285) (width 0.2) (layer "F.Cu") (net 584))
  (segment (start 223.735 123.35) (end 223.8 123.285) (width 0.2) (layer "F.Cu") (net 584))
  (segment (start 146.161328 106.872157) (end 144.719657 106.872157) (width 0.1) (layer "F.Cu") (net 585))
  (segment (start 147.036328 107.747157) (end 147.566328 107.747157) (width 0.1) (layer "F.Cu") (net 585))
  (segment (start 144.719657 106.872157) (end 144.7175 106.87) (width 0.1) (layer "F.Cu") (net 585))
  (segment (start 146.161328 106.872157) (end 147.036328 107.747157) (width 0.1) (layer "F.Cu") (net 585))
  (segment (start 146.536328 106.372157) (end 144.719657 106.372157) (width 0.1) (layer "F.Cu") (net 586))
  (segment (start 146.786328 106.622157) (end 147.551328 106.622157) (width 0.1) (layer "F.Cu") (net 586))
  (segment (start 146.536328 106.372157) (end 146.786328 106.622157) (width 0.1) (layer "F.Cu") (net 586))
  (segment (start 144.719657 106.372157) (end 144.7175 106.37) (width 0.1) (layer "F.Cu") (net 586))
  (segment (start 144.719657 105.872157) (end 144.7175 105.87) (width 0.1) (layer "F.Cu") (net 587))
  (segment (start 146.536328 105.872157) (end 144.719657 105.872157) (width 0.1) (layer "F.Cu") (net 587))
  (segment (start 146.911328 105.497157) (end 147.551328 105.497157) (width 0.1) (layer "F.Cu") (net 587))
  (segment (start 146.536328 105.872157) (end 146.911328 105.497157) (width 0.1) (layer "F.Cu") (net 587))
  (segment (start 146.556742 105.366743) (end 147.551328 104.372157) (width 0.1) (layer "F.Cu") (net 588))
  (segment (start 144.720757 105.366743) (end 146.556742 105.366743) (width 0.1) (layer "F.Cu") (net 588))
  (segment (start 144.720757 105.366743) (end 144.7175 105.37) (width 0.1) (layer "F.Cu") (net 588))
  (segment (start 145.913485 104.37) (end 146.411328 103.872157) (width 0.11) (layer "F.Cu") (net 589))
  (segment (start 146.661328 103.622157) (end 146.661328 102.497157) (width 0.1) (layer "F.Cu") (net 589))
  (segment (start 147.036328 102.122157) (end 147.551328 102.122157) (width 0.1) (layer "F.Cu") (net 589))
  (segment (start 144.7175 104.37) (end 145.913485 104.37) (width 0.11) (layer "F.Cu") (net 589))
  (segment (start 146.661328 102.497157) (end 147.036328 102.122157) (width 0.1) (layer "F.Cu") (net 589))
  (segment (start 146.411328 103.872157) (end 146.661328 103.622157) (width 0.1) (layer "F.Cu") (net 589))
  (segment (start 142.53 103.1825) (end 142.53 100.738485) (width 0.127) (layer "F.Cu") (net 590))
  (segment (start 142.53 100.738485) (end 142.536328 100.732157) (width 0.127) (layer "F.Cu") (net 590))
  (segment (start 142 102.085829) (end 141.411328 101.497157) (width 0.1) (layer "F.Cu") (net 591))
  (segment (start 142 103.1525) (end 142.03 103.1825) (width 0.1) (layer "F.Cu") (net 591))
  (segment (start 142 102.085829) (end 142 103.1525) (width 0.1) (layer "F.Cu") (net 591))
  (segment (start 141.411328 101.497157) (end 141.411328 100.732157) (width 0.1) (layer "F.Cu") (net 591))
  (segment (start 137.5 103.1525) (end 137.53 103.1825) (width 0.1) (layer "F.Cu") (net 592))
  (segment (start 135.786328 102.247157) (end 135.411328 102.622157) (width 0.1) (layer "F.Cu") (net 592))
  (segment (start 137.5 102.585829) (end 137.5 103.1525) (width 0.1) (layer "F.Cu") (net 592))
  (segment (start 135.411328 102.622157) (end 134.396328 102.622157) (width 0.1) (layer "F.Cu") (net 592))
  (segment (start 137.5 102.585829) (end 137.161328 102.247157) (width 0.1) (layer "F.Cu") (net 592))
  (segment (start 137.161328 102.247157) (end 135.786328 102.247157) (width 0.1) (layer "F.Cu") (net 592))
  (segment (start 143.03 111.73) (end 143.03 111.0575) (width 0.1) (layer "F.Cu") (net 593))
  (segment (start 144.462143 112.297972) (end 143.597972 112.297972) (width 0.1) (layer "F.Cu") (net 593))
  (segment (start 147.551328 113.122157) (end 145.286328 113.122157) (width 0.1) (layer "F.Cu") (net 593))
  (segment (start 143.597972 112.297972) (end 143.03 111.73) (width 0.1) (layer "F.Cu") (net 593))
  (segment (start 145.286328 113.122157) (end 144.462143 112.297972) (width 0.1) (layer "F.Cu") (net 593))
  (segment (start 143.882157 111.982157) (end 143.53 111.63) (width 0.1) (layer "F.Cu") (net 594))
  (segment (start 143.882157 111.982157) (end 147.571328 111.982157) (width 0.1) (layer "F.Cu") (net 594))
  (segment (start 143.53 111.63) (end 143.53 111.0575) (width 0.1) (layer "F.Cu") (net 594))
  (segment (start 147.571328 110.907157) (end 146.992843 110.907157) (width 0.11) (layer "F.Cu") (net 595))
  (segment (start 144.4 111.7) (end 144.03 111.33) (width 0.11) (layer "F.Cu") (net 595))
  (segment (start 144.03 111.33) (end 144.03 111.0575) (width 0.11) (layer "F.Cu") (net 595))
  (segment (start 146.2 111.7) (end 144.4 111.7) (width 0.11) (layer "F.Cu") (net 595))
  (segment (start 146.992843 110.907157) (end 146.2 111.7) (width 0.11) (layer "F.Cu") (net 595))
  (segment (start 224.8855 115.731) (end 226.1785 115.731) (width 0.1) (layer "F.Cu") (net 596))
  (segment (start 233.9255 118.271) (end 235.282 118.271) (width 0.1) (layer "F.Cu") (net 597))
  (segment (start 146.411328 110.372157) (end 146.951328 109.832157) (width 0.1) (layer "F.Cu") (net 598))
  (segment (start 146.951328 109.832157) (end 147.571328 109.832157) (width 0.1) (layer "F.Cu") (net 598))
  (segment (start 146.411328 110.372157) (end 144.719657 110.372157) (width 0.1) (layer "F.Cu") (net 598))
  (segment (start 144.719657 110.372157) (end 144.7175 110.37) (width 0.1) (layer "F.Cu") (net 598))
  (segment (start 233.9255 117.001) (end 235.282 117.001) (width 0.1) (layer "F.Cu") (net 599))
  (segment (start 224.8855 118.271) (end 226.1785 118.271) (width 0.1) (layer "F.Cu") (net 600))
  (segment (start 118.956328 97.406328) (end 118.956328 97.880008) (width 0.15) (layer "F.Cu") (net 601))
  (segment (start 118.723477 96.795008) (end 118.723477 97.173477) (width 0.15) (layer "F.Cu") (net 601))
  (segment (start 118.723477 97.173477) (end 118.956328 97.406328) (width 0.15) (layer "F.Cu") (net 601))
  (segment (start 135.536328 105.372157) (end 136.840343 105.372157) (width 0.1) (layer "F.Cu") (net 602))
  (segment (start 135.536328 105.372157) (end 135.036328 105.872157) (width 0.1) (layer "F.Cu") (net 602))
  (segment (start 135.036328 105.872157) (end 134.396328 105.872157) (width 0.1) (layer "F.Cu") (net 602))
  (segment (start 136.840343 105.372157) (end 136.8425 105.37) (width 0.1) (layer "F.Cu") (net 602))
  (segment (start 140.436328 89.110008) (end 140.936328 89.610008) (width 0.2) (layer "F.Cu") (net 603))
  (segment (start 139.636328 89.110008) (end 140.436328 89.110008) (width 0.2) (layer "F.Cu") (net 603))
  (segment (start 175 130.25) (end 182.05 130.25) (width 0.2) (layer "F.Cu") (net 604))
  (segment (start 198.925 118.575) (end 198.925 120) (width 0.2) (layer "F.Cu") (net 604))
  (segment (start 203.55 113.95) (end 198.925 118.575) (width 0.2) (layer "F.Cu") (net 604))
  (segment (start 203.55 111.9) (end 203.55 113.95) (width 0.2) (layer "F.Cu") (net 604))
  (segment (start 182.05 130.25) (end 182.9 131.1) (width 0.2) (layer "F.Cu") (net 604))
  (via (at 195.7 131.3) (size 0.5) (drill 0.2) (layers "F.Cu" "B.Cu") (free) (net 604))
  (via (at 195.7 129.5) (size 0.5) (drill 0.2) (layers "F.Cu" "B.Cu") (free) (net 604))
  (via (at 196.3 131.3) (size 0.5) (drill 0.2) (layers "F.Cu" "B.Cu") (free) (net 604))
  (via (at 195.7 130.7) (size 0.5) (drill 0.2) (layers "F.Cu" "B.Cu") (free) (net 604))
  (via (at 196.3 130.7) (size 0.5) (drill 0.2) (layers "F.Cu" "B.Cu") (free) (net 604))
  (via (at 182.9 131.1) (size 0.5) (drill 0.2) (layers "F.Cu" "B.Cu") (net 604))
  (via (at 195.7 130.1) (size 0.5) (drill 0.2) (layers "F.Cu" "B.Cu") (free) (net 604))
  (via (at 198.925 120) (size 0.5) (drill 0.2) (layers "F.Cu" "B.Cu") (net 604))
  (via (at 175 130.25) (size 0.5) (drill 0.2) (layers "F.Cu" "B.Cu") (net 604))
  (via (at 196.3 130.1) (size 0.5) (drill 0.2) (layers "F.Cu" "B.Cu") (free) (net 604))
  (via (at 196.3 129.5) (size 0.5) (drill 0.2) (layers "F.Cu" "B.Cu") (free) (net 604))
  (segment (start 172.3 132.95) (end 175 130.25) (width 0.2) (layer "B.Cu") (net 604))
  (segment (start 175 130.25) (end 175.64 130.25) (width 0.2) (layer "B.Cu") (net 604))
  (segment (start 198.875 120.05) (end 198.925 120) (width 0.1) (layer "B.Cu") (net 604))
  (segment (start 175.64 130.25) (end 175.765 130.125) (width 0.2) (layer "B.Cu") (net 604))
  (segment (start 172.3 132.95) (end 171.55 132.95) (width 0.2) (layer "B.Cu") (net 604))
  (segment (start 197.6 120.05) (end 198.875 120.05) (width 0.15) (layer "B.Cu") (net 604))
  (via (at 181.81 118.375) (size 0.5) (drill 0.2) (layers "F.Cu" "B.Cu") (net 605))
  (via (at 182.7 117.8) (size 0.5) (drill 0.2) (layers "F.Cu" "B.Cu") (net 605))
  (via (at 182.4 118.375) (size 0.5) (drill 0.2) (layers "F.Cu" "B.Cu") (net 605))
  (via (at 182.1 117.8) (size 0.5) (drill 0.2) (layers "F.Cu" "B.Cu") (net 605))
  (segment (start 172.45 121.95) (end 170.713035 121.95) (width 0.4) (layer "In2.Cu") (net 605))
  (segment (start 170.713035 121.95) (end 169.466638 123.196397) (width 0.4) (layer "In2.Cu") (net 605))
  (segment (start 181.81 118.375) (end 176.025 118.375) (width 0.4) (layer "In2.Cu") (net 605))
  (segment (start 169.466638 123.196397) (end 159.785 123.196397) (width 0.4) (layer "In2.Cu") (net 605))
  (segment (start 176.025 118.375) (end 172.45 121.95) (width 0.4) (layer "In2.Cu") (net 605))
  (segment (start 180.76 118.405) (end 181.78 118.405) (width 0.4) (layer "B.Cu") (net 605))
  (segment (start 181.78 118.405) (end 181.81 118.375) (width 0.4) (layer "B.Cu") (net 605))
  (via (at 182.35 121.1) (size 0.5) (drill 0.2) (layers "F.Cu" "B.Cu") (net 606))
  (via (at 182.9 121.1) (size 0.5) (drill 0.2) (layers "F.Cu" "B.Cu") (net 606))
  (via (at 181.81 120.975) (size 0.5) (drill 0.2) (layers "F.Cu" "B.Cu") (net 606))
  (segment (start 175.8 126.1) (end 172.85 129.05) (width 0.4) (layer "In2.Cu") (net 606))
  (segment (start 166.918603 129.05) (end 162.325 124.456397) (width 0.4) (layer "In2.Cu") (net 606))
  (segment (start 181.81 120.975) (end 181.225 120.975) (width 0.4) (layer "In2.Cu") (net 606))
  (segment (start 181.225 120.975) (end 181.475 120.975) (width 0.4) (layer "In2.Cu") (net 606))
  (segment (start 179.275 120.975) (end 175.8 124.45) (width 0.4) (layer "In2.Cu") (net 606))
  (segment (start 181.225 120.975) (end 179.275 120.975) (width 0.4) (layer "In2.Cu") (net 606))
  (segment (start 172.85 129.05) (end 166.918603 129.05) (width 0.4) (layer "In2.Cu") (net 606))
  (segment (start 181.81 120.975) (end 181.81 121.01) (width 0.4) (layer "In2.Cu") (net 606))
  (segment (start 175.8 124.45) (end 175.8 126.1) (width 0.4) (layer "In2.Cu") (net 606))
  (segment (start 180.76 120.945) (end 181.78 120.945) (width 0.4) (layer "B.Cu") (net 606))
  (segment (start 181.78 120.945) (end 181.81 120.975) (width 0.4) (layer "B.Cu") (net 606))
  (segment (start 175.36 120.97) (end 175.36 124.49) (width 0.4) (layer "B.Cu") (net 607))
  (segment (start 174.075 125.775) (end 172.916347 125.775) (width 0.4) (layer "B.Cu") (net 607))
  (segment (start 171.597744 124.456397) (end 168.675 124.456397) (width 0.4) (layer "B.Cu") (net 607))
  (segment (start 172.916347 125.775) (end 171.597744 124.456397) (width 0.4) (layer "B.Cu") (net 607))
  (segment (start 175.36 124.49) (end 174.075 125.775) (width 0.4) (layer "B.Cu") (net 607))
  (segment (start 174.37 118.43) (end 175.36 118.43) (width 0.4) (layer "B.Cu") (net 608))
  (segment (start 173.75 119.05) (end 174.37 118.43) (width 0.4) (layer "B.Cu") (net 608))
  (segment (start 173.099302 122.300698) (end 173.75 121.65) (width 0.4) (layer "B.Cu") (net 608))
  (segment (start 172.100698 122.300698) (end 173.099302 122.300698) (width 0.4) (layer "B.Cu") (net 608))
  (segment (start 171.215 123.186397) (end 172.100698 122.300698) (width 0.4) (layer "B.Cu") (net 608))
  (segment (start 173.75 121.65) (end 173.75 119.05) (width 0.4) (layer "B.Cu") (net 608))
  (segment (start 201.9 112.05) (end 202.05 111.9) (width 0.2) (layer "F.Cu") (net 609))
  (segment (start 201.9 113.215) (end 201.9 112.05) (width 0.2) (layer "F.Cu") (net 609))
  (segment (start 180.35 125.155) (end 179.995 124.8) (width 0.2) (layer "B.Cu") (net 610))
  (segment (start 180.35 126.245) (end 180.35 125.155) (width 0.2) (layer "B.Cu") (net 610))
  (segment (start 181 124.81) (end 181.21 124.6) (width 0.2) (layer "B.Cu") (net 611))
  (segment (start 181 126.245) (end 181 124.81) (width 0.2) (layer "B.Cu") (net 611))
  (segment (start 184.55 128.605) (end 184.8 128.855) (width 0.2) (layer "B.Cu") (net 612))
  (segment (start 183.36 128.605) (end 184.55 128.605) (width 0.2) (layer "B.Cu") (net 612))
  (segment (start 119.604 100.64) (end 119.604 101.42) (width 0.15) (layer "F.Cu") (net 613))
  (segment (start 122.012385 102.247157) (end 121.551328 102.247157) (width 0.2) (layer "F.Cu") (net 613))
  (segment (start 122.056828 102.202714) (end 122.012385 102.247157) (width 0.2) (layer "F.Cu") (net 613))
  (via (at 119.604 101.42) (size 0.5) (drill 0.2) (layers "F.Cu" "B.Cu") (net 613))
  (via (at 122.056828 102.202714) (size 0.5) (drill 0.2) (layers "F.Cu" "B.Cu") (net 613))
  (segment (start 120.795 101.42) (end 119.604 101.42) (width 0.2) (layer "B.Cu") (net 613))
  (segment (start 121.577714 102.202714) (end 120.795 101.42) (width 0.2) (layer "B.Cu") (net 613))
  (segment (start 122.056828 102.202714) (end 121.577714 102.202714) (width 0.2) (layer "B.Cu") (net 613))
  (segment (start 170.15 134.5) (end 175.75 134.5) (width 0.2) (layer "B.Cu") (net 615))
  (segment (start 177.09 133.16) (end 177.145 133.105) (width 0.2) (layer "B.Cu") (net 615))
  (segment (start 167.625 134.16) (end 169.81 134.16) (width 0.2) (layer "B.Cu") (net 615))
  (segment (start 175.75 134.5) (end 177.09 133.16) (width 0.2) (layer "B.Cu") (net 615))
  (segment (start 179.585 133.105) (end 179.59 133.1) (width 0.2) (layer "B.Cu") (net 615))
  (segment (start 177.145 133.105) (end 179.585 133.105) (width 0.2) (layer "B.Cu") (net 615))
  (segment (start 169.81 134.16) (end 170.15 134.5) (width 0.2) (layer "B.Cu") (net 615))
  (segment (start 117.459171 99.607157) (end 117.021328 99.607157) (width 0.15) (layer "F.Cu") (net 616))
  (segment (start 117.536328 99.53) (end 117.459171 99.607157) (width 0.15) (layer "F.Cu") (net 616))
  (segment (start 118.204 99.53) (end 117.536328 99.53) (width 0.15) (layer "F.Cu") (net 616))
  (segment (start 116.707157 99.607157) (end 116.411328 99.607157) (width 0.15) (layer "F.Cu") (net 616))
  (segment (start 117.021328 99.607157) (end 116.707157 99.607157) (width 0.15) (layer "F.Cu") (net 616))
  (segment (start 116.707157 99.607157) (end 116.507157 99.607157) (width 0.15) (layer "F.Cu") (net 616))
  (segment (start 184.41 127.605) (end 184.06 127.955) (width 0.2) (layer "B.Cu") (net 617))
  (segment (start 183.36 127.955) (end 184.06 127.955) (width 0.2) (layer "B.Cu") (net 617))
  (segment (start 185.165 127.605) (end 184.41 127.605) (width 0.2) (layer "B.Cu") (net 617))
  (segment (start 183.85 127.305) (end 184.8 126.355) (width 0.2) (layer "B.Cu") (net 618))
  (segment (start 183.36 127.305) (end 183.85 127.305) (width 0.2) (layer "B.Cu") (net 618))
  (segment (start 176.889767 128.259767) (end 176.735 128.105) (width 0.2) (layer "B.Cu") (net 619))
  (segment (start 177.140233 128.259767) (end 176.889767 128.259767) (width 0.2) (layer "B.Cu") (net 619))
  (segment (start 178.64 128.605) (end 177.485466 128.605) (width 0.2) (layer "B.Cu") (net 619))
  (segment (start 177.485466 128.605) (end 177.140233 128.259767) (width 0.2) (layer "B.Cu") (net 619))
  (segment (start 181 132.7) (end 180.8 132.9) (width 0.2) (layer "B.Cu") (net 620))
  (segment (start 181 130.965) (end 181 132.7) (width 0.2) (layer "B.Cu") (net 620))
  (segment (start 180.56 133.1) (end 180.6 133.1) (width 0.127) (layer "B.Cu") (net 620))
  (segment (start 180.6 133.1) (end 180.8 132.9) (width 0.127) (layer "B.Cu") (net 620))
  (segment (start 176.735 130.125) (end 177.25 130.125) (width 0.2) (layer "B.Cu") (net 621))
  (segment (start 177.25 130.125) (end 177.47 129.905) (width 0.2) (layer "B.Cu") (net 621))
  (segment (start 178.64 129.905) (end 177.47 129.905) (width 0.2) (layer "B.Cu") (net 621))
  (segment (start 176.885 129.255) (end 176.735 129.105) (width 0.2) (layer "B.Cu") (net 622))
  (segment (start 178.64 129.255) (end 176.885 129.255) (width 0.2) (layer "B.Cu") (net 622))
  (segment (start 152.499328 115.187008) (end 153.099328 114.587008) (width 0.2) (layer "F.Cu") (net 624))
  (segment (start 152.499328 115.827008) (end 152.499328 115.187008) (width 0.2) (layer "F.Cu") (net 624))
  (segment (start 153.449328 115.287008) (end 154.149328 114.587008) (width 0.2) (layer "F.Cu") (net 625))
  (segment (start 153.449328 115.827008) (end 153.449328 115.287008) (width 0.2) (layer "F.Cu") (net 625))
  (segment (start 154.149328 114.587008) (end 155.149328 114.587008) (width 0.2) (layer "F.Cu") (net 625))
  (segment (start 239.285 124.285) (end 239.3 124.3) (width 0.2) (layer "F.Cu") (net 626))
  (segment (start 238.3 124.285) (end 239.285 124.285) (width 0.2) (layer "F.Cu") (net 626))
  (via (at 239.3 124.3) (size 0.5) (drill 0.2) (layers "F.Cu" "B.Cu") (net 626))
  (via (at 159.6 134.2) (size 0.5) (drill 0.2) (layers "F.Cu" "B.Cu") (net 626))
  (segment (start 191.8 132) (end 216.2 132) (width 0.2) (layer "In2.Cu") (net 626))
  (segment (start 176 130.3) (end 190.1 130.3) (width 0.2) (layer "In2.Cu") (net 626))
  (segment (start 159.6 134.2) (end 172.1 134.2) (width 0.2) (layer "In2.Cu") (net 626))
  (segment (start 190.1 130.3) (end 191.8 132) (width 0.2) (layer "In2.Cu") (net 626))
  (segment (start 216.2 132) (end 220.7 127.5) (width 0.2) (layer "In2.Cu") (net 626))
  (segment (start 172.1 134.2) (end 176 130.3) (width 0.2) (layer "In2.Cu") (net 626))
  (segment (start 220.7 127.5) (end 237.8 127.5) (width 0.2) (layer "In2.Cu") (net 626))
  (segment (start 239.3 126) (end 239.3 124.3) (width 0.2) (layer "In2.Cu") (net 626))
  (segment (start 237.8 127.5) (end 239.3 126) (width 0.2) (layer "In2.Cu") (net 626))
  (segment (start 121.2 131.2) (end 121.2 125.7) (width 0.2) (layer "B.Cu") (net 626))
  (segment (start 124.1 134.1) (end 121.2 131.2) (width 0.2) (layer "B.Cu") (net 626))
  (segment (start 119.8 124.3) (end 118.35 124.3) (width 0.2) (layer "B.Cu") (net 626))
  (segment (start 153.9 132.3) (end 144.1 132.3) (width 0.2) (layer "B.Cu") (net 626))
  (segment (start 144.1 132.3) (end 142.3 134.1) (width 0.2) (layer "B.Cu") (net 626))
  (segment (start 142.3 134.1) (end 124.1 134.1) (width 0.2) (layer "B.Cu") (net 626))
  (segment (start 161.375 134.16) (end 155.76 134.16) (width 0.2) (layer "B.Cu") (net 626))
  (segment (start 155.76 134.16) (end 153.9 132.3) (width 0.2) (layer "B.Cu") (net 626))
  (segment (start 121.2 125.7) (end 119.8 124.3) (width 0.2) (layer "B.Cu") (net 626))
  (segment (start 170.09 132.89) (end 170.15 132.95) (width 0.2) (layer "B.Cu") (net 627))
  (segment (start 167.625 132.89) (end 170.09 132.89) (width 0.2) (layer "B.Cu") (net 627))
  (segment (start 161.375 132.89) (end 159.565 132.89) (width 0.2) (layer "B.Cu") (net 628))
  (segment (start 159.565 132.89) (end 159.45 132.775) (width 0.2) (layer "B.Cu") (net 628))
  (segment (start 183.89 129.255) (end 184.505 129.87) (width 0.2) (layer "B.Cu") (net 629))
  (segment (start 183.36 129.255) (end 183.89 129.255) (width 0.2) (layer "B.Cu") (net 629))
  (segment (start 185.135 129.87) (end 185.165 129.9) (width 0.2) (layer "B.Cu") (net 629))
  (segment (start 184.505 129.87) (end 185.135 129.87) (width 0.2) (layer "B.Cu") (net 629))
  (segment (start 156.05 109.35) (end 155.812501 109.587499) (width 0.1) (layer "F.Cu") (net 630))
  (segment (start 155.891339 109.938839) (end 155.8125 109.86) (width 0.1) (layer "F.Cu") (net 630))
  (segment (start 155.812501 109.587499) (end 155.8125 109.86) (width 0.1) (layer "F.Cu") (net 630))
  (segment (start 156.014499 109.938839) (end 155.891339 109.938839) (width 0.1) (layer "F.Cu") (net 630))
  (via (at 156.014499 109.938839) (size 0.5) (drill 0.2) (layers "F.Cu" "B.Cu") (net 630))
  (segment (start 155.8145 109.73884) (end 156.014499 109.938839) (width 0.1) (layer "B.Cu") (net 630))
  (segment (start 155.914499 109.145499) (end 155.914499 109.430499) (width 0.1) (layer "B.Cu") (net 630))
  (segment (start 158.707134 114.775) (end 160.212134 114.775) (width 0.1) (layer "B.Cu") (net 630))
  (segment (start 161.15 118.912134) (end 161.055 119.007134) (width 0.1) (layer "B.Cu") (net 630))
  (segment (start 161.15 115.712866) (end 161.15 118.912134) (width 0.1) (layer "B.Cu") (net 630))
  (segment (start 156.014499 109.938839) (end 155.8145 110.138838) (width 0.1) (layer "B.Cu") (net 630))
  (segment (start 155.8145 110.138838) (end 155.814499 111.882365) (width 0.1) (layer "B.Cu") (net 630))
  (segment (start 161.055 119.007134) (end 161.055 120.656397) (width 0.1) (layer "B.Cu") (net 630))
  (segment (start 155.914499 109.430499) (end 155.814499 109.530499) (width 0.1) (layer "B.Cu") (net 630))
  (segment (start 155.814499 109.530499) (end 155.8145 109.73884) (width 0.1) (layer "B.Cu") (net 630))
  (segment (start 160.212134 114.775) (end 161.15 115.712866) (width 0.1) (layer "B.Cu") (net 630))
  (segment (start 155.814499 111.882365) (end 158.707134 114.775) (width 0.1) (layer "B.Cu") (net 630))
  (segment (start 155.433661 109.938839) (end 155.5125 109.86) (width 0.1) (layer "F.Cu") (net 631))
  (segment (start 155.512499 109.587499) (end 155.5125 109.86) (width 0.1) (layer "F.Cu") (net 631))
  (segment (start 155.275 109.35) (end 155.512499 109.587499) (width 0.1) (layer "F.Cu") (net 631))
  (segment (start 155.314499 109.938839) (end 155.433661 109.938839) (width 0.1) (layer "F.Cu") (net 631))
  (via (at 155.314499 109.938839) (size 0.5) (drill 0.2) (layers "F.Cu" "B.Cu") (net 631))
  (segment (start 155.5145 109.738838) (end 155.314499 109.938839) (width 0.1) (layer "B.Cu") (net 631))
  (segment (start 160.518603 118.85) (end 160.8 118.85) (width 0.1) (layer "B.Cu") (net 631))
  (segment (start 160.85 118.8) (end 160.85 117.4) (width 0.1) (layer "B.Cu") (net 631))
  (segment (start 158.582866 115.075) (end 155.514499 112.006633) (width 0.1) (layer "B.Cu") (net 631))
  (segment (start 160.65 117.2) (end 160.625234 117.2) (width 0.1) (layer "B.Cu") (net 631))
  (segment (start 155.514498 110.138838) (end 155.314499 109.938839) (width 0.1) (layer "B.Cu") (net 631))
  (segment (start 155.4145 109.430499) (end 155.5145 109.530499) (width 0.1) (layer "B.Cu") (net 631))
  (segment (start 159.785 118.116397) (end 160.518603 118.85) (width 0.1) (layer "B.Cu") (net 631))
  (segment (start 160.625234 116.8) (end 160.65 116.8) (width 0.1) (layer "B.Cu") (net 631))
  (segment (start 160.087866 115.075) (end 158.582866 115.075) (width 0.1) (layer "B.Cu") (net 631))
  (segment (start 160.8 118.85) (end 160.85 118.8) (width 0.1) (layer "B.Cu") (net 631))
  (segment (start 160.85 115.837134) (end 160.087866 115.075) (width 0.1) (layer "B.Cu") (net 631))
  (segment (start 155.4145 109.145499) (end 155.4145 109.430499) (width 0.1) (layer "B.Cu") (net 631))
  (segment (start 155.514499 112.006633) (end 155.514498 110.138838) (width 0.1) (layer "B.Cu") (net 631))
  (segment (start 155.5145 109.530499) (end 155.5145 109.738838) (width 0.1) (layer "B.Cu") (net 631))
  (segment (start 160.85 116.6) (end 160.85 115.837134) (width 0.1) (layer "B.Cu") (net 631))
  (arc (start 160.65 116.8) (mid 160.791421 116.741421) (end 160.85 116.6) (width 0.1) (layer "B.Cu") (net 631))
  (arc (start 160.425234 117) (mid 160.483813 116.858579) (end 160.625234 116.8) (width 0.1) (layer "B.Cu") (net 631))
  (arc (start 160.625234 117.2) (mid 160.483813 117.141421) (end 160.425234 117) (width 0.1) (layer "B.Cu") (net 631))
  (arc (start 160.85 117.4) (mid 160.791421 117.258579) (end 160.65 117.2) (width 0.1) (layer "B.Cu") (net 631))
  (segment (start 193.636328 101.060008) (end 193.136328 100.560008) (width 0.127) (layer "F.Cu") (net 632))
  (via blind (at 193.636328 101.060008) (size 0.5) (drill 0.2) (layers "F.Cu" "In2.Cu") (net 632))
  (via (at 256.08 123.19) (size 0.5) (drill 0.2) (layers "F.Cu" "B.Cu") (net 632))
  (segment (start 194.368077 101.631016) (end 195.092971 101.631016) (width 0.082) (layer "In2.Cu") (net 632))
  (segment (start 249.471219 118.528) (end 252.428781 118.528) (width 0.13) (layer "In2.Cu") (net 632))
  (segment (start 242.636417 116.927793) (end 242.897207 117.188583) (width 0.13) (layer "In2.Cu") (net 632))
  (segment (start 237.597 106.520483) (end 237.597 109.033368) (width 0.13) (layer "In2.Cu") (net 632))
  (segment (start 243.23379 117.328) (end 243.828781 117.328) (width 0.13) (layer "In2.Cu") (net 632))
  (segment (start 234.544996 102.261372) (end 235.700554 103.41693) (width 0.13) (layer "In2.Cu") (net 632))
  (segment (start 234.347 101.020483) (end 234.347 101.783368) (width 0.13) (layer "In2.Cu") (net 632))
  (segment (start 243.970203 117.386579) (end 244.051496 117.467872) (width 0.13) (layer "In2.Cu") (net 632))
  (segment (start 207.670483 99.778) (end 233.104517 99.778) (width 0.13) (layer "In2.Cu") (net 632))
  (segment (start 244.317368 117.578) (end 245.954517 117.578) (width 0.13) (layer "In2.Cu") (net 632))
  (segment (start 239.347 111.270483) (end 239.347 112.533368) (width 0.13) (layer "In2.Cu") (net 632))
  (segment (start 249.073504 118.842872) (end 249.329797 118.586579) (width 0.13) (layer "In2.Cu") (net 632))
  (segment (start 253.899492 122.090868) (end 254.709496 122.900872) (width 0.13) (layer "In2.Cu") (net 632))
  (segment (start 235.847 103.770483) (end 235.847 104.283368) (width 0.13) (layer "In2.Cu") (net 632))
  (segment (start 233.458071 99.924447) (end 234.200554 100.66693) (width 0.13) (layer "In2.Cu") (net 632))
  (segment (start 198.137161 102.628738) (end 204.33263 102.628738) (width 0.13) (layer "In2.Cu") (net 632))
  (segment (start 194.050328 101.211765) (end 194.050328 101.313267) (width 0.082) (layer "In2.Cu") (net 632))
  (segment (start 193.636328 101.060008) (end 193.898571 101.060008) (width 0.082) (layer "In2.Cu") (net 632))
  (segment (start 194.105978 101.447618) (end 194.233727 101.575367) (width 0.082) (layer "In2.Cu") (net 632))
  (segment (start 252.747 118.846219) (end 252.747 121.24121) (width 0.13) (layer "In2.Cu") (net 632))
  (segment (start 196.143077 102.561) (end 197.98658 102.561) (width 0.082) (layer "In2.Cu") (net 632))
  (segment (start 204.810634 102.430742) (end 207.31693 99.924446) (width 0.13) (layer "In2.Cu") (net 632))
  (segment (start 254.975368 123.011) (end 255.818157 123.011) (width 0.13) (layer "In2.Cu") (net 632))
  (segment (start 246.308071 117.724447) (end 247.338628 118.755004) (width 0.13) (layer "In2.Cu") (net 632))
  (segment (start 237.794996 109.511372) (end 239.200554 110.91693) (width 0.13) (layer "In2.Cu") (net 632))
  (segment (start 239.544996 113.011372) (end 242.350554 115.81693) (width 0.13) (layer "In2.Cu") (net 632))
  (segment (start 198.128002 102.619579) (end 198.137161 102.628738) (width 0.082) (layer "In2.Cu") (net 632))
  (segment (start 195.163682 101.660306) (end 196.008727 102.505351) (width 0.082) (layer "In2.Cu") (net 632))
  (segment (start 242.497 116.170483) (end 242.497 116.59121) (width 0.13) (layer "In2.Cu") (net 632))
  (segment (start 252.886417 121.577793) (end 253.172207 121.863583) (width 0.13) (layer "In2.Cu") (net 632))
  (segment (start 253.50879 122.003) (end 253.68736 122.003) (width 0.13) (layer "In2.Cu") (net 632))
  (segment (start 193.969282 101.089298) (end 194.021039 101.141055) (width 0.082) (layer "In2.Cu") (net 632))
  (segment (start 236.044996 104.761372) (end 237.450554 106.16693) (width 0.13) (layer "In2.Cu") (net 632))
  (segment (start 252.570202 118.586578) (end 252.688421 118.704797) (width 0.13) (layer "In2.Cu") (net 632))
  (segment (start 255.959578 123.069578) (end 256.08 123.19) (width 0.13) (layer "In2.Cu") (net 632))
  (segment (start 247.816632 118.953) (end 248.807632 118.953) (width 0.13) (layer "In2.Cu") (net 632))
  (arc (start 194.050328 101.211765) (mid 194.042716 101.173497) (end 194.021039 101.141055) (width 0.082) (layer "In2.Cu") (net 632))
  (arc (start 244.317368 117.578) (mid 244.173479 117.549379) (end 244.051496 117.467872) (width 0.13) (layer "In2.Cu") (net 632))
  (arc (start 242.636417 116.927793) (mid 242.533233 116.773367) (end 242.497 116.59121) (width 0.13) (layer "In2.Cu") (net 632))
  (arc (start 252.428781 118.528) (mid 252.505317 118.543224) (end 252.570202 118.586578) (width 0.13) (layer "In2.Cu") (net 632))
  (arc (start 207.31693 99.924446) (mid 207.479142 99.81606) (end 207.670483 99.778) (width 0.13) (layer "In2.Cu") (net 632))
  (arc (start 235.700554 103.41693) (mid 235.80894 103.579142) (end 235.847 103.770483) (width 0.13) (layer "In2.Cu") (net 632))
  (arc (start 195.092971 101.631016) (mid 195.13124 101.638628) (end 195.163682 101.660306) (width 0.082) (layer "In2.Cu") (net 632))
  (arc (start 242.897207 117.188583) (mid 243.051633 117.291767) (end 243.23379 117.328) (width 0.13) (layer "In2.Cu") (net 632))
  (arc (start 239.200554 110.91693) (mid 239.30894 111.079142) (end 239.347 111.270483) (width 0.13) (layer "In2.Cu") (net 632))
  (arc (start 234.347 101.783368) (mid 234.398457 102.042062) (end 234.544996 102.261372) (width 0.13) (layer "In2.Cu") (net 632))
  (arc (start 252.747 121.24121) (mid 252.783233 121.423367) (end 252.886417 121.577793) (width 0.13) (layer "In2.Cu") (net 632))
  (arc (start 197.98658 102.561) (mid 198.063117 102.576224) (end 198.128002 102.619579) (width 0.082) (layer "In2.Cu") (net 632))
  (arc (start 252.688421 118.704797) (mid 252.731776 118.769682) (end 252.747 118.846219) (width 0.13) (layer "In2.Cu") (net 632))
  (arc (start 253.899492 122.090868) (mid 253.802165 122.025836) (end 253.68736 122.003) (width 0.13) (layer "In2.Cu") (net 632))
  (arc (start 196.143077 102.561) (mid 196.070367 102.546537) (end 196.008727 102.505351) (width 0.082) (layer "In2.Cu") (net 632))
  (arc (start 234.200554 100.66693) (mid 234.30894 100.829142) (end 234.347 101.020483) (width 0.13) (layer "In2.Cu") (net 632))
  (arc (start 248.807632 118.953) (mid 248.951521 118.924379) (end 249.073504 118.842872) (width 0.13) (layer "In2.Cu") (net 632))
  (arc (start 194.050328 101.313267) (mid 194.064791 101.385977) (end 194.105978 101.447618) (width 0.082) (layer "In2.Cu") (net 632))
  (arc (start 237.597 109.033368) (mid 237.648458 109.292062) (end 237.794996 109.511372) (width 0.13) (layer "In2.Cu") (net 632))
  (arc (start 193.898571 101.060008) (mid 193.93684 101.06762) (end 193.969282 101.089298) (width 0.082) (layer "In2.Cu") (net 632))
  (arc (start 247.338628 118.755004) (mid 247.557938 118.901542) (end 247.816632 118.953) (width 0.13) (layer "In2.Cu") (net 632))
  (arc (start 246.308071 117.724447) (mid 246.145859 117.61606) (end 245.954517 117.578) (width 0.13) (layer "In2.Cu") (net 632))
  (arc (start 235.847 104.283368) (mid 235.898458 104.542062) (end 236.044996 104.761372) (width 0.13) (layer "In2.Cu") (net 632))
  (arc (start 243.828781 117.328) (mid 243.905318 117.343224) (end 243.970203 117.386579) (width 0.13) (layer "In2.Cu") (net 632))
  (arc (start 242.497 116.170483) (mid 242.45894 115.979142) (end 242.350554 115.81693) (width 0.13) (layer "In2.Cu") (net 632))
  (arc (start 204.33263 102.628738) (mid 204.591324 102.57728) (end 204.810634 102.430742) (width 0.13) (layer "In2.Cu") (net 632))
  (arc (start 255.818157 123.011) (mid 255.894693 123.026224) (end 255.959578 123.069578) (width 0.13) (layer "In2.Cu") (net 632))
  (arc (start 249.329797 118.586579) (mid 249.394682 118.543224) (end 249.471219 118.528) (width 0.13) (layer "In2.Cu") (net 632))
  (arc (start 254.709496 122.900872) (mid 254.831479 122.982379) (end 254.975368 123.011) (width 0.13) (layer "In2.Cu") (net 632))
  (arc (start 233.104517 99.778) (mid 233.295859 99.81606) (end 233.458071 99.924447) (width 0.13) (layer "In2.Cu") (net 632))
  (arc (start 237.450554 106.16693) (mid 237.55894 106.329142) (end 237.597 106.520483) (width 0.13) (layer "In2.Cu") (net 632))
  (arc (start 253.172207 121.863583) (mid 253.326633 121.966767) (end 253.50879 122.003) (width 0.13) (layer "In2.Cu") (net 632))
  (arc (start 239.347 112.533368) (mid 239.398457 112.792062) (end 239.544996 113.011372) (width 0.13) (layer "In2.Cu") (net 632))
  (arc (start 194.368077 101.631016) (mid 194.295367 101.616553) (end 194.233727 101.575367) (width 0.082) (layer "In2.Cu") (net 632))
  (segment (start 256.685079 123.060079) (end 256.685711 123.060711) (width 0.122) (layer "B.Cu") (net 632))
  (segment (start 256.08 123.19) (end 256.209922 123.060078) (width 0.122) (layer "B.Cu") (net 632))
  (segment (start 256.351343 123.0015) (end 256.543657 123.0015) (width 0.122) (layer "B.Cu") (net 632))
  (segment (start 256.715 123.131421) (end 256.715 123.495) (width 0.122) (layer "B.Cu") (net 632))
  (arc (start 256.715 123.131421) (mid 256.707388 123.093153) (end 256.685711 123.060711) (width 0.122) (layer "B.Cu") (net 632))
  (arc (start 256.543657 123.0015) (mid 256.620194 123.016724) (end 256.685079 123.060079) (width 0.122) (layer "B.Cu") (net 632))
  (arc (start 256.351343 123.0015) (mid 256.274807 123.016724) (end 256.209922 123.060078) (width 0.122) (layer "B.Cu") (net 632))
  (segment (start 194.636328 101.060008) (end 194.136328 100.560008) (width 0.127) (layer "F.Cu") (net 633))
  (via blind (at 194.636328 101.060008) (size 0.5) (drill 0.2) (layers "F.Cu" "In2.Cu") (net 633))
  (via (at 256.08 122.526) (size 0.5) (drill 0.2) (layers "F.Cu" "B.Cu") (net 633))
  (segment (start 195.84163 101.84697) (end 195.84163 101.846971) (width 0.082) (layer "In2.Cu") (net 633))
  (segment (start 195.84163 101.846971) (end 195.823678 101.864922) (width 0.082) (layer "In2.Cu") (net 633))
  (segment (start 195.611546 101.864922) (end 195.611547 101.864923) (width 0.082) (layer "In2.Cu") (net 633))
  (segment (start 255.959578 122.646422) (end 256.08 122.526) (width 0.13) (layer "In2.Cu") (net 633))
  (segment (start 253.140868 121.399492) (end 253.350508 121.609132) (width 0.13) (layer "In2.Cu") (net 633))
  (segment (start 195.611547 101.864923) (end 195.26129 101.514666) (width 0.082) (layer "In2.Cu") (net 633))
  (segment (start 244.371219 117.272) (end 246.008368 117.272) (width 0.13) (layer "In2.Cu") (net 633))
  (segment (start 196.035812 102.077055) (end 196.053763 102.059103) (width 0.082) (layer "In2.Cu") (net 633))
  (segment (start 194.251617 101.168399) (end 194.330718 101.089298) (width 0.082) (layer "In2.Cu") (net 633))
  (segment (start 233.636372 99.669996) (end 234.455004 100.488628) (width 0.13) (layer "In2.Cu") (net 633))
  (segment (start 207.616632 99.472) (end 233.158368 99.472) (width 0.13) (layer "In2.Cu") (net 633))
  (segment (start 253.56264 121.697) (end 253.74121 121.697) (width 0.13) (layer "In2.Cu") (net 633))
  (segment (start 237.903 106.466218) (end 237.903 108.979517) (width 0.13) (layer "In2.Cu") (net 633))
  (segment (start 244.148504 117.132128) (end 244.229798 117.213422) (width 0.13) (layer "In2.Cu") (net 633))
  (segment (start 194.331335 101.429727) (end 194.251618 101.35001) (width 0.082) (layer "In2.Cu") (net 633))
  (segment (start 236.153 103.716632) (end 236.153 104.229517) (width 0.13) (layer "In2.Cu") (net 633))
  (segment (start 249.417368 118.222) (end 252.482632 118.222) (width 0.13) (layer "In2.Cu") (net 633))
  (segment (start 238.049447 109.333071) (end 239.455297 110.738921) (width 0.13) (layer "In2.Cu") (net 633))
  (segment (start 252.748504 118.332128) (end 252.942872 118.526496) (width 0.13) (layer "In2.Cu") (net 633))
  (segment (start 246.486372 117.469996) (end 247.51693 118.500554) (width 0.13) (layer "In2.Cu") (net 633))
  (segment (start 254.077793 121.836417) (end 254.887797 122.646421) (width 0.13) (layer "In2.Cu") (net 633))
  (segment (start 196.106335 102.359711) (end 196.035812 102.289188) (width 0.082) (layer "In2.Cu") (net 633))
  (segment (start 234.653 100.966632) (end 234.653 101.729517) (width 0.13) (layer "In2.Cu") (net 633))
  (segment (start 198.137161 102.322738) (end 204.278779 102.322738) (width 0.13) (layer "In2.Cu") (net 633))
  (segment (start 195.126939 101.459016) (end 194.402045 101.459016) (width 0.082) (layer "In2.Cu") (net 633))
  (segment (start 194.401429 101.060008) (end 194.636328 101.060008) (width 0.082) (layer "In2.Cu") (net 633))
  (segment (start 194.222328 101.279299) (end 194.222328 101.239109) (width 0.082) (layer "In2.Cu") (net 633))
  (segment (start 247.870483 118.647) (end 248.753781 118.647) (width 0.13) (layer "In2.Cu") (net 633))
  (segment (start 239.799447 112.833071) (end 242.605004 115.638628) (width 0.13) (layer "In2.Cu") (net 633))
  (segment (start 242.803 116.116632) (end 242.803 116.53736) (width 0.13) (layer "In2.Cu") (net 633))
  (segment (start 243.28764 117.022) (end 243.882632 117.022) (width 0.13) (layer "In2.Cu") (net 633))
  (segment (start 239.653 111.216218) (end 239.653 112.479517) (width 0.13) (layer "In2.Cu") (net 633))
  (segment (start 196.035811 102.077055) (end 196.035812 102.077055) (width 0.082) (layer "In2.Cu") (net 633))
  (segment (start 204.632332 102.176292) (end 207.138628 99.669996) (width 0.13) (layer "In2.Cu") (net 633))
  (segment (start 197.988056 102.389) (end 196.177045 102.389) (width 0.082) (layer "In2.Cu") (net 633))
  (segment (start 248.895202 118.588422) (end 249.151496 118.332128) (width 0.13) (layer "In2.Cu") (net 633))
  (segment (start 253.053 118.792368) (end 253.053 121.18736) (width 0.13) (layer "In2.Cu") (net 633))
  (segment (start 255.029219 122.705) (end 255.818157 122.705) (width 0.13) (layer "In2.Cu") (net 633))
  (segment (start 242.890868 116.749492) (end 243.075508 116.934132) (width 0.13) (layer "In2.Cu") (net 633))
  (segment (start 198.137161 102.322738) (end 198.129478 102.330421) (width 0.082) (layer "In2.Cu") (net 633))
  (segment (start 234.799447 102.083071) (end 235.955004 103.238628) (width 0.13) (layer "In2.Cu") (net 633))
  (segment (start 236.299447 104.583071) (end 237.705297 105.988921) (width 0.13) (layer "In2.Cu") (net 633))
  (arc (start 204.278779 102.322738) (mid 204.47012 102.284678) (end 204.632332 102.176292) (width 0.13) (layer "In2.Cu") (net 633))
  (arc (start 233.158368 99.472) (mid 233.417062 99.523458) (end 233.636372 99.669996) (width 0.13) (layer "In2.Cu") (net 633))
  (arc (start 196.035812 102.289188) (mid 195.991877 102.183122) (end 196.035811 102.077055) (width 0.082) (layer "In2.Cu") (net 633))
  (arc (start 243.28764 117.022) (mid 243.172835 116.999164) (end 243.075508 116.934132) (width 0.13) (layer "In2.Cu") (net 633))
  (arc (start 234.455004 100.488628) (mid 234.601543 100.707938) (end 234.653 100.966632) (width 0.13) (layer "In2.Cu") (net 633))
  (arc (start 247.51693 118.500554) (mid 247.679142 118.60894) (end 247.870483 118.647) (width 0.13) (layer "In2.Cu") (net 633))
  (arc (start 196.053763 102.059103) (mid 196.097697 101.953037) (end 196.053763 101.846971) (width 0.082) (layer "In2.Cu") (net 633))
  (arc (start 198.129478 102.330421) (mid 198.064593 102.373776) (end 197.988056 102.389) (width 0.082) (layer "In2.Cu") (net 633))
  (arc (start 234.653 101.729517) (mid 234.69106 101.920859) (end 234.799447 102.083071) (width 0.13) (layer "In2.Cu") (net 633))
  (arc (start 249.151496 118.332128) (mid 249.273479 118.250621) (end 249.417368 118.222) (width 0.13) (layer "In2.Cu") (net 633))
  (arc (start 195.26129 101.514666) (mid 195.199649 101.473479) (end 195.126939 101.459016) (width 0.082) (layer "In2.Cu") (net 633))
  (arc (start 237.705297 105.988921) (mid 237.851619 106.207907) (end 237.903 106.466218) (width 0.13) (layer "In2.Cu") (net 633))
  (arc (start 239.653 112.479517) (mid 239.69106 112.670859) (end 239.799447 112.833071) (width 0.13) (layer "In2.Cu") (net 633))
  (arc (start 194.330718 101.089298) (mid 194.36316 101.06762) (end 194.401429 101.060008) (width 0.082) (layer "In2.Cu") (net 633))
  (arc (start 196.177045 102.389) (mid 196.138777 102.381388) (end 196.106335 102.359711) (width 0.082) (layer "In2.Cu") (net 633))
  (arc (start 252.942872 118.526496) (mid 253.024379 118.648479) (end 253.053 118.792368) (width 0.13) (layer "In2.Cu") (net 633))
  (arc (start 243.882632 117.022) (mid 244.026521 117.050621) (end 244.148504 117.132128) (width 0.13) (layer "In2.Cu") (net 633))
  (arc (start 246.486372 117.469996) (mid 246.267062 117.323458) (end 246.008368 117.272) (width 0.13) (layer "In2.Cu") (net 633))
  (arc (start 242.803 116.116632) (mid 242.751543 115.857938) (end 242.605004 115.638628) (width 0.13) (layer "In2.Cu") (net 633))
  (arc (start 255.818157 122.705) (mid 255.894693 122.689776) (end 255.959578 122.646422) (width 0.13) (layer "In2.Cu") (net 633))
  (arc (start 196.053763 101.846971) (mid 195.947697 101.803036) (end 195.84163 101.84697) (width 0.082) (layer "In2.Cu") (net 633))
  (arc (start 252.482632 118.222) (mid 252.626521 118.250621) (end 252.748504 118.332128) (width 0.13) (layer "In2.Cu") (net 633))
  (arc (start 194.222328 101.239109) (mid 194.22994 101.200841) (end 194.251617 101.168399) (width 0.082) (layer "In2.Cu") (net 633))
  (arc (start 236.153 104.229517) (mid 236.19106 104.420859) (end 236.299447 104.583071) (width 0.13) (layer "In2.Cu") (net 633))
  (arc (start 254.887797 122.646421) (mid 254.952682 122.689776) (end 255.029219 122.705) (width 0.13) (layer "In2.Cu") (net 633))
  (arc (start 237.903 108.979517) (mid 237.94106 109.170859) (end 238.049447 109.333071) (width 0.13) (layer "In2.Cu") (net 633))
  (arc (start 253.74121 121.697) (mid 253.923367 121.733233) (end 254.077793 121.836417) (width 0.13) (layer "In2.Cu") (net 633))
  (arc (start 253.56264 121.697) (mid 253.447835 121.674164) (end 253.350508 121.609132) (width 0.13) (layer "In2.Cu") (net 633))
  (arc (start 207.138628 99.669996) (mid 207.357938 99.523458) (end 207.616632 99.472) (width 0.13) (layer "In2.Cu") (net 633))
  (arc (start 235.955004 103.238628) (mid 236.101542 103.457938) (end 236.153 103.716632) (width 0.13) (layer "In2.Cu") (net 633))
  (arc (start 194.402045 101.459016) (mid 194.363777 101.451404) (end 194.331335 101.429727) (width 0.082) (layer "In2.Cu") (net 633))
  (arc (start 194.251618 101.35001) (mid 194.22994 101.317568) (end 194.222328 101.279299) (width 0.082) (layer "In2.Cu") (net 633))
  (arc (start 253.053 121.18736) (mid 253.075836 121.302165) (end 253.140868 121.399492) (width 0.13) (layer "In2.Cu") (net 633))
  (arc (start 242.890868 116.749492) (mid 242.825836 116.652165) (end 242.803 116.53736) (width 0.13) (layer "In2.Cu") (net 633))
  (arc (start 244.371219 117.272) (mid 244.294683 117.256776) (end 244.229798 117.213422) (width 0.13) (layer "In2.Cu") (net 633))
  (arc (start 239.455297 110.738921) (mid 239.601619 110.957907) (end 239.653 111.216218) (width 0.13) (layer "In2.Cu") (net 633))
  (arc (start 195.823678 101.864922) (mid 195.717612 101.908856) (end 195.611546 101.864922) (width 0.082) (layer "In2.Cu") (net 633))
  (arc (start 248.753781 118.647) (mid 248.830317 118.631776) (end 248.895202 118.588422) (width 0.13) (layer "In2.Cu") (net 633))
  (segment (start 256.351343 122.7145) (end 256.527657 122.7145) (width 0.122) (layer "B.Cu") (net 633))
  (segment (start 256.669079 122.655921) (end 256.685711 122.639289) (width 0.122) (layer "B.Cu") (net 633))
  (segment (start 256.08 122.526) (end 256.209922 122.655922) (width 0.122) (layer "B.Cu") (net 633))
  (segment (start 256.715 122.568579) (end 256.715 122.225) (width 0.122) (layer "B.Cu") (net 633))
  (arc (start 256.351343 122.7145) (mid 256.274807 122.699276) (end 256.209922 122.655922) (width 0.122) (layer "B.Cu") (net 633))
  (arc (start 256.685711 122.639289) (mid 256.707388 122.606847) (end 256.715 122.568579) (width 0.122) (layer "B.Cu") (net 633))
  (arc (start 256.527657 122.7145) (mid 256.604194 122.699276) (end 256.669079 122.655921) (width 0.122) (layer "B.Cu") (net 633))
  (segment (start 193.636328 99.060008) (end 193.136328 98.560008) (width 0.127) (layer "F.Cu") (net 634))
  (via blind (at 193.636328 99.060008) (size 0.5) (drill 0.2) (layers "F.Cu" "In2.Cu") (net 634))
  (via (at 256.08 118.11) (size 0.5) (drill 0.2) (layers "F.Cu" "B.Cu") (net 634))
  (segment (start 239.200554 101.66693) (end 237.794996 100.261372) (width 0.13) (layer "In2.Cu") (net 634))
  (segment (start 195.213682 99.660306) (end 195.283727 99.730351) (width 0.082) (layer "In2.Cu") (net 634))
  (segment (start 194.105978 99.447618) (end 194.233727 99.575367) (width 0.082) (layer "In2.Cu") (net 634))
  (segment (start 237.450554 99.26693) (end 235.313071 97.129447) (width 0.13) (layer "In2.Cu") (net 634))
  (segment (start 193.969282 99.089298) (end 194.021039 99.141055) (width 0.082) (layer "In2.Cu") (net 634))
  (segment (start 240.847 107.033368) (end 240.847 105.270483) (width 0.13) (layer "In2.Cu") (net 634))
  (segment (start 248.204517 111.578) (end 244.141632 111.578) (width 0.13) (layer "In2.Cu") (net 634))
  (segment (start 240.700554 104.91693) (end 239.544996 103.761372) (width 0.13) (layer "In2.Cu") (net 634))
  (segment (start 255.238421 115.679797) (end 254.395202 114.836578) (width 0.13) (layer "In2.Cu") (net 634))
  (segment (start 197.141274 99.73035) (end 197.210312 99.661312) (width 0.082) (layer "In2.Cu") (net 634))
  (segment (start 254.253781 114.778) (end 251.767368 114.778) (width 0.13) (layer "In2.Cu") (net 634))
  (segment (start 242.200553 108.666929) (end 241.044996 107.511372) (width 0.13) (layer "In2.Cu") (net 634))
  (segment (start 197.281022 99.632023) (end 197.99618 99.632023) (width 0.082) (layer "In2.Cu") (net 634))
  (segment (start 255.297 117.482632) (end 255.297 115.821219) (width 0.13) (layer "In2.Cu") (net 634))
  (segment (start 201.953368 99.703) (end 198.15 99.703) (width 0.13) (layer "In2.Cu") (net 634))
  (segment (start 256.08 118.11) (end 255.959578 117.989578) (width 0.13) (layer "In2.Cu") (net 634))
  (segment (start 194.368077 99.631016) (end 195.142971 99.631016) (width 0.082) (layer "In2.Cu") (net 634))
  (segment (start 234.959517 96.983) (end 205.160483 96.983) (width 0.13) (layer "In2.Cu") (net 634))
  (segment (start 193.636328 99.060008) (end 193.898571 99.060008) (width 0.082) (layer "In2.Cu") (net 634))
  (segment (start 194.050328 99.211765) (end 194.050328 99.313267) (width 0.082) (layer "In2.Cu") (net 634))
  (segment (start 251.501496 114.667872) (end 248.558071 111.724447) (width 0.13) (layer "In2.Cu") (net 634))
  (segment (start 239.347 103.283368) (end 239.347 102.020483) (width 0.13) (layer "In2.Cu") (net 634))
  (segment (start 255.508785 117.850161) (end 255.407128 117.748504) (width 0.13) (layer "In2.Cu") (net 634))
  (segment (start 204.80693 97.129446) (end 202.431372 99.505004) (width 0.13) (layer "In2.Cu") (net 634))
  (segment (start 195.418077 99.786) (end 197.006923 99.786) (width 0.082) (layer "In2.Cu") (net 634))
  (segment (start 237.597 99.783368) (end 237.597 99.620483) (width 0.13) (layer "In2.Cu") (net 634))
  (segment (start 255.818157 117.931) (end 255.703947 117.931) (width 0.13) (layer "In2.Cu") (net 634))
  (segment (start 243.663628 111.380004) (end 242.544996 110.261372) (width 0.13) (layer "In2.Cu") (net 634))
  (segment (start 198.137602 99.690602) (end 198.15 99.703) (width 0.082) (layer "In2.Cu") (net 634))
  (segment (start 242.347 109.783368) (end 242.347 109.020483) (width 0.13) (layer "In2.Cu") (net 634))
  (arc (start 240.847 105.270483) (mid 240.80894 105.079142) (end 240.700554 104.91693) (width 0.13) (layer "In2.Cu") (net 634))
  (arc (start 242.544996 110.261372) (mid 242.398457 110.042062) (end 242.347 109.783368) (width 0.13) (layer "In2.Cu") (net 634))
  (arc (start 244.141632 111.578) (mid 243.882938 111.526542) (end 243.663628 111.380004) (width 0.13) (layer "In2.Cu") (net 634))
  (arc (start 255.959578 117.989578) (mid 255.894693 117.946224) (end 255.818157 117.931) (width 0.13) (layer "In2.Cu") (net 634))
  (arc (start 195.283727 99.730351) (mid 195.345367 99.771538) (end 195.418077 99.786) (width 0.082) (layer "In2.Cu") (net 634))
  (arc (start 239.544996 103.761372) (mid 239.398457 103.542062) (end 239.347 103.283368) (width 0.13) (layer "In2.Cu") (net 634))
  (arc (start 197.99618 99.632023) (mid 198.072717 99.647247) (end 198.137602 99.690602) (width 0.082) (layer "In2.Cu") (net 634))
  (arc (start 193.969282 99.089298) (mid 193.93684 99.06762) (end 193.898571 99.060008) (width 0.082) (layer "In2.Cu") (net 634))
  (arc (start 248.558071 111.724447) (mid 248.395859 111.61606) (end 248.204517 111.578) (width 0.13) (layer "In2.Cu") (net 634))
  (arc (start 254.395202 114.836578) (mid 254.330317 114.793224) (end 254.253781 114.778) (width 0.13) (layer "In2.Cu") (net 634))
  (arc (start 237.794996 100.261372) (mid 237.648458 100.042062) (end 237.597 99.783368) (width 0.13) (layer "In2.Cu") (net 634))
  (arc (start 235.313071 97.129447) (mid 235.150859 97.02106) (end 234.959517 96.983) (width 0.13) (layer "In2.Cu") (net 634))
  (arc (start 195.213682 99.660306) (mid 195.18124 99.638628) (end 195.142971 99.631016) (width 0.082) (layer "In2.Cu") (net 634))
  (arc (start 205.160483 96.983) (mid 204.969142 97.02106) (end 204.80693 97.129446) (width 0.13) (layer "In2.Cu") (net 634))
  (arc (start 239.347 102.020483) (mid 239.30894 101.829142) (end 239.200554 101.66693) (width 0.13) (layer "In2.Cu") (net 634))
  (arc (start 202.431372 99.505004) (mid 202.212062 99.651543) (end 201.953368 99.703) (width 0.13) (layer "In2.Cu") (net 634))
  (arc (start 241.044996 107.511372) (mid 240.898458 107.292062) (end 240.847 107.033368) (width 0.13) (layer "In2.Cu") (net 634))
  (arc (start 255.407128 117.748504) (mid 255.325621 117.626521) (end 255.297 117.482632) (width 0.13) (layer "In2.Cu") (net 634))
  (arc (start 237.597 99.620483) (mid 237.55894 99.429142) (end 237.450554 99.26693) (width 0.13) (layer "In2.Cu") (net 634))
  (arc (start 255.508785 117.850161) (mid 255.598326 117.909991) (end 255.703947 117.931) (width 0.13) (layer "In2.Cu") (net 634))
  (arc (start 194.233727 99.575367) (mid 194.295367 99.616554) (end 194.368077 99.631016) (width 0.082) (layer "In2.Cu") (net 634))
  (arc (start 242.347 109.020483) (mid 242.30894 108.829141) (end 242.200553 108.666929) (width 0.13) (layer "In2.Cu") (net 634))
  (arc (start 194.021039 99.141055) (mid 194.042716 99.173497) (end 194.050328 99.211765) (width 0.082) (layer "In2.Cu") (net 634))
  (arc (start 251.767368 114.778) (mid 251.623479 114.749379) (end 251.501496 114.667872) (width 0.13) (layer "In2.Cu") (net 634))
  (arc (start 255.297 115.821219) (mid 255.281776 115.744682) (end 255.238421 115.679797) (width 0.13) (layer "In2.Cu") (net 634))
  (arc (start 194.105978 99.447618) (mid 194.064791 99.385977) (end 194.050328 99.313267) (width 0.082) (layer "In2.Cu") (net 634))
  (arc (start 197.141274 99.73035) (mid 197.079633 99.771537) (end 197.006923 99.786) (width 0.082) (layer "In2.Cu") (net 634))
  (arc (start 197.210312 99.661312) (mid 197.242754 99.639635) (end 197.281022 99.632023) (width 0.082) (layer "In2.Cu") (net 634))
  (segment (start 256.685079 117.980079) (end 256.685711 117.980711) (width 0.122) (layer "B.Cu") (net 634))
  (segment (start 256.351343 117.9215) (end 256.543657 117.9215) (width 0.122) (layer "B.Cu") (net 634))
  (segment (start 256.715 118.051421) (end 256.715 118.415) (width 0.122) (layer "B.Cu") (net 634))
  (segment (start 256.08 118.11) (end 256.209922 117.980078) (width 0.122) (layer "B.Cu") (net 634))
  (arc (start 256.543657 117.9215) (mid 256.620194 117.936724) (end 256.685079 117.980079) (width 0.122) (layer "B.Cu") (net 634))
  (arc (start 256.715 118.051421) (mid 256.707388 118.013153) (end 256.685711 117.980711) (width 0.122) (layer "B.Cu") (net 634))
  (arc (start 256.351343 117.9215) (mid 256.274807 117.936724) (end 256.209922 117.980078) (width 0.122) (layer "B.Cu") (net 634))
  (segment (start 194.636328 99.060008) (end 194.136328 98.560008) (width 0.127) (layer "F.Cu") (net 635))
  (via (at 256.08 117.446) (size 0.5) (drill 0.2) (layers "F.Cu" "B.Cu") (net 635))
  (via blind (at 194.636328 99.060008) (size 0.5) (drill 0.2) (layers "F.Cu" "In2.Cu") (net 635))
  (segment (start 198.15 99.397) (end 198.145556 99.401444) (width 0.082) (layer "In2.Cu") (net 635))
  (segment (start 198.15 99.397) (end 201.899517 99.397) (width 0.13) (layer "In2.Cu") (net 635))
  (segment (start 255.959579 117.566421) (end 256.08 117.446) (width 0.13) (layer "In2.Cu") (net 635))
  (segment (start 194.222328 99.279299) (end 194.222328 99.239109) (width 0.082) (layer "In2.Cu") (net 635))
  (segment (start 235.491372 96.874996) (end 237.705004 99.088628) (width 0.13) (layer "In2.Cu") (net 635))
  (segment (start 196.972955 99.614) (end 196.404 99.614) (width 0.082) (layer "In2.Cu") (net 635))
  (segment (start 248.736372 111.469996) (end 251.679798 114.413422) (width 0.13) (layer "In2.Cu") (net 635))
  (segment (start 196.279 99.489) (end 196.279 99.435708) (width 0.082) (layer "In2.Cu") (net 635))
  (segment (start 255.757797 117.625) (end 255.818157 117.625) (width 0.13) (layer "In2.Cu") (net 635))
  (segment (start 238.049447 100.083071) (end 239.455004 101.488628) (width 0.13) (layer "In2.Cu") (net 635))
  (segment (start 205.106632 96.677) (end 235.013368 96.677) (width 0.13) (layer "In2.Cu") (net 635))
  (segment (start 239.799447 103.583071) (end 240.955297 104.738921) (width 0.13) (layer "In2.Cu") (net 635))
  (segment (start 241.299447 107.333071) (end 242.455297 108.488921) (width 0.13) (layer "In2.Cu") (net 635))
  (segment (start 254.573504 114.582128) (end 255.492872 115.501496) (width 0.13) (layer "In2.Cu") (net 635))
  (segment (start 255.661579 117.570203) (end 255.687087 117.595711) (width 0.13) (layer "In2.Cu") (net 635))
  (segment (start 241.153 105.216218) (end 241.153 106.979517) (width 0.13) (layer "In2.Cu") (net 635))
  (segment (start 242.799447 110.083071) (end 243.84193 111.125554) (width 0.13) (layer "In2.Cu") (net 635))
  (segment (start 195.904 99.614) (end 195.854 99.614) (width 0.082) (layer "In2.Cu") (net 635))
  (segment (start 195.176939 99.459016) (end 194.402045 99.459016) (width 0.082) (layer "In2.Cu") (net 635))
  (segment (start 194.331335 99.429727) (end 194.251618 99.35001) (width 0.082) (layer "In2.Cu") (net 635))
  (segment (start 202.253071 99.250553) (end 204.628628 96.874996) (width 0.13) (layer "In2.Cu") (net 635))
  (segment (start 198.004134 99.460023) (end 197.247054 99.460023) (width 0.082) (layer "In2.Cu") (net 635))
  (segment (start 194.401429 99.060008) (end 194.636328 99.060008) (width 0.082) (layer "In2.Cu") (net 635))
  (segment (start 239.653 101.966632) (end 239.653 103.229517) (width 0.13) (layer "In2.Cu") (net 635))
  (segment (start 195.381335 99.584711) (end 195.31129 99.514666) (width 0.082) (layer "In2.Cu") (net 635))
  (segment (start 195.854 99.614) (end 195.452045 99.614) (width 0.082) (layer "In2.Cu") (net 635))
  (segment (start 197.112704 99.515672) (end 197.043666 99.58471) (width 0.082) (layer "In2.Cu") (net 635))
  (segment (start 251.821219 114.472) (end 254.307632 114.472) (width 0.13) (layer "In2.Cu") (net 635))
  (segment (start 196.029 99.435708) (end 196.029 99.489) (width 0.082) (layer "In2.Cu") (net 635))
  (segment (start 194.251617 99.168399) (end 194.330718 99.089298) (width 0.082) (layer "In2.Cu") (net 635))
  (segment (start 237.903 99.566632) (end 237.903 99.729517) (width 0.13) (layer "In2.Cu") (net 635))
  (segment (start 244.195483 111.272) (end 248.258368 111.272) (width 0.13) (layer "In2.Cu") (net 635))
  (segment (start 255.603 115.767368) (end 255.603 117.428781) (width 0.13) (layer "In2.Cu") (net 635))
  (segment (start 242.653 108.966218) (end 242.653 109.729517) (width 0.13) (layer "In2.Cu") (net 635))
  (arc (start 197.247054 99.460023) (mid 197.174344 99.474485) (end 197.112704 99.515672) (width 0.082) (layer "In2.Cu") (net 635))
  (arc (start 255.818157 117.625) (mid 255.894694 117.609776) (end 255.959579 117.566421) (width 0.13) (layer "In2.Cu") (net 635))
  (arc (start 243.84193 111.125554) (mid 244.004142 111.23394) (end 244.195483 111.272) (width 0.13) (layer "In2.Cu") (net 635))
  (arc (start 204.628628 96.874996) (mid 204.847938 96.728457) (end 205.106632 96.677) (width 0.13) (layer "In2.Cu") (net 635))
  (arc (start 239.653 103.229517) (mid 239.69106 103.420859) (end 239.799447 103.583071) (width 0.13) (layer "In2.Cu") (net 635))
  (arc (start 241.153 106.979517) (mid 241.19106 107.170859) (end 241.299447 107.333071) (width 0.13) (layer "In2.Cu") (net 635))
  (arc (start 237.903 99.729517) (mid 237.94106 99.920859) (end 238.049447 100.083071) (width 0.13) (layer "In2.Cu") (net 635))
  (arc (start 194.402045 99.459016) (mid 194.363777 99.451404) (end 194.331335 99.429727) (width 0.082) (layer "In2.Cu") (net 635))
  (arc (start 240.955297 104.738921) (mid 241.101619 104.957907) (end 241.153 105.216218) (width 0.13) (layer "In2.Cu") (net 635))
  (arc (start 248.258368 111.272) (mid 248.517062 111.323457) (end 248.736372 111.469996) (width 0.13) (layer "In2.Cu") (net 635))
  (arc (start 255.492872 115.501496) (mid 255.574379 115.623479) (end 255.603 115.767368) (width 0.13) (layer "In2.Cu") (net 635))
  (arc (start 251.679798 114.413422) (mid 251.744683 114.456776) (end 251.821219 114.472) (width 0.13) (layer "In2.Cu") (net 635))
  (arc (start 239.455004 101.488628) (mid 239.601542 101.707938) (end 239.653 101.966632) (width 0.13) (layer "In2.Cu") (net 635))
  (arc (start 194.222328 99.239109) (mid 194.22994 99.200841) (end 194.251617 99.168399) (width 0.082) (layer "In2.Cu") (net 635))
  (arc (start 196.029 99.489) (mid 195.992388 99.577388) (end 195.904 99.614) (width 0.082) (layer "In2.Cu") (net 635))
  (arc (start 255.687087 117.595711) (mid 255.719529 117.617388) (end 255.757797 117.625) (width 0.13) (layer "In2.Cu") (net 635))
  (arc (start 195.452045 99.614) (mid 195.413777 99.606388) (end 195.381335 99.584711) (width 0.082) (layer "In2.Cu") (net 635))
  (arc (start 194.251618 99.35001) (mid 194.22994 99.317568) (end 194.222328 99.279299) (width 0.082) (layer "In2.Cu") (net 635))
  (arc (start 196.279 99.435708) (mid 196.242388 99.34732) (end 196.154 99.310708) (width 0.082) (layer "In2.Cu") (net 635))
  (arc (start 254.307632 114.472) (mid 254.451521 114.500621) (end 254.573504 114.582128) (width 0.13) (layer "In2.Cu") (net 635))
  (arc (start 237.705004 99.088628) (mid 237.851543 99.307938) (end 237.903 99.566632) (width 0.13) (layer "In2.Cu") (net 635))
  (arc (start 242.653 109.729517) (mid 242.69106 109.920859) (end 242.799447 110.083071) (width 0.13) (layer "In2.Cu") (net 635))
  (arc (start 196.404 99.614) (mid 196.315612 99.577388) (end 196.279 99.489) (width 0.082) (layer "In2.Cu") (net 635))
  (arc (start 196.154 99.310708) (mid 196.065612 99.34732) (end 196.029 99.435708) (width 0.082) (layer "In2.Cu") (net 635))
  (arc (start 255.603 117.428781) (mid 255.618224 117.505318) (end 255.661579 117.570203) (width 0.13) (layer "In2.Cu") (net 635))
  (arc (start 198.145556 99.401444) (mid 198.080671 99.444799) (end 198.004134 99.460023) (width 0.082) (layer "In2.Cu") (net 635))
  (arc (start 235.013368 96.677) (mid 235.272062 96.728458) (end 235.491372 96.874996) (width 0.13) (layer "In2.Cu") (net 635))
  (arc (start 197.043666 99.58471) (mid 197.011224 99.606388) (end 196.972955 99.614) (width 0.082) (layer "In2.Cu") (net 635))
  (arc (start 195.31129 99.514666) (mid 195.249649 99.473479) (end 195.176939 99.459016) (width 0.082) (layer "In2.Cu") (net 635))
  (arc (start 201.899517 99.397) (mid 202.090859 99.35894) (end 202.253071 99.250553) (width 0.13) (layer "In2.Cu") (net 635))
  (arc (start 194.330718 99.089298) (mid 194.36316 99.06762) (end 194.401429 99.060008) (width 0.082) (layer "In2.Cu") (net 635))
  (arc (start 242.455297 108.488921) (mid 242.601619 108.707907) (end 242.653 108.966218) (width 0.13) (layer "In2.Cu") (net 635))
  (segment (start 256.669079 117.575921) (end 256.685711 117.559289) (width 0.122) (layer "B.Cu") (net 635))
  (segment (start 256.351343 117.6345) (end 256.527657 117.6345) (width 0.122) (layer "B.Cu") (net 635))
  (segment (start 256.715 117.488579) (end 256.715 117.145) (width 0.122) (layer "B.Cu") (net 635))
  (segment (start 256.08 117.446) (end 256.209922 117.575922) (width 0.122) (layer "B.Cu") (net 635))
  (arc (start 256.351343 117.6345) (mid 256.274807 117.619276) (end 256.209922 117.575922) (width 0.122) (layer "B.Cu") (net 635))
  (arc (start 256.527657 117.6345) (mid 256.604194 117.619276) (end 256.669079 117.575921) (width 0.122) (layer "B.Cu") (net 635))
  (arc (start 256.685711 117.559289) (mid 256.707388 117.526847) (end 256.715 117.488579) (width 0.122) (layer "B.Cu") (net 635))
  (segment (start 193.636328 97.060008) (end 193.136328 96.560008) (width 0.127) (layer "F.Cu") (net 636))
  (via (at 256.08 113.03) (size 0.5) (drill 0.2) (layers "F.Cu" "B.Cu") (net 636))
  (via blind (at 193.636328 97.060008) (size 0.5) (drill 0.2) (layers "F.Cu" "In2.Cu") (net 636))
  (segment (start 242.544996 106.511372) (end 243.588628 107.555004) (width 0.13) (layer "In2.Cu") (net 636))
  (segment (start 248.708071 107.899447) (end 253.461628 112.653004) (width 0.13) (layer "In2.Cu") (net 636))
  (segment (start 255.959579 112.909579) (end 256.08 113.03) (width 0.13) (layer "In2.Cu") (net 636))
  (segment (start 195.568077 97.936) (end 196.906923 97.936) (width 0.082) (layer "In2.Cu") (net 636))
  (segment (start 236.458071 95.874447) (end 239.200554 98.61693) (width 0.13) (layer "In2.Cu") (net 636))
  (segment (start 204.070483 95.728) (end 236.104517 95.728) (width 0.13) (layer "In2.Cu") (net 636))
  (segment (start 197.333392 97.629653) (end 197.99381 97.629653) (width 0.082) (layer "In2.Cu") (net 636))
  (segment (start 239.347 98.970483) (end 239.347 99.283368) (width 0.13) (layer "In2.Cu") (net 636))
  (segment (start 244.066632 107.753) (end 248.354517 107.753) (width 0.13) (layer "In2.Cu") (net 636))
  (segment (start 194.368077 97.631016) (end 195.142971 97.631016) (width 0.082) (layer "In2.Cu") (net 636))
  (segment (start 202.086372 97.505004) (end 203.71693 95.874446) (width 0.13) (layer "In2.Cu") (net 636))
  (segment (start 197.041274 97.88035) (end 197.262682 97.658942) (width 0.082) (layer "In2.Cu") (net 636))
  (segment (start 193.636328 97.060008) (end 193.898571 97.060008) (width 0.082) (layer "In2.Cu") (net 636))
  (segment (start 253.939632 112.851) (end 255.818157 112.851) (width 0.13) (layer "In2.Cu") (net 636))
  (segment (start 241.044996 103.261372) (end 242.200554 104.41693) (width 0.13) (layer "In2.Cu") (net 636))
  (segment (start 195.213682 97.660306) (end 195.433727 97.880351) (width 0.082) (layer "In2.Cu") (net 636))
  (segment (start 239.544996 99.761372) (end 240.700554 100.91693) (width 0.13) (layer "In2.Cu") (net 636))
  (segment (start 242.347 104.770483) (end 242.347 106.033368) (width 0.13) (layer "In2.Cu") (net 636))
  (segment (start 194.105978 97.447618) (end 194.233727 97.575367) (width 0.082) (layer "In2.Cu") (net 636))
  (segment (start 198.135232 97.688232) (end 198.15 97.703) (width 0.082) (layer "In2.Cu") (net 636))
  (segment (start 194.050328 97.211765) (end 194.050328 97.313267) (width 0.082) (layer "In2.Cu") (net 636))
  (segment (start 193.969282 97.089298) (end 194.021039 97.141055) (width 0.082) (layer "In2.Cu") (net 636))
  (segment (start 201.608368 97.703) (end 198.15 97.703) (width 0.13) (layer "In2.Cu") (net 636))
  (segment (start 240.847 101.270483) (end 240.847 102.783368) (width 0.13) (layer "In2.Cu") (net 636))
  (arc (start 197.333392 97.629653) (mid 197.295124 97.637265) (end 197.262682 97.658942) (width 0.082) (layer "In2.Cu") (net 636))
  (arc (start 195.433727 97.880351) (mid 195.495367 97.921538) (end 195.568077 97.936) (width 0.082) (layer "In2.Cu") (net 636))
  (arc (start 255.959579 112.909579) (mid 255.894694 112.866224) (end 255.818157 112.851) (width 0.13) (layer "In2.Cu") (net 636))
  (arc (start 204.070483 95.728) (mid 203.879142 95.76606) (end 203.71693 95.874446) (width 0.13) (layer "In2.Cu") (net 636))
  (arc (start 242.200554 104.41693) (mid 242.30894 104.579142) (end 242.347 104.770483) (width 0.13) (layer "In2.Cu") (net 636))
  (arc (start 239.544996 99.761372) (mid 239.398458 99.542062) (end 239.347 99.283368) (width 0.13) (layer "In2.Cu") (net 636))
  (arc (start 240.847 102.783368) (mid 240.898457 103.042062) (end 241.044996 103.261372) (width 0.13) (layer "In2.Cu") (net 636))
  (arc (start 194.050328 97.211765) (mid 194.042716 97.173497) (end 194.021039 97.141055) (width 0.082) (layer "In2.Cu") (net 636))
  (arc (start 197.99381 97.629653) (mid 198.070347 97.644877) (end 198.135232 97.688232) (width 0.082) (layer "In2.Cu") (net 636))
  (arc (start 240.700554 100.91693) (mid 240.80894 101.079142) (end 240.847 101.270483) (width 0.13) (layer "In2.Cu") (net 636))
  (arc (start 197.041274 97.88035) (mid 196.979633 97.921537) (end 196.906923 97.936) (width 0.082) (layer "In2.Cu") (net 636))
  (arc (start 239.347 98.970483) (mid 239.30894 98.779142) (end 239.200554 98.61693) (width 0.13) (layer "In2.Cu") (net 636))
  (arc (start 202.086372 97.505004) (mid 201.867062 97.651542) (end 201.608368 97.703) (width 0.13) (layer "In2.Cu") (net 636))
  (arc (start 243.588628 107.555004) (mid 243.807938 107.701542) (end 244.066632 107.753) (width 0.13) (layer "In2.Cu") (net 636))
  (arc (start 253.461628 112.653004) (mid 253.680938 112.799542) (end 253.939632 112.851) (width 0.13) (layer "In2.Cu") (net 636))
  (arc (start 236.458071 95.874447) (mid 236.295859 95.76606) (end 236.104517 95.728) (width 0.13) (layer "In2.Cu") (net 636))
  (arc (start 194.105978 97.447618) (mid 194.064791 97.385977) (end 194.050328 97.313267) (width 0.082) (layer "In2.Cu") (net 636))
  (arc (start 242.544996 106.511372) (mid 242.398458 106.292062) (end 242.347 106.033368) (width 0.13) (layer "In2.Cu") (net 636))
  (arc (start 248.708071 107.899447) (mid 248.545859 107.79106) (end 248.354517 107.753) (width 0.13) (layer "In2.Cu") (net 636))
  (arc (start 195.213682 97.660306) (mid 195.18124 97.638628) (end 195.142971 97.631016) (width 0.082) (layer "In2.Cu") (net 636))
  (arc (start 193.898571 97.060008) (mid 193.93684 97.06762) (end 193.969282 97.089298) (width 0.082) (layer "In2.Cu") (net 636))
  (arc (start 194.368077 97.631016) (mid 194.295367 97.616553) (end 194.233727 97.575367) (width 0.082) (layer "In2.Cu") (net 636))
  (segment (start 256.08 113.03) (end 256.209922 112.900078) (width 0.122) (layer "B.Cu") (net 636))
  (segment (start 256.685079 112.900079) (end 256.685711 112.900711) (width 0.122) (layer "B.Cu") (net 636))
  (segment (start 256.351343 112.8415) (end 256.543657 112.8415) (width 0.122) (layer "B.Cu") (net 636))
  (segment (start 256.715 112.971421) (end 256.715 113.335) (width 0.122) (layer "B.Cu") (net 636))
  (arc (start 256.715 112.971421) (mid 256.707388 112.933153) (end 256.685711 112.900711) (width 0.122) (layer "B.Cu") (net 636))
  (arc (start 256.351343 112.8415) (mid 256.274807 112.856724) (end 256.209922 112.900078) (width 0.122) (layer "B.Cu") (net 636))
  (arc (start 256.543657 112.8415) (mid 256.620194 112.856724) (end 256.685079 112.900079) (width 0.122) (layer "B.Cu") (net 636))
  (segment (start 194.636328 97.060008) (end 194.136328 96.560008) (width 0.127) (layer "F.Cu") (net 637))
  (via blind (at 194.636328 97.060008) (size 0.5) (drill 0.2) (layers "F.Cu" "In2.Cu") (net 637))
  (via (at 256.08 112.366) (size 0.5) (drill 0.2) (layers "F.Cu" "B.Cu") (net 637))
  (segment (start 195.886 97.764) (end 195.836 97.764) (width 0.082) (layer "In2.Cu") (net 637))
  (segment (start 195.531335 97.734711) (end 195.31129 97.514666) (width 0.082) (layer "In2.Cu") (net 637))
  (segment (start 196.411 97.589) (end 196.411 97.583808) (width 0.082) (layer "In2.Cu") (net 637))
  (segment (start 239.653 98.916632) (end 239.653 99.229517) (width 0.13) (layer "In2.Cu") (net 637))
  (segment (start 248.886372 107.644996) (end 253.63993 112.398554) (width 0.13) (layer "In2.Cu") (net 637))
  (segment (start 194.401429 97.060008) (end 194.636328 97.060008) (width 0.082) (layer "In2.Cu") (net 637))
  (segment (start 204.016632 95.422) (end 236.158368 95.422) (width 0.13) (layer "In2.Cu") (net 637))
  (segment (start 195.836 97.764) (end 195.602045 97.764) (width 0.082) (layer "In2.Cu") (net 637))
  (segment (start 236.636372 95.619996) (end 239.455004 98.438628) (width 0.13) (layer "In2.Cu") (net 637))
  (segment (start 194.251617 97.168399) (end 194.330718 97.089298) (width 0.082) (layer "In2.Cu") (net 637))
  (segment (start 255.959579 112.486421) (end 256.08 112.366) (width 0.13) (layer "In2.Cu") (net 637))
  (segment (start 198.15 97.397) (end 201.554517 97.397) (width 0.13) (layer "In2.Cu") (net 637))
  (segment (start 196.872955 97.764) (end 196.586 97.764) (width 0.082) (layer "In2.Cu") (net 637))
  (segment (start 244.120483 107.447) (end 248.408368 107.447) (width 0.13) (layer "In2.Cu") (net 637))
  (segment (start 253.993483 112.545) (end 255.818157 112.545) (width 0.13) (layer "In2.Cu") (net 637))
  (segment (start 198.15 97.397) (end 198.147926 97.399074) (width 0.082) (layer "In2.Cu") (net 637))
  (segment (start 201.908071 97.250553) (end 203.538628 95.619996) (width 0.13) (layer "In2.Cu") (net 637))
  (segment (start 198.006504 97.457653) (end 197.299424 97.457653) (width 0.082) (layer "In2.Cu") (net 637))
  (segment (start 196.061 97.583808) (end 196.061 97.589) (width 0.082) (layer "In2.Cu") (net 637))
  (segment (start 241.299447 103.083071) (end 242.455297 104.238921) (width 0.13) (layer "In2.Cu") (net 637))
  (segment (start 241.153 101.216632) (end 241.153 102.729517) (width 0.13) (layer "In2.Cu") (net 637))
  (segment (start 197.165074 97.513302) (end 196.943666 97.73471) (width 0.082) (layer "In2.Cu") (net 637))
  (segment (start 194.331335 97.429727) (end 194.251618 97.35001) (width 0.082) (layer "In2.Cu") (net 637))
  (segment (start 239.799447 99.583071) (end 240.955004 100.738628) (width 0.13) (layer "In2.Cu") (net 637))
  (segment (start 242.799447 106.333071) (end 243.76693 107.300554) (width 0.13) (layer "In2.Cu") (net 637))
  (segment (start 194.222328 97.279299) (end 194.222328 97.239109) (width 0.082) (layer "In2.Cu") (net 637))
  (segment (start 195.176939 97.459016) (end 194.402045 97.459016) (width 0.082) (layer "In2.Cu") (net 637))
  (segment (start 242.653 104.716218) (end 242.653 105.979517) (width 0.13) (layer "In2.Cu") (net 637))
  (arc (start 239.653 99.229517) (mid 239.69106 99.420859) (end 239.799447 99.583071) (width 0.13) (layer "In2.Cu") (net 637))
  (arc (start 248.408368 107.447) (mid 248.667062 107.498458) (end 248.886372 107.644996) (width 0.13) (layer "In2.Cu") (net 637))
  (arc (start 197.299424 97.457653) (mid 197.226714 97.472115) (end 197.165074 97.513302) (width 0.082) (layer "In2.Cu") (net 637))
  (arc (start 194.251618 97.35001) (mid 194.22994 97.317568) (end 194.222328 97.279299) (width 0.082) (layer "In2.Cu") (net 637))
  (arc (start 194.330718 97.089298) (mid 194.36316 97.06762) (end 194.401429 97.060008) (width 0.082) (layer "In2.Cu") (net 637))
  (arc (start 201.554517 97.397) (mid 201.745859 97.35894) (end 201.908071 97.250553) (width 0.13) (layer "In2.Cu") (net 637))
  (arc (start 196.236 97.408808) (mid 196.112256 97.460064) (end 196.061 97.583808) (width 0.082) (layer "In2.Cu") (net 637))
  (arc (start 195.602045 97.764) (mid 195.563777 97.756388) (end 195.531335 97.734711) (width 0.082) (layer "In2.Cu") (net 637))
  (arc (start 194.222328 97.239109) (mid 194.22994 97.200841) (end 194.251617 97.168399) (width 0.082) (layer "In2.Cu") (net 637))
  (arc (start 203.538628 95.619996) (mid 203.757938 95.473458) (end 204.016632 95.422) (width 0.13) (layer "In2.Cu") (net 637))
  (arc (start 242.455297 104.238921) (mid 242.601619 104.457907) (end 242.653 104.716218) (width 0.13) (layer "In2.Cu") (net 637))
  (arc (start 243.76693 107.300554) (mid 243.929142 107.40894) (end 244.120483 107.447) (width 0.13) (layer "In2.Cu") (net 637))
  (arc (start 240.955004 100.738628) (mid 241.101542 100.957938) (end 241.153 101.216632) (width 0.13) (layer "In2.Cu") (net 637))
  (arc (start 239.455004 98.438628) (mid 239.601543 98.657938) (end 239.653 98.916632) (width 0.13) (layer "In2.Cu") (net 637))
  (arc (start 196.411 97.583808) (mid 196.359744 97.460064) (end 196.236 97.408808) (width 0.082) (layer "In2.Cu") (net 637))
  (arc (start 241.153 102.729517) (mid 241.19106 102.920859) (end 241.299447 103.083071) (width 0.13) (layer "In2.Cu") (net 637))
  (arc (start 194.402045 97.459016) (mid 194.363777 97.451404) (end 194.331335 97.429727) (width 0.082) (layer "In2.Cu") (net 637))
  (arc (start 242.653 105.979517) (mid 242.69106 106.170859) (end 242.799447 106.333071) (width 0.13) (layer "In2.Cu") (net 637))
  (arc (start 196.061 97.589) (mid 196.009744 97.712744) (end 195.886 97.764) (width 0.082) (layer "In2.Cu") (net 637))
  (arc (start 255.818157 112.545) (mid 255.894694 112.529776) (end 255.959579 112.486421) (width 0.13) (layer "In2.Cu") (net 637))
  (arc (start 195.31129 97.514666) (mid 195.249649 97.473479) (end 195.176939 97.459016) (width 0.082) (layer "In2.Cu") (net 637))
  (arc (start 196.586 97.764) (mid 196.462256 97.712744) (end 196.411 97.589) (width 0.082) (layer "In2.Cu") (net 637))
  (arc (start 198.147926 97.399074) (mid 198.083041 97.442429) (end 198.006504 97.457653) (width 0.082) (layer "In2.Cu") (net 637))
  (arc (start 236.158368 95.422) (mid 236.417062 95.473457) (end 236.636372 95.619996) (width 0.13) (layer "In2.Cu") (net 637))
  (arc (start 253.63993 112.398554) (mid 253.802142 112.50694) (end 253.993483 112.545) (width 0.13) (layer "In2.Cu") (net 637))
  (arc (start 196.943666 97.73471) (mid 196.911224 97.756388) (end 196.872955 97.764) (width 0.082) (layer "In2.Cu") (net 637))
  (segment (start 256.08 112.366) (end 256.209922 112.495922) (width 0.122) (layer "B.Cu") (net 637))
  (segment (start 256.715 112.408579) (end 256.715 112.065) (width 0.122) (layer "B.Cu") (net 637))
  (segment (start 256.351343 112.5545) (end 256.527657 112.5545) (width 0.122) (layer "B.Cu") (net 637))
  (segment (start 256.669079 112.495921) (end 256.685711 112.479289) (width 0.122) (layer "B.Cu") (net 637))
  (arc (start 256.527657 112.5545) (mid 256.604194 112.539276) (end 256.669079 112.495921) (width 0.122) (layer "B.Cu") (net 637))
  (arc (start 256.685711 112.479289) (mid 256.707388 112.446847) (end 256.715 112.408579) (width 0.122) (layer "B.Cu") (net 637))
  (arc (start 256.351343 112.5545) (mid 256.274807 112.539276) (end 256.209922 112.495922) (width 0.122) (layer "B.Cu") (net 637))
  (segment (start 193.636328 95.060008) (end 193.136328 94.560008) (width 0.127) (layer "F.Cu") (net 638))
  (via blind (at 193.636328 95.060008) (size 0.5) (drill 0.2) (layers "F.Cu" "In2.Cu") (net 638))
  (via (at 256.08 107.95) (size 0.5) (drill 0.2) (layers "F.Cu" "B.Cu") (net 638))
  (segment (start 240.700553 97.691929) (end 237.58307 94.574446) (width 0.13) (layer "In2.Cu") (net 638))
  (segment (start 194.368077 95.631016) (end 195.092971 95.631016) (width 0.082) (layer "In2.Cu") (net 638))
  (segment (start 198.141579 95.694579) (end 198.15 95.703) (width 0.082) (layer "In2.Cu") (net 638))
  (segment (start 255.818157 107.771) (end 253.609632 107.771) (width 0.13) (layer "In2.Cu") (net 638))
  (segment (start 193.969282 95.089298) (end 194.021039 95.141055) (width 0.082) (layer "In2.Cu") (net 638))
  (segment (start 197.241274 95.75535) (end 197.331335 95.665289) (width 0.082) (layer "In2.Cu") (net 638))
  (segment (start 242.200553 100.416929) (end 240.993446 99.209822) (width 0.13) (layer "In2.Cu") (net 638))
  (segment (start 237.229517 94.428) (end 202.595483 94.428) (width 0.13) (layer "In2.Cu") (net 638))
  (segment (start 202.241929 94.574447) (end 201.311372 95.505004) (width 0.13) (layer "In2.Cu") (net 638))
  (segment (start 194.050328 95.211765) (end 194.050328 95.313267) (width 0.082) (layer "In2.Cu") (net 638))
  (segment (start 242.347 101.958368) (end 242.347 100.770483) (width 0.13) (layer "In2.Cu") (net 638))
  (segment (start 197.402045 95.636) (end 198.000157 95.636) (width 0.082) (layer "In2.Cu") (net 638))
  (segment (start 240.847 98.856269) (end 240.847 98.045483) (width 0.13) (layer "In2.Cu") (net 638))
  (segment (start 193.636328 95.060008) (end 193.898571 95.060008) (width 0.082) (layer "In2.Cu") (net 638))
  (segment (start 253.131628 107.573004) (end 249.63307 104.074446) (width 0.13) (layer "In2.Cu") (net 638))
  (segment (start 249.279517 103.928) (end 244.316632 103.928) (width 0.13) (layer "In2.Cu") (net 638))
  (segment (start 200.833368 95.703) (end 198.15 95.703) (width 0.13) (layer "In2.Cu") (net 638))
  (segment (start 195.163682 95.660306) (end 195.258727 95.755351) (width 0.082) (layer "In2.Cu") (net 638))
  (segment (start 194.105978 95.447618) (end 194.233727 95.575367) (width 0.082) (layer "In2.Cu") (net 638))
  (segment (start 243.838628 103.730004) (end 242.544996 102.436372) (width 0.13) (layer "In2.Cu") (net 638))
  (segment (start 256.08 107.95) (end 255.959578 107.829578) (width 0.13) (layer "In2.Cu") (net 638))
  (segment (start 195.393077 95.811) (end 197.106923 95.811) (width 0.082) (layer "In2.Cu") (net 638))
  (arc (start 253.609632 107.771) (mid 253.350938 107.719543) (end 253.131628 107.573004) (width 0.13) (layer "In2.Cu") (net 638))
  (arc (start 240.847 98.045483) (mid 240.80894 97.854141) (end 240.700553 97.691929) (width 0.13) (layer "In2.Cu") (net 638))
  (arc (start 255.818157 107.771) (mid 255.894693 107.786224) (end 255.959578 107.829578) (width 0.13) (layer "In2.Cu") (net 638))
  (arc (start 194.050328 95.313267) (mid 194.064791 95.385977) (end 194.105978 95.447618) (width 0.082) (layer "In2.Cu") (net 638))
  (arc (start 197.241274 95.75535) (mid 197.179633 95.796537) (end 197.106923 95.811) (width 0.082) (layer "In2.Cu") (net 638))
  (arc (start 243.838628 103.730004) (mid 244.057938 103.876542) (end 244.316632 103.928) (width 0.13) (layer "In2.Cu") (net 638))
  (arc (start 242.544996 102.436372) (mid 242.398458 102.217062) (end 242.347 101.958368) (width 0.13) (layer "In2.Cu") (net 638))
  (arc (start 198.141579 95.694579) (mid 198.076694 95.651224) (end 198.000157 95.636) (width 0.082) (layer "In2.Cu") (net 638))
  (arc (start 195.092971 95.631016) (mid 195.13124 95.638628) (end 195.163682 95.660306) (width 0.082) (layer "In2.Cu") (net 638))
  (arc (start 194.021039 95.141055) (mid 194.042716 95.173497) (end 194.050328 95.211765) (width 0.082) (layer "In2.Cu") (net 638))
  (arc (start 249.63307 104.074446) (mid 249.470858 103.96606) (end 249.279517 103.928) (width 0.13) (layer "In2.Cu") (net 638))
  (arc (start 240.847 98.856269) (mid 240.88506 99.04761) (end 240.993446 99.209822) (width 0.13) (layer "In2.Cu") (net 638))
  (arc (start 197.331335 95.665289) (mid 197.363777 95.643612) (end 197.402045 95.636) (width 0.082) (layer "In2.Cu") (net 638))
  (arc (start 195.258727 95.755351) (mid 195.320367 95.796538) (end 195.393077 95.811) (width 0.082) (layer "In2.Cu") (net 638))
  (arc (start 242.347 100.770483) (mid 242.30894 100.579141) (end 242.200553 100.416929) (width 0.13) (layer "In2.Cu") (net 638))
  (arc (start 194.368077 95.631016) (mid 194.295367 95.616553) (end 194.233727 95.575367) (width 0.082) (layer "In2.Cu") (net 638))
  (arc (start 193.969282 95.089298) (mid 193.93684 95.06762) (end 193.898571 95.060008) (width 0.082) (layer "In2.Cu") (net 638))
  (arc (start 202.595483 94.428) (mid 202.404141 94.46606) (end 202.241929 94.574447) (width 0.13) (layer "In2.Cu") (net 638))
  (arc (start 237.58307 94.574446) (mid 237.420858 94.46606) (end 237.229517 94.428) (width 0.13) (layer "In2.Cu") (net 638))
  (arc (start 201.311372 95.505004) (mid 201.092062 95.651542) (end 200.833368 95.703) (width 0.13) (layer "In2.Cu") (net 638))
  (segment (start 256.351343 107.7615) (end 256.543657 107.7615) (width 0.122) (layer "B.Cu") (net 638))
  (segment (start 256.715 107.891421) (end 256.715 108.255) (width 0.122) (layer "B.Cu") (net 638))
  (segment (start 256.685079 107.820079) (end 256.685711 107.820711) (width 0.122) (layer "B.Cu") (net 638))
  (segment (start 256.08 107.95) (end 256.209922 107.820078) (width 0.122) (layer "B.Cu") (net 638))
  (arc (start 256.351343 107.7615) (mid 256.274807 107.776724) (end 256.209922 107.820078) (width 0.122) (layer "B.Cu") (net 638))
  (arc (start 256.351343 107.7615) (mid 256.274807 107.776724) (end 256.209922 107.820078) (width 0.122) (layer "B.Cu") (net 638))
  (arc (start 256.715 107.891421) (mid 256.707388 107.853153) (end 256.685711 107.820711) (width 0.122) (layer "B.Cu") (net 638))
  (arc (start 256.543657 107.7615) (mid 256.620194 107.776724) (end 256.685079 107.820079) (width 0.122) (layer "B.Cu") (net 638))
  (arc (start 256.543657 107.7615) (mid 256.620194 107.776724) (end 256.685079 107.820079) (width 0.122) (layer "B.Cu") (net 638))
  (arc (start 256.715 107.891421) (mid 256.707388 107.853153) (end 256.685711 107.820711) (width 0.122) (layer "B.Cu") (net 638))
  (segment (start 194.636328 95.060008) (end 194.136328 94.560008) (width 0.127) (layer "F.Cu") (net 639))
  (via blind (at 194.636328 95.060008) (size 0.5) (drill 0.2) (layers "F.Cu" "In2.Cu") (net 639))
  (via (at 256.08 107.286) (size 0.5) (drill 0.2) (layers "F.Cu" "B.Cu") (net 639))
  (segment (start 244.370483 103.622) (end 249.333368 103.622) (width 0.13) (layer "In2.Cu") (net 639))
  (segment (start 237.761372 94.319996) (end 240.955004 97.513628) (width 0.13) (layer "In2.Cu") (net 639))
  (segment (start 194.222328 95.279299) (end 194.222328 95.239109) (width 0.082) (layer "In2.Cu") (net 639))
  (segment (start 194.251617 95.168399) (end 194.330718 95.089298) (width 0.082) (layer "In2.Cu") (net 639))
  (segment (start 197.233727 95.519649) (end 197.143666 95.60971) (width 0.082) (layer "In2.Cu") (net 639))
  (segment (start 194.401429 95.060008) (end 194.636328 95.060008) (width 0.082) (layer "In2.Cu") (net 639))
  (segment (start 242.799447 102.258071) (end 244.01693 103.475554) (width 0.13) (layer "In2.Cu") (net 639))
  (segment (start 242.653 100.716632) (end 242.653 101.904517) (width 0.13) (layer "In2.Cu") (net 639))
  (segment (start 196.411 95.639) (end 197.072955 95.639) (width 0.082) (layer "In2.Cu") (net 639))
  (segment (start 195.126939 95.459016) (end 194.402045 95.459016) (width 0.082) (layer "In2.Cu") (net 639))
  (segment (start 201.133071 95.250553) (end 202.063628 94.319996) (width 0.13) (layer "In2.Cu") (net 639))
  (segment (start 195.811 95.639) (end 195.761 95.639) (width 0.082) (layer "In2.Cu") (net 639))
  (segment (start 249.811372 103.819996) (end 253.30993 107.318554) (width 0.13) (layer "In2.Cu") (net 639))
  (segment (start 202.541632 94.122) (end 237.283368 94.122) (width 0.13) (layer "In2.Cu") (net 639))
  (segment (start 241.299447 99.083071) (end 242.455004 100.238628) (width 0.13) (layer "In2.Cu") (net 639))
  (segment (start 198.000157 95.464) (end 197.368077 95.464) (width 0.082) (layer "In2.Cu") (net 639))
  (segment (start 253.663483 107.465) (end 255.818157 107.465) (width 0.13) (layer "In2.Cu") (net 639))
  (segment (start 195.761 95.639) (end 195.427045 95.639) (width 0.082) (layer "In2.Cu") (net 639))
  (segment (start 198.15 95.397) (end 198.141579 95.405421) (width 0.082) (layer "In2.Cu") (net 639))
  (segment (start 196.261 95.489) (end 196.261 95.438608) (width 0.082) (layer "In2.Cu") (net 639))
  (segment (start 198.15 95.397) (end 200.779517 95.397) (width 0.13) (layer "In2.Cu") (net 639))
  (segment (start 255.959579 107.406421) (end 256.08 107.286) (width 0.13) (layer "In2.Cu") (net 639))
  (segment (start 195.961 95.438608) (end 195.961 95.489) (width 0.082) (layer "In2.Cu") (net 639))
  (segment (start 194.331335 95.429727) (end 194.251618 95.35001) (width 0.082) (layer "In2.Cu") (net 639))
  (segment (start 241.153 97.991632) (end 241.153 98.729517) (width 0.13) (layer "In2.Cu") (net 639))
  (segment (start 195.356335 95.609711) (end 195.26129 95.514666) (width 0.082) (layer "In2.Cu") (net 639))
  (arc (start 202.063628 94.319996) (mid 202.282938 94.173457) (end 202.541632 94.122) (width 0.13) (layer "In2.Cu") (net 639))
  (arc (start 198.141579 95.405421) (mid 198.076694 95.448776) (end 198.000157 95.464) (width 0.082) (layer "In2.Cu") (net 639))
  (arc (start 194.251618 95.35001) (mid 194.22994 95.317568) (end 194.222328 95.279299) (width 0.082) (layer "In2.Cu") (net 639))
  (arc (start 253.30993 107.318554) (mid 253.472142 107.42694) (end 253.663483 107.465) (width 0.13) (layer "In2.Cu") (net 639))
  (arc (start 196.411 95.639) (mid 196.304934 95.595066) (end 196.261 95.489) (width 0.082) (layer "In2.Cu") (net 639))
  (arc (start 200.779517 95.397) (mid 200.970859 95.35894) (end 201.133071 95.250553) (width 0.13) (layer "In2.Cu") (net 639))
  (arc (start 255.818157 107.465) (mid 255.894694 107.449776) (end 255.959579 107.406421) (width 0.13) (layer "In2.Cu") (net 639))
  (arc (start 194.222328 95.239109) (mid 194.22994 95.200841) (end 194.251617 95.168399) (width 0.082) (layer "In2.Cu") (net 639))
  (arc (start 195.26129 95.514666) (mid 195.199649 95.473479) (end 195.126939 95.459016) (width 0.082) (layer "In2.Cu") (net 639))
  (arc (start 242.653 101.904517) (mid 242.69106 102.095859) (end 242.799447 102.258071) (width 0.13) (layer "In2.Cu") (net 639))
  (arc (start 237.283368 94.122) (mid 237.542062 94.173457) (end 237.761372 94.319996) (width 0.13) (layer "In2.Cu") (net 639))
  (arc (start 241.153 98.729517) (mid 241.19106 98.920859) (end 241.299447 99.083071) (width 0.13) (layer "In2.Cu") (net 639))
  (arc (start 249.333368 103.622) (mid 249.592062 103.673458) (end 249.811372 103.819996) (width 0.13) (layer "In2.Cu") (net 639))
  (arc (start 195.961 95.489) (mid 195.917066 95.595066) (end 195.811 95.639) (width 0.082) (layer "In2.Cu") (net 639))
  (arc (start 244.01693 103.475554) (mid 244.179142 103.58394) (end 244.370483 103.622) (width 0.13) (layer "In2.Cu") (net 639))
  (arc (start 242.455004 100.238628) (mid 242.601542 100.457938) (end 242.653 100.716632) (width 0.13) (layer "In2.Cu") (net 639))
  (arc (start 195.427045 95.639) (mid 195.388777 95.631388) (end 195.356335 95.609711) (width 0.082) (layer "In2.Cu") (net 639))
  (arc (start 196.261 95.438608) (mid 196.217066 95.332542) (end 196.111 95.288608) (width 0.082) (layer "In2.Cu") (net 639))
  (arc (start 194.402045 95.459016) (mid 194.363777 95.451404) (end 194.331335 95.429727) (width 0.082) (layer "In2.Cu") (net 639))
  (arc (start 197.368077 95.464) (mid 197.295367 95.478463) (end 197.233727 95.519649) (width 0.082) (layer "In2.Cu") (net 639))
  (arc (start 194.330718 95.089298) (mid 194.36316 95.06762) (end 194.401429 95.060008) (width 0.082) (layer "In2.Cu") (net 639))
  (arc (start 196.111 95.288608) (mid 196.004934 95.332542) (end 195.961 95.438608) (width 0.082) (layer "In2.Cu") (net 639))
  (arc (start 240.955004 97.513628) (mid 241.101543 97.732938) (end 241.153 97.991632) (width 0.13) (layer "In2.Cu") (net 639))
  (arc (start 197.143666 95.60971) (mid 197.111224 95.631388) (end 197.072955 95.639) (width 0.082) (layer "In2.Cu") (net 639))
  (segment (start 256.351343 107.4745) (end 256.527657 107.4745) (width 0.122) (layer "B.Cu") (net 639))
  (segment (start 256.08 107.286) (end 256.209922 107.415922) (width 0.122) (layer "B.Cu") (net 639))
  (segment (start 256.669079 107.415921) (end 256.685711 107.399289) (width 0.122) (layer "B.Cu") (net 639))
  (segment (start 256.715 107.328579) (end 256.715 106.985) (width 0.122) (layer "B.Cu") (net 639))
  (arc (start 256.351343 107.4745) (mid 256.274807 107.459276) (end 256.209922 107.415922) (width 0.122) (layer "B.Cu") (net 639))
  (arc (start 256.527657 107.4745) (mid 256.604194 107.459276) (end 256.669079 107.415921) (width 0.122) (layer "B.Cu") (net 639))
  (arc (start 256.527657 107.4745) (mid 256.604194 107.459276) (end 256.669079 107.415921) (width 0.122) (layer "B.Cu") (net 639))
  (arc (start 256.685711 107.399289) (mid 256.707388 107.366847) (end 256.715 107.328579) (width 0.122) (layer "B.Cu") (net 639))
  (arc (start 256.685711 107.399289) (mid 256.707388 107.366847) (end 256.715 107.328579) (width 0.122) (layer "B.Cu") (net 639))
  (arc (start 256.351343 107.4745) (mid 256.274807 107.459276) (end 256.209922 107.415922) (width 0.122) (layer "B.Cu") (net 639))
  (segment (start 193.636328 93.060008) (end 193.136328 92.560008) (width 0.127) (layer "F.Cu") (net 640))
  (via blind (at 193.636328 93.060008) (size 0.5) (drill 0.2) (layers "F.Cu" "In2.Cu") (net 640))
  (via (at 256.08 102.87) (size 0.5) (drill 0.2) (layers "F.Cu" "B.Cu") (net 640))
  (segment (start 251.726496 103.192872) (end 251.557128 103.023504) (width 0.13) (layer "In2.Cu") (net 640))
  (segment (start 194.368077 93.631016) (end 195.192971 93.631016) (width 0.082) (layer "In2.Cu") (net 640))
  (segment (start 243.788628 99.955004) (end 242.544996 98.711372) (width 0.13) (layer "In2.Cu") (net 640))
  (segment (start 256.08 102.87) (end 255.959578 102.749578) (width 0.13) (layer "In2.Cu") (net 640))
  (segment (start 238.104517 93.178) (end 199.769028 93.178) (width 0.13) (layer "In2.Cu") (net 640))
  (segment (start 251.447 102.757632) (end 251.447 102.421219) (width 0.13) (layer "In2.Cu") (net 640))
  (segment (start 194.105978 93.447618) (end 194.233727 93.575367) (width 0.082) (layer "In2.Cu") (net 640))
  (segment (start 242.200554 97.06693) (end 238.458071 93.324447) (width 0.13) (layer "In2.Cu") (net 640))
  (segment (start 254.816798 102.749578) (end 254.373504 103.192872) (width 0.13) (layer "In2.Cu") (net 640))
  (segment (start 195.418077 93.736) (end 198.000157 93.736) (width 0.082) (layer "In2.Cu") (net 640))
  (segment (start 251.388422 102.279798) (end 249.408071 100.299447) (width 0.13) (layer "In2.Cu") (net 640))
  (segment (start 198.141579 93.794579) (end 198.15 93.803) (width 0.082) (layer "In2.Cu") (net 640))
  (segment (start 193.636328 93.060008) (end 193.898571 93.060008) (width 0.082) (layer "In2.Cu") (net 640))
  (segment (start 254.107632 103.303) (end 251.992368 103.303) (width 0.13) (layer "In2.Cu") (net 640))
  (segment (start 249.054517 100.153) (end 244.266632 100.153) (width 0.13) (layer "In2.Cu") (net 640))
  (segment (start 255.818157 102.691) (end 254.958219 102.691) (width 0.13) (layer "In2.Cu") (net 640))
  (segment (start 198.999053 93.803) (end 198.15 93.803) (width 0.13) (layer "In2.Cu") (net 640))
  (segment (start 199.716702 93.199674) (end 199.194214 93.722162) (width 0.13) (layer "In2.Cu") (net 640))
  (segment (start 195.263682 93.660306) (end 195.283727 93.680351) (width 0.082) (layer "In2.Cu") (net 640))
  (segment (start 242.347 98.233368) (end 242.347 97.420483) (width 0.13) (layer "In2.Cu") (net 640))
  (segment (start 194.050328 93.211765) (end 194.050328 93.313267) (width 0.082) (layer "In2.Cu") (net 640))
  (segment (start 193.969282 93.089298) (end 194.021039 93.141055) (width 0.082) (layer "In2.Cu") (net 640))
  (arc (start 194.050328 93.211765) (mid 194.042716 93.173497) (end 194.021039 93.141055) (width 0.082) (layer "In2.Cu") (net 640))
  (arc (start 255.959578 102.749578) (mid 255.894693 102.706224) (end 255.818157 102.691) (width 0.13) (layer "In2.Cu") (net 640))
  (arc (start 242.544996 98.711372) (mid 242.398458 98.492062) (end 242.347 98.233368) (width 0.13) (layer "In2.Cu") (net 640))
  (arc (start 194.368077 93.631016) (mid 194.295367 93.616553) (end 194.233727 93.575367) (width 0.082) (layer "In2.Cu") (net 640))
  (arc (start 244.266632 100.153) (mid 244.007938 100.101542) (end 243.788628 99.955004) (width 0.13) (layer "In2.Cu") (net 640))
  (arc (start 198.000157 93.736) (mid 198.076694 93.751224) (end 198.141579 93.794579) (width 0.082) (layer "In2.Cu") (net 640))
  (arc (start 254.373504 103.192872) (mid 254.251521 103.274379) (end 254.107632 103.303) (width 0.13) (layer "In2.Cu") (net 640))
  (arc (start 249.408071 100.299447) (mid 249.245859 100.19106) (end 249.054517 100.153) (width 0.13) (layer "In2.Cu") (net 640))
  (arc (start 194.105978 93.447618) (mid 194.064791 93.385977) (end 194.050328 93.313267) (width 0.082) (layer "In2.Cu") (net 640))
  (arc (start 195.418077 93.736) (mid 195.345367 93.721537) (end 195.283727 93.680351) (width 0.082) (layer "In2.Cu") (net 640))
  (arc (start 251.557128 103.023504) (mid 251.475621 102.901521) (end 251.447 102.757632) (width 0.13) (layer "In2.Cu") (net 640))
  (arc (start 254.958219 102.691) (mid 254.881683 102.706224) (end 254.816798 102.749578) (width 0.13) (layer "In2.Cu") (net 640))
  (arc (start 195.192971 93.631016) (mid 195.23124 93.638628) (end 195.263682 93.660306) (width 0.082) (layer "In2.Cu") (net 640))
  (arc (start 199.716702 93.199674) (mid 199.740709 93.183633) (end 199.769028 93.178) (width 0.13) (layer "In2.Cu") (net 640))
  (arc (start 251.447 102.421219) (mid 251.431776 102.344683) (end 251.388422 102.279798) (width 0.13) (layer "In2.Cu") (net 640))
  (arc (start 193.898571 93.060008) (mid 193.93684 93.06762) (end 193.969282 93.089298) (width 0.082) (layer "In2.Cu") (net 640))
  (arc (start 199.194214 93.722162) (mid 199.104673 93.781991) (end 198.999053 93.803) (width 0.13) (layer "In2.Cu") (net 640))
  (arc (start 251.992368 103.303) (mid 251.848479 103.274379) (end 251.726496 103.192872) (width 0.13) (layer "In2.Cu") (net 640))
  (arc (start 242.347 97.420483) (mid 242.30894 97.229142) (end 242.200554 97.06693) (width 0.13) (layer "In2.Cu") (net 640))
  (arc (start 238.458071 93.324447) (mid 238.295859 93.21606) (end 238.104517 93.178) (width 0.13) (layer "In2.Cu") (net 640))
  (segment (start 256.685079 102.740079) (end 256.685711 102.740711) (width 0.122) (layer "B.Cu") (net 640))
  (segment (start 256.08 102.87) (end 256.209922 102.740078) (width 0.122) (layer "B.Cu") (net 640))
  (segment (start 256.351343 102.6815) (end 256.543657 102.6815) (width 0.122) (layer "B.Cu") (net 640))
  (segment (start 256.715 102.811421) (end 256.715 103.175) (width 0.122) (layer "B.Cu") (net 640))
  (arc (start 256.543657 102.6815) (mid 256.620194 102.696724) (end 256.685079 102.740079) (width 0.122) (layer "B.Cu") (net 640))
  (arc (start 256.351343 102.6815) (mid 256.274807 102.696724) (end 256.209922 102.740078) (width 0.122) (layer "B.Cu") (net 640))
  (arc (start 256.715 102.811421) (mid 256.707388 102.773153) (end 256.685711 102.740711) (width 0.122) (layer "B.Cu") (net 640))
  (segment (start 194.636328 93.060008) (end 194.136328 92.560008) (width 0.127) (layer "F.Cu") (net 641))
  (via blind (at 194.636328 93.060008) (size 0.5) (drill 0.2) (layers "F.Cu" "In2.Cu") (net 641))
  (via (at 256.08 102.206) (size 0.5) (drill 0.2) (layers "F.Cu" "B.Cu") (net 641))
  (segment (start 194.330718 93.089298) (end 194.251617 93.168399) (width 0.082) (layer "In2.Cu") (net 641))
  (segment (start 252.046219 102.997) (end 254.053781 102.997) (width 0.13) (layer "In2.Cu") (net 641))
  (segment (start 198.141579 93.505421) (end 198.15 93.497) (width 0.082) (layer "In2.Cu") (net 641))
  (segment (start 194.222328 93.239109) (end 194.222328 93.279299) (width 0.082) (layer "In2.Cu") (net 641))
  (segment (start 199.71518 92.872) (end 238.158368 92.872) (width 0.13) (layer "In2.Cu") (net 641))
  (segment (start 242.653 97.366632) (end 242.653 98.179517) (width 0.13) (layer "In2.Cu") (net 641))
  (segment (start 242.799447 98.533071) (end 243.96693 99.700554) (width 0.13) (layer "In2.Cu") (net 641))
  (segment (start 238.636372 93.069996) (end 242.455004 96.888628) (width 0.13) (layer "In2.Cu") (net 641))
  (segment (start 196.381 93.372958) (end 196.381 93.389) (width 0.082) (layer "In2.Cu") (net 641))
  (segment (start 196.031 93.389) (end 196.031 93.372958) (width 0.082) (layer "In2.Cu") (net 641))
  (segment (start 251.811579 102.845203) (end 251.904798 102.938422) (width 0.13) (layer "In2.Cu") (net 641))
  (segment (start 254.904368 102.385) (end 255.818157 102.385) (width 0.13) (layer "In2.Cu") (net 641))
  (segment (start 249.586372 100.044996) (end 251.642872 102.101496) (width 0.13) (layer "In2.Cu") (net 641))
  (segment (start 198.15 93.497) (end 198.945203 93.497) (width 0.13) (layer "In2.Cu") (net 641))
  (segment (start 196.556 93.564) (end 198.000157 93.564) (width 0.082) (layer "In2.Cu") (net 641))
  (segment (start 194.636328 93.060008) (end 194.401429 93.060008) (width 0.082) (layer "In2.Cu") (net 641))
  (segment (start 195.36129 93.514666) (end 195.381335 93.534711) (width 0.082) (layer "In2.Cu") (net 641))
  (segment (start 251.753 102.367368) (end 251.753 102.703781) (width 0.13) (layer "In2.Cu") (net 641))
  (segment (start 244.320483 99.847) (end 249.108368 99.847) (width 0.13) (layer "In2.Cu") (net 641))
  (segment (start 195.452045 93.564) (end 195.856 93.564) (width 0.082) (layer "In2.Cu") (net 641))
  (segment (start 255.959579 102.326421) (end 256.08 102.206) (width 0.13) (layer "In2.Cu") (net 641))
  (segment (start 199.015914 93.46771) (end 199.015917 93.46771) (width 0.13) (layer "In2.Cu") (net 641))
  (segment (start 199.015917 93.46771) (end 199.5384 92.945227) (width 0.13) (layer "In2.Cu") (net 641))
  (segment (start 254.195203 102.938421) (end 254.638496 102.495128) (width 0.13) (layer "In2.Cu") (net 641))
  (segment (start 194.251618 93.35001) (end 194.331335 93.429727) (width 0.082) (layer "In2.Cu") (net 641))
  (segment (start 194.402045 93.459016) (end 195.226939 93.459016) (width 0.082) (layer "In2.Cu") (net 641))
  (arc (start 254.638496 102.495128) (mid 254.760479 102.413621) (end 254.904368 102.385) (width 0.13) (layer "In2.Cu") (net 641))
  (arc (start 194.251617 93.168399) (mid 194.22994 93.200841) (end 194.222328 93.239109) (width 0.082) (layer "In2.Cu") (net 641))
  (arc (start 196.381 93.389) (mid 196.432256 93.512744) (end 196.556 93.564) (width 0.082) (layer "In2.Cu") (net 641))
  (arc (start 199.5384 92.945227) (mid 199.619507 92.891031) (end 199.71518 92.872) (width 0.13) (layer "In2.Cu") (net 641))
  (arc (start 238.158368 92.872) (mid 238.417062 92.923457) (end 238.636372 93.069996) (width 0.13) (layer "In2.Cu") (net 641))
  (arc (start 195.856 93.564) (mid 195.979744 93.512744) (end 196.031 93.389) (width 0.082) (layer "In2.Cu") (net 641))
  (arc (start 198.000157 93.564) (mid 198.076694 93.548776) (end 198.141579 93.505421) (width 0.082) (layer "In2.Cu") (net 641))
  (arc (start 194.222328 93.279299) (mid 194.22994 93.317568) (end 194.251618 93.35001) (width 0.082) (layer "In2.Cu") (net 641))
  (arc (start 196.206 93.197958) (mid 196.329744 93.249214) (end 196.381 93.372958) (width 0.082) (layer "In2.Cu") (net 641))
  (arc (start 243.96693 99.700554) (mid 244.129142 99.80894) (end 244.320483 99.847) (width 0.13) (layer "In2.Cu") (net 641))
  (arc (start 198.945203 93.497) (mid 198.983472 93.489389) (end 199.015914 93.46771) (width 0.13) (layer "In2.Cu") (net 641))
  (arc (start 242.455004 96.888628) (mid 242.601543 97.107938) (end 242.653 97.366632) (width 0.13) (layer "In2.Cu") (net 641))
  (arc (start 254.053781 102.997) (mid 254.130318 102.981776) (end 254.195203 102.938421) (width 0.13) (layer "In2.Cu") (net 641))
  (arc (start 251.642872 102.101496) (mid 251.724379 102.223479) (end 251.753 102.367368) (width 0.13) (layer "In2.Cu") (net 641))
  (arc (start 255.818157 102.385) (mid 255.894694 102.369776) (end 255.959579 102.326421) (width 0.13) (layer "In2.Cu") (net 641))
  (arc (start 251.753 102.703781) (mid 251.768224 102.780318) (end 251.811579 102.845203) (width 0.13) (layer "In2.Cu") (net 641))
  (arc (start 195.381335 93.534711) (mid 195.413777 93.556388) (end 195.452045 93.564) (width 0.082) (layer "In2.Cu") (net 641))
  (arc (start 196.031 93.372958) (mid 196.082256 93.249214) (end 196.206 93.197958) (width 0.082) (layer "In2.Cu") (net 641))
  (arc (start 249.108368 99.847) (mid 249.367062 99.898457) (end 249.586372 100.044996) (width 0.13) (layer "In2.Cu") (net 641))
  (arc (start 242.653 98.179517) (mid 242.69106 98.370859) (end 242.799447 98.533071) (width 0.13) (layer "In2.Cu") (net 641))
  (arc (start 251.904798 102.938422) (mid 251.969683 102.981776) (end 252.046219 102.997) (width 0.13) (layer "In2.Cu") (net 641))
  (arc (start 194.401429 93.060008) (mid 194.36316 93.06762) (end 194.330718 93.089298) (width 0.082) (layer "In2.Cu") (net 641))
  (arc (start 194.331335 93.429727) (mid 194.363777 93.451404) (end 194.402045 93.459016) (width 0.082) (layer "In2.Cu") (net 641))
  (arc (start 195.226939 93.459016) (mid 195.299649 93.473479) (end 195.36129 93.514666) (width 0.082) (layer "In2.Cu") (net 641))
  (segment (start 256.715 102.248579) (end 256.715 101.905) (width 0.122) (layer "B.Cu") (net 641))
  (segment (start 256.669079 102.335921) (end 256.685711 102.319289) (width 0.122) (layer "B.Cu") (net 641))
  (segment (start 256.351343 102.3945) (end 256.527657 102.3945) (width 0.122) (layer "B.Cu") (net 641))
  (segment (start 256.08 102.206) (end 256.209922 102.335922) (width 0.122) (layer "B.Cu") (net 641))
  (arc (start 256.685711 102.319289) (mid 256.707388 102.286847) (end 256.715 102.248579) (width 0.122) (layer "B.Cu") (net 641))
  (arc (start 256.527657 102.3945) (mid 256.604194 102.379276) (end 256.669079 102.335921) (width 0.122) (layer "B.Cu") (net 641))
  (arc (start 256.351343 102.3945) (mid 256.274807 102.379276) (end 256.209922 102.335922) (width 0.122) (layer "B.Cu") (net 641))
  (segment (start 121.936328 104.940008) (end 121.936328 103.990008) (width 0.2) (layer "F.Cu") (net 642))
  (segment (start 121.936328 103.990008) (end 121.926328 103.980008) (width 0.2) (layer "F.Cu") (net 642))
  (via (at 121.926328 103.980008) (size 0.5) (drill 0.2) (layers "F.Cu" "B.Cu") (net 642))
  (segment (start 122.736328 103.985008) (end 121.931328 103.985008) (width 0.2) (layer "B.Cu") (net 642))
  (segment (start 121.931328 103.985008) (end 121.926328 103.980008) (width 0.2) (layer "B.Cu") (net 642))
  (segment (start 133.636328 92.710008) (end 134.086328 93.160008) (width 0.2) (layer "F.Cu") (net 643))
  (segment (start 134.086328 93.160008) (end 134.386328 93.160008) (width 0.2) (layer "F.Cu") (net 643))
  (via (at 134.386328 93.160008) (size 0.5) (drill 0.2) (layers "F.Cu" "B.Cu") (net 643))
  (segment (start 134.386328 93.825008) (end 134.386328 93.160008) (width 0.2) (layer "B.Cu") (net 643))
  (segment (start 193.636328 89.060008) (end 193.136328 88.560008) (width 0.127) (layer "F.Cu") (net 645))
  (via blind (at 193.636328 89.060008) (size 0.5) (drill 0.2) (layers "F.Cu" "In2.Cu") (net 645))
  (via (at 254.81 110.49) (size 0.5) (drill 0.2) (layers "F.Cu" "B.Cu") (net 645))
  (segment (start 195.716274 88.54465) (end 196.212682 89.041058) (width 0.082) (layer "In2.Cu") (net 645))
  (segment (start 252.991929 94.450553) (end 250.961372 92.419996) (width 0.13) (layer "In2.Cu") (net 645))
  (segment (start 257.473 97.40236) (end 257.473 96.050271) (width 0.13) (layer "In2.Cu") (net 645))
  (segment (start 257.333583 95.713688) (end 256.293082 94.673187) (width 0.13) (layer "In2.Cu") (net 645))
  (segment (start 258.383583 98.437207) (end 257.560868 97.614492) (width 0.13) (layer "In2.Cu") (net 645))
  (segment (start 258.133 105.21621) (end 258.133 101.99764) (width 0.13) (layer "In2.Cu") (net 645))
  (segment (start 200.733368 88.997) (end 198.15 88.997) (width 0.13) (layer "In2.Cu") (net 645))
  (segment (start 241.766929 92.075553) (end 240.236372 90.544996) (width 0.13) (layer "In2.Cu") (net 645))
  (segment (start 258.220868 101.785508) (end 258.383583 101.622793) (width 0.13) (layer "In2.Cu") (net 645))
  (segment (start 194.368077 88.489) (end 195.581923 88.489) (width 0.082) (layer "In2.Cu") (net 645))
  (segment (start 254.81 110.49) (end 254.930422 110.369578) (width 0.13) (layer "In2.Cu") (net 645))
  (segment (start 239.758368 90.347) (end 202.570483 90.347) (width 0.13) (layer "In2.Cu") (net 645))
  (segment (start 193.969282 89.030718) (end 194.021039 88.978961) (width 0.082) (layer "In2.Cu") (net 645))
  (segment (start 257.553 109.732632) (end 257.553 106.11764) (width 0.13) (layer "In2.Cu") (net 645))
  (segment (start 193.636328 89.060008) (end 193.898571 89.060008) (width 0.082) (layer "In2.Cu") (net 645))
  (segment (start 256.293082 94.673187) (end 256.287685 94.673187) (width 0.13) (layer "In2.Cu") (net 645))
  (segment (start 202.216929 90.200553) (end 201.211372 89.194996) (width 0.13) (layer "In2.Cu") (net 645))
  (segment (start 257.240504 110.200872) (end 257.442872 109.998504) (width 0.13) (layer "In2.Cu") (net 645))
  (segment (start 256.057632 94.597) (end 253.345483 94.597) (width 0.13) (layer "In2.Cu") (net 645))
  (segment (start 257.640868 105.905508) (end 257.993583 105.552793) (width 0.13) (layer "In2.Cu") (net 645))
  (segment (start 194.105978 88.672398) (end 194.233727 88.544649) (width 0.082) (layer "In2.Cu") (net 645))
  (segment (start 258.523 101.28621) (end 258.523 98.77379) (width 0.13) (layer "In2.Cu") (net 645))
  (segment (start 250.483368 92.222) (end 242.120483 92.222) (width 0.13) (layer "In2.Cu") (net 645))
  (segment (start 198.135232 89.011768) (end 198.15 88.997) (width 0.082) (layer "In2.Cu") (net 645))
  (segment (start 196.283392 89.070347) (end 197.99381 89.070347) (width 0.082) (layer "In2.Cu") (net 645))
  (segment (start 255.071843 110.311) (end 256.974632 110.311) (width 0.13) (layer "In2.Cu") (net 645))
  (segment (start 194.050328 88.908251) (end 194.050328 88.806749) (width 0.082) (layer "In2.Cu") (net 645))
  (arc (start 202.570483 90.347) (mid 202.379141 90.30894) (end 202.216929 90.200553) (width 0.13) (layer "In2.Cu") (net 645))
  (arc (start 250.961372 92.419996) (mid 250.742062 92.273457) (end 250.483368 92.222) (width 0.13) (layer "In2.Cu") (net 645))
  (arc (start 257.473 96.050271) (mid 257.436767 95.868114) (end 257.333583 95.713688) (width 0.13) (layer "In2.Cu") (net 645))
  (arc (start 240.236372 90.544996) (mid 240.017062 90.398458) (end 239.758368 90.347) (width 0.13) (layer "In2.Cu") (net 645))
  (arc (start 194.105978 88.672398) (mid 194.064791 88.734039) (end 194.050328 88.806749) (width 0.082) (layer "In2.Cu") (net 645))
  (arc (start 257.553 106.11764) (mid 257.575836 106.002835) (end 257.640868 105.905508) (width 0.13) (layer "In2.Cu") (net 645))
  (arc (start 258.133 105.21621) (mid 258.096767 105.398367) (end 257.993583 105.552793) (width 0.13) (layer "In2.Cu") (net 645))
  (arc (start 256.974632 110.311) (mid 257.118521 110.282379) (end 257.240504 110.200872) (width 0.13) (layer "In2.Cu") (net 645))
  (arc (start 253.345483 94.597) (mid 253.154141 94.55894) (end 252.991929 94.450553) (width 0.13) (layer "In2.Cu") (net 645))
  (arc (start 194.233727 88.544649) (mid 194.295367 88.503462) (end 194.368077 88.489) (width 0.082) (layer "In2.Cu") (net 645))
  (arc (start 193.969282 89.030718) (mid 193.93684 89.052396) (end 193.898571 89.060008) (width 0.082) (layer "In2.Cu") (net 645))
  (arc (start 198.135232 89.011768) (mid 198.070347 89.055123) (end 197.99381 89.070347) (width 0.082) (layer "In2.Cu") (net 645))
  (arc (start 242.120483 92.222) (mid 241.929141 92.18394) (end 241.766929 92.075553) (width 0.13) (layer "In2.Cu") (net 645))
  (arc (start 258.133 101.99764) (mid 258.155836 101.882835) (end 258.220868 101.785508) (width 0.13) (layer "In2.Cu") (net 645))
  (arc (start 258.383583 101.622793) (mid 258.486767 101.468367) (end 258.523 101.28621) (width 0.13) (layer "In2.Cu") (net 645))
  (arc (start 254.930422 110.369578) (mid 254.995307 110.326224) (end 255.071843 110.311) (width 0.13) (layer "In2.Cu") (net 645))
  (arc (start 196.212682 89.041058) (mid 196.245124 89.062735) (end 196.283392 89.070347) (width 0.082) (layer "In2.Cu") (net 645))
  (arc (start 256.287685 94.673187) (mid 256.178488 94.616963) (end 256.057632 94.597) (width 0.13) (layer "In2.Cu") (net 645))
  (arc (start 194.050328 88.908251) (mid 194.042716 88.946519) (end 194.021039 88.978961) (width 0.082) (layer "In2.Cu") (net 645))
  (arc (start 201.211372 89.194996) (mid 200.992062 89.048458) (end 200.733368 88.997) (width 0.13) (layer "In2.Cu") (net 645))
  (arc (start 257.560868 97.614492) (mid 257.495836 97.517165) (end 257.473 97.40236) (width 0.13) (layer "In2.Cu") (net 645))
  (arc (start 195.716274 88.54465) (mid 195.654633 88.503463) (end 195.581923 88.489) (width 0.082) (layer "In2.Cu") (net 645))
  (arc (start 258.523 98.77379) (mid 258.486767 98.591633) (end 258.383583 98.437207) (width 0.13) (layer "In2.Cu") (net 645))
  (arc (start 257.442872 109.998504) (mid 257.524379 109.876521) (end 257.553 109.732632) (width 0.13) (layer "In2.Cu") (net 645))
  (segment (start 255.415079 110.360079) (end 255.415711 110.360711) (width 0.122) (layer "B.Cu") (net 645))
  (segment (start 254.81 110.49) (end 254.939922 110.360078) (width 0.122) (layer "B.Cu") (net 645))
  (segment (start 255.081343 110.3015) (end 255.273657 110.3015) (width 0.122) (layer "B.Cu") (net 645))
  (segment (start 255.445 110.431421) (end 255.445 110.795) (width 0.122) (layer "B.Cu") (net 645))
  (arc (start 255.081343 110.3015) (mid 255.004807 110.316724) (end 254.939922 110.360078) (width 0.122) (layer "B.Cu") (net 645))
  (arc (start 255.273657 110.3015) (mid 255.350194 110.316724) (end 255.415079 110.360079) (width 0.122) (layer "B.Cu") (net 645))
  (arc (start 255.445 110.431421) (mid 255.437388 110.393153) (end 255.415711 110.360711) (width 0.122) (layer "B.Cu") (net 645))
  (segment (start 194.636328 89.060008) (end 194.136328 88.560008) (width 0.127) (layer "F.Cu") (net 646))
  (via blind (at 194.636328 89.060008) (size 0.5) (drill 0.2) (layers "F.Cu" "In2.Cu") (net 646))
  (via (at 254.81 109.826) (size 0.5) (drill 0.2) (layers "F.Cu" "B.Cu") (net 646))
  (segment (start 195.618666 88.69029) (end 195.672863 88.744487) (width 0.082) (layer "In2.Cu") (net 646))
  (segment (start 241.588628 92.330004) (end 240.058071 90.799447) (width 0.13) (layer "In2.Cu") (net 646))
  (segment (start 202.038628 90.455004) (end 201.033071 89.449447) (width 0.13) (layer "In2.Cu") (net 646))
  (segment (start 195.349 88.833761) (end 195.349 88.811) (width 0.082) (layer "In2.Cu") (net 646))
  (segment (start 252.813628 94.705004) (end 250.783071 92.674447) (width 0.13) (layer "In2.Cu") (net 646))
  (segment (start 255.067 94.903) (end 253.291632 94.903) (width 0.13) (layer "In2.Cu") (net 646))
  (segment (start 195.672863 88.744487) (end 196.115074 89.186698) (width 0.082) (layer "In2.Cu") (net 646))
  (segment (start 257.025709 108.873) (end 257.047 108.873) (width 0.13) (layer "In2.Cu") (net 646))
  (segment (start 195.049 88.811) (end 195.049 88.833761) (width 0.082) (layer "In2.Cu") (net 646))
  (segment (start 194.636328 89.060008) (end 194.401429 89.060008) (width 0.082) (layer "In2.Cu") (net 646))
  (segment (start 194.251618 88.770006) (end 194.331335 88.690289) (width 0.082) (layer "In2.Cu") (net 646))
  (segment (start 255.267 95.118714) (end 255.267 95.103) (width 0.13) (layer "In2.Cu") (net 646))
  (segment (start 194.402045 88.661) (end 194.899 88.661) (width 0.082) (layer "In2.Cu") (net 646))
  (segment (start 257.167 97.45621) (end 257.167 96.104121) (width 0.13) (layer "In2.Cu") (net 646))
  (segment (start 257.047 109.273) (end 257.025709 109.273) (width 0.13) (layer "In2.Cu") (net 646))
  (segment (start 194.330718 89.030718) (end 194.251617 88.951617) (width 0.082) (layer "In2.Cu") (net 646))
  (segment (start 195.499 88.661) (end 195.547955 88.661) (width 0.082) (layer "In2.Cu") (net 646))
  (segment (start 200.679517 89.303) (end 198.15 89.303) (width 0.13) (layer "In2.Cu") (net 646))
  (segment (start 257.062202 109.946422) (end 257.188421 109.820203) (width 0.13) (layer "In2.Cu") (net 646))
  (segment (start 250.429517 92.528) (end 242.066632 92.528) (width 0.13) (layer "In2.Cu") (net 646))
  (segment (start 257.966417 101.607207) (end 258.129132 101.444492) (width 0.13) (layer "In2.Cu") (net 646))
  (segment (start 257.247 109.678781) (end 257.247 109.473) (width 0.13) (layer "In2.Cu") (net 646))
  (segment (start 258.129132 98.615508) (end 257.306417 97.792793) (width 0.13) (layer "In2.Cu") (net 646))
  (segment (start 239.704517 90.653) (end 202.516632 90.653) (width 0.13) (layer "In2.Cu") (net 646))
  (segment (start 257.386417 105.727207) (end 257.739132 105.374492) (width 0.13) (layer "In2.Cu") (net 646))
  (segment (start 257.827 105.16236) (end 257.827 101.94379) (width 0.13) (layer "In2.Cu") (net 646))
  (segment (start 256.003781 94.903) (end 255.867 94.903) (width 0.13) (layer "In2.Cu") (net 646))
  (segment (start 254.81 109.826) (end 254.930421 109.946421) (width 0.13) (layer "In2.Cu") (net 646))
  (segment (start 255.667 95.103) (end 255.667 95.118714) (width 0.13) (layer "In2.Cu") (net 646))
  (segment (start 257.247 108.673) (end 257.247 108.623) (width 0.13) (layer "In2.Cu") (net 646))
  (segment (start 258.217 101.23236) (end 258.217 98.82764) (width 0.13) (layer "In2.Cu") (net 646))
  (segment (start 194.222328 88.880907) (end 194.222328 88.840717) (width 0.082) (layer "In2.Cu") (net 646))
  (segment (start 198.147926 89.300926) (end 198.15 89.303) (width 0.082) (layer "In2.Cu") (net 646))
  (segment (start 256.121392 94.934249) (end 256.116539 94.934249) (width 0.13) (layer "In2.Cu") (net 646))
  (segment (start 255.071843 110.005) (end 256.920781 110.005) (width 0.13) (layer "In2.Cu") (net 646))
  (segment (start 257.079132 95.891989) (end 256.121392 94.934249) (width 0.13) (layer "In2.Cu") (net 646))
  (segment (start 196.249424 89.242347) (end 198.006504 89.242347) (width 0.082) (layer "In2.Cu") (net 646))
  (segment (start 257.247 108.623) (end 257.247 106.06379) (width 0.13) (layer "In2.Cu") (net 646))
  (arc (start 195.199 88.983761) (mid 195.305066 88.939827) (end 195.349 88.833761) (width 0.082) (layer "In2.Cu") (net 646))
  (arc (start 256.116539 94.934249) (mid 256.061841 94.911607) (end 256.003781 94.903) (width 0.13) (layer "In2.Cu") (net 646))
  (arc (start 257.247 106.06379) (mid 257.283233 105.881633) (end 257.386417 105.727207) (width 0.13) (layer "In2.Cu") (net 646))
  (arc (start 202.516632 90.653) (mid 202.257938 90.601542) (end 202.038628 90.455004) (width 0.13) (layer "In2.Cu") (net 646))
  (arc (start 257.047 108.873) (mid 257.188421 108.814421) (end 257.247 108.673) (width 0.13) (layer "In2.Cu") (net 646))
  (arc (start 194.222328 88.840717) (mid 194.22994 88.802448) (end 194.251618 88.770006) (width 0.082) (layer "In2.Cu") (net 646))
  (arc (start 256.920781 110.005) (mid 256.997317 109.989776) (end 257.062202 109.946422) (width 0.13) (layer "In2.Cu") (net 646))
  (arc (start 196.115074 89.186698) (mid 196.176714 89.227885) (end 196.249424 89.242347) (width 0.082) (layer "In2.Cu") (net 646))
  (arc (start 194.401429 89.060008) (mid 194.36316 89.052396) (end 194.330718 89.030718) (width 0.082) (layer "In2.Cu") (net 646))
  (arc (start 250.783071 92.674447) (mid 250.620859 92.56606) (end 250.429517 92.528) (width 0.13) (layer "In2.Cu") (net 646))
  (arc (start 255.867 94.903) (mid 255.725579 94.961579) (end 255.667 95.103) (width 0.13) (layer "In2.Cu") (net 646))
  (arc (start 201.033071 89.449447) (mid 200.870859 89.34106) (end 200.679517 89.303) (width 0.13) (layer "In2.Cu") (net 646))
  (arc (start 257.827 101.94379) (mid 257.863233 101.761633) (end 257.966417 101.607207) (width 0.13) (layer "In2.Cu") (net 646))
  (arc (start 198.006504 89.242347) (mid 198.083041 89.257571) (end 198.147926 89.300926) (width 0.082) (layer "In2.Cu") (net 646))
  (arc (start 255.467 95.318714) (mid 255.325579 95.260135) (end 255.267 95.118714) (width 0.13) (layer "In2.Cu") (net 646))
  (arc (start 195.547955 88.661) (mid 195.586224 88.668612) (end 195.618666 88.69029) (width 0.082) (layer "In2.Cu") (net 646))
  (arc (start 255.267 95.103) (mid 255.208421 94.961579) (end 255.067 94.903) (width 0.13) (layer "In2.Cu") (net 646))
  (arc (start 194.899 88.661) (mid 195.005066 88.704934) (end 195.049 88.811) (width 0.082) (layer "In2.Cu") (net 646))
  (arc (start 257.306417 97.792793) (mid 257.203233 97.638367) (end 257.167 97.45621) (width 0.13) (layer "In2.Cu") (net 646))
  (arc (start 256.825709 109.073) (mid 256.884288 108.931579) (end 257.025709 108.873) (width 0.13) (layer "In2.Cu") (net 646))
  (arc (start 242.066632 92.528) (mid 241.807938 92.476543) (end 241.588628 92.330004) (width 0.13) (layer "In2.Cu") (net 646))
  (arc (start 258.129132 101.444492) (mid 258.194164 101.347165) (end 258.217 101.23236) (width 0.13) (layer "In2.Cu") (net 646))
  (arc (start 194.331335 88.690289) (mid 194.363777 88.668612) (end 194.402045 88.661) (width 0.082) (layer "In2.Cu") (net 646))
  (arc (start 257.247 109.473) (mid 257.188421 109.331579) (end 257.047 109.273) (width 0.13) (layer "In2.Cu") (net 646))
  (arc (start 257.739132 105.374492) (mid 257.804164 105.277165) (end 257.827 105.16236) (width 0.13) (layer "In2.Cu") (net 646))
  (arc (start 195.049 88.833761) (mid 195.092934 88.939827) (end 195.199 88.983761) (width 0.082) (layer "In2.Cu") (net 646))
  (arc (start 240.058071 90.799447) (mid 239.895859 90.69106) (end 239.704517 90.653) (width 0.13) (layer "In2.Cu") (net 646))
  (arc (start 257.025709 109.273) (mid 256.884288 109.214421) (end 256.825709 109.073) (width 0.13) (layer "In2.Cu") (net 646))
  (arc (start 254.930421 109.946421) (mid 254.995306 109.989776) (end 255.071843 110.005) (width 0.13) (layer "In2.Cu") (net 646))
  (arc (start 194.251617 88.951617) (mid 194.22994 88.919175) (end 194.222328 88.880907) (width 0.082) (layer "In2.Cu") (net 646))
  (arc (start 257.167 96.104121) (mid 257.144164 95.989316) (end 257.079132 95.891989) (width 0.13) (layer "In2.Cu") (net 646))
  (arc (start 255.667 95.118714) (mid 255.608421 95.260135) (end 255.467 95.318714) (width 0.13) (layer "In2.Cu") (net 646))
  (arc (start 253.291632 94.903) (mid 253.032938 94.851542) (end 252.813628 94.705004) (width 0.13) (layer "In2.Cu") (net 646))
  (arc (start 195.349 88.811) (mid 195.392934 88.704934) (end 195.499 88.661) (width 0.082) (layer "In2.Cu") (net 646))
  (arc (start 258.217 98.82764) (mid 258.194164 98.712835) (end 258.129132 98.615508) (width 0.13) (layer "In2.Cu") (net 646))
  (arc (start 257.188421 109.820203) (mid 257.231776 109.755318) (end 257.247 109.678781) (width 0.13) (layer "In2.Cu") (net 646))
  (segment (start 255.399079 109.955921) (end 255.415711 109.939289) (width 0.122) (layer "B.Cu") (net 646))
  (segment (start 255.081343 110.0145) (end 255.257657 110.0145) (width 0.122) (layer "B.Cu") (net 646))
  (segment (start 254.81 109.826) (end 254.939922 109.955922) (width 0.122) (layer "B.Cu") (net 646))
  (segment (start 255.445 109.868579) (end 255.445 109.525) (width 0.122) (layer "B.Cu") (net 646))
  (arc (start 255.257657 110.0145) (mid 255.334194 109.999276) (end 255.399079 109.955921) (width 0.122) (layer "B.Cu") (net 646))
  (arc (start 255.415711 109.939289) (mid 255.437388 109.906847) (end 255.445 109.868579) (width 0.122) (layer "B.Cu") (net 646))
  (arc (start 255.081343 110.0145) (mid 255.004807 109.999276) (end 254.939922 109.955922) (width 0.122) (layer "B.Cu") (net 646))
  (segment (start 193.636328 91.060008) (end 193.136328 90.560008) (width 0.127) (layer "F.Cu") (net 647))
  (via (at 254.81 105.41) (size 0.5) (drill 0.2) (layers "F.Cu" "B.Cu") (net 647))
  (via blind (at 193.636328 91.060008) (size 0.5) (drill 0.2) (layers "F.Cu" "In2.Cu") (net 647))
  (segment (start 193.969282 91.030718) (end 194.021039 90.978961) (width 0.082) (layer "In2.Cu") (net 647))
  (segment (start 239.477201 91.785825) (end 243.59193 95.900554) (width 0.13) (layer "In2.Cu") (net 647))
  (segment (start 200.411312 91.587829) (end 238.999197 91.587829) (width 0.13) (layer "In2.Cu") (net 647))
  (segment (start 256.000342 105.231) (end 255.051132 105.231) (width 0.13) (layer "In2.Cu") (net 647))
  (segment (start 256.978 99.497368) (end 256.978 104.253342) (width 0.13) (layer "In2.Cu") (net 647))
  (segment (start 250.033504 96.157128) (end 250.444798 96.568422) (width 0.13) (layer "In2.Cu") (net 647))
  (segment (start 194.368077 90.489) (end 198.028213 90.489) (width 0.082) (layer "In2.Cu") (net 647))
  (segment (start 198.18 90.420056) (end 198.880688 90.420056) (width 0.13) (layer "In2.Cu") (net 647))
  (segment (start 254.945066 105.274934) (end 254.81 105.41) (width 0.13) (layer "In2.Cu") (net 647))
  (segment (start 193.636328 91.060008) (end 193.898571 91.060008) (width 0.082) (layer "In2.Cu") (net 647))
  (segment (start 194.050328 90.908251) (end 194.050328 90.806749) (width 0.082) (layer "In2.Cu") (net 647))
  (segment (start 199.14656 90.530184) (end 200.057759 91.441383) (width 0.13) (layer "In2.Cu") (net 647))
  (segment (start 194.105978 90.672398) (end 194.233727 90.544649) (width 0.082) (layer "In2.Cu") (net 647))
  (segment (start 255.773504 98.707128) (end 255.904798 98.838422) (width 0.13) (layer "In2.Cu") (net 647))
  (segment (start 256.046219 98.897) (end 256.377632 98.897) (width 0.13) (layer "In2.Cu") (net 647))
  (segment (start 198.169635 90.430421) (end 198.18 90.420056) (width 0.082) (layer "In2.Cu") (net 647))
  (segment (start 243.945483 96.047) (end 249.767632 96.047) (width 0.13) (layer "In2.Cu") (net 647))
  (segment (start 254.166219 98.597) (end 255.507632 98.597) (width 0.13) (layer "In2.Cu") (net 647))
  (segment (start 252.171955 96.685579) (end 254.024798 98.538422) (width 0.13) (layer "In2.Cu") (net 647))
  (segment (start 256.882517 104.483859) (end 256.230859 105.135517) (width 0.13) (layer "In2.Cu") (net 647))
  (segment (start 250.586219 96.627) (end 252.030533 96.627) (width 0.13) (layer "In2.Cu") (net 647))
  (segment (start 256.643504 99.007128) (end 256.867872 99.231496) (width 0.13) (layer "In2.Cu") (net 647))
  (arc (start 256.978 99.497368) (mid 256.949379 99.353479) (end 256.867872 99.231496) (width 0.13) (layer "In2.Cu") (net 647))
  (arc (start 200.057759 91.441383) (mid 200.219971 91.549769) (end 200.411312 91.587829) (width 0.13) (layer "In2.Cu") (net 647))
  (arc (start 194.368077 90.489) (mid 194.295367 90.503463) (end 194.233727 90.544649) (width 0.082) (layer "In2.Cu") (net 647))
  (arc (start 255.507632 98.597) (mid 255.651521 98.625621) (end 255.773504 98.707128) (width 0.13) (layer "In2.Cu") (net 647))
  (arc (start 198.169635 90.430421) (mid 198.10475 90.473776) (end 198.028213 90.489) (width 0.082) (layer "In2.Cu") (net 647))
  (arc (start 256.978 104.253342) (mid 256.953185 104.378097) (end 256.882517 104.483859) (width 0.13) (layer "In2.Cu") (net 647))
  (arc (start 243.59193 95.900554) (mid 243.754142 96.00894) (end 243.945483 96.047) (width 0.13) (layer "In2.Cu") (net 647))
  (arc (start 252.171955 96.685579) (mid 252.10707 96.642224) (end 252.030533 96.627) (width 0.13) (layer "In2.Cu") (net 647))
  (arc (start 255.051132 105.231) (mid 254.993729 105.242418) (end 254.945066 105.274934) (width 0.13) (layer "In2.Cu") (net 647))
  (arc (start 193.969282 91.030718) (mid 193.93684 91.052396) (end 193.898571 91.060008) (width 0.082) (layer "In2.Cu") (net 647))
  (arc (start 194.105978 90.672398) (mid 194.064791 90.734039) (end 194.050328 90.806749) (width 0.082) (layer "In2.Cu") (net 647))
  (arc (start 198.880688 90.420056) (mid 199.024577 90.448677) (end 199.14656 90.530184) (width 0.13) (layer "In2.Cu") (net 647))
  (arc (start 238.999197 91.587829) (mid 239.257891 91.639286) (end 239.477201 91.785825) (width 0.13) (layer "In2.Cu") (net 647))
  (arc (start 256.046219 98.897) (mid 255.969683 98.881776) (end 255.904798 98.838422) (width 0.13) (layer "In2.Cu") (net 647))
  (arc (start 194.021039 90.978961) (mid 194.042716 90.946519) (end 194.050328 90.908251) (width 0.082) (layer "In2.Cu") (net 647))
  (arc (start 256.230859 105.135517) (mid 256.125097 105.206185) (end 256.000342 105.231) (width 0.13) (layer "In2.Cu") (net 647))
  (arc (start 256.643504 99.007128) (mid 256.521521 98.925621) (end 256.377632 98.897) (width 0.13) (layer "In2.Cu") (net 647))
  (arc (start 249.767632 96.047) (mid 249.911521 96.075621) (end 250.033504 96.157128) (width 0.13) (layer "In2.Cu") (net 647))
  (arc (start 254.166219 98.597) (mid 254.089683 98.581776) (end 254.024798 98.538422) (width 0.13) (layer "In2.Cu") (net 647))
  (arc (start 250.444798 96.568422) (mid 250.509683 96.611776) (end 250.586219 96.627) (width 0.13) (layer "In2.Cu") (net 647))
  (segment (start 255.415079 105.280079) (end 255.415711 105.280711) (width 0.122) (layer "B.Cu") (net 647))
  (segment (start 255.445 105.351421) (end 255.445 105.715) (width 0.122) (layer "B.Cu") (net 647))
  (segment (start 254.81 105.41) (end 254.939922 105.280078) (width 0.122) (layer "B.Cu") (net 647))
  (segment (start 255.081343 105.2215) (end 255.273657 105.2215) (width 0.122) (layer "B.Cu") (net 647))
  (arc (start 255.445 105.351421) (mid 255.437388 105.313153) (end 255.415711 105.280711) (width 0.122) (layer "B.Cu") (net 647))
  (arc (start 255.081343 105.2215) (mid 255.004807 105.236724) (end 254.939922 105.280078) (width 0.122) (layer "B.Cu") (net 647))
  (arc (start 255.273657 105.2215) (mid 255.350194 105.236724) (end 255.415079 105.280079) (width 0.122) (layer "B.Cu") (net 647))
  (segment (start 194.636328 91.060008) (end 194.136328 90.560008) (width 0.127) (layer "F.Cu") (net 648))
  (via blind (at 194.636328 91.060008) (size 0.5) (drill 0.2) (layers "F.Cu" "In2.Cu") (net 648))
  (via (at 254.81 104.746) (size 0.5) (drill 0.2) (layers "F.Cu" "B.Cu") (net 648))
  (segment (start 256.052558 104.881066) (end 256.066812 104.866812) (width 0.13) (layer "In2.Cu") (net 648))
  (segment (start 243.413628 96.155004) (end 239.2989 92.040276) (width 0.13) (layer "In2.Cu") (net 648))
  (segment (start 256.066813 104.442547) (end 256.102169 104.407192) (width 0.13) (layer "In2.Cu") (net 648))
  (segment (start 256.672 104.199493) (end 256.672 99.551219) (width 0.13) (layer "In2.Cu") (net 648))
  (segment (start 256.526434 104.407193) (end 256.628067 104.305558) (width 0.13) (layer "In2.Cu") (net 648))
  (segment (start 198.173523 90.719579) (end 198.18 90.726056) (width 0.082) (layer "In2.Cu") (net 648))
  (segment (start 195.061 90.761) (end 195.061 90.776095) (width 0.082) (layer "In2.Cu") (net 648))
  (segment (start 255.778046 99.144422) (end 255.595203 98.961579) (width 0.13) (layer "In2.Cu") (net 648))
  (segment (start 194.636328 91.060008) (end 194.401429 91.060008) (width 0.082) (layer "In2.Cu") (net 648))
  (segment (start 253.208613 98.473187) (end 253.208612 98.473187) (width 0.13) (layer "In2.Cu") (net 648))
  (segment (start 195.761 90.661) (end 198.032101 90.661) (width 0.082) (layer "In2.Cu") (net 648))
  (segment (start 199.879457 91.695833) (end 198.968258 90.784634) (width 0.13) (layer "In2.Cu") (net 648))
  (segment (start 256.323781 99.203) (end 255.919467 99.203) (width 0.13) (layer "In2.Cu") (net 648))
  (segment (start 195.261 90.776095) (end 195.261 90.761) (width 0.082) (layer "In2.Cu") (net 648))
  (segment (start 252.882345 98.163056) (end 252.890414 98.154988) (width 0.13) (layer "In2.Cu") (net 648))
  (segment (start 255.051132 104.925) (end 255.946492 104.925) (width 0.13) (layer "In2.Cu") (net 648))
  (segment (start 194.222328 90.880907) (end 194.222328 90.840717) (width 0.082) (layer "In2.Cu") (net 648))
  (segment (start 256.613422 99.409798) (end 256.465203 99.261579) (width 0.13) (layer "In2.Cu") (net 648))
  (segment (start 252.890415 97.836791) (end 252.045203 96.991579) (width 0.13) (layer "In2.Cu") (net 648))
  (segment (start 252.890414 97.83679) (end 252.890415 97.836791) (width 0.13) (layer "In2.Cu") (net 648))
  (segment (start 195.461 90.761) (end 195.461 90.776095) (width 0.082) (layer "In2.Cu") (net 648))
  (segment (start 194.402045 90.661) (end 194.961 90.661) (width 0.082) (layer "In2.Cu") (net 648))
  (segment (start 253.846496 98.792872) (end 253.526812 98.473188) (width 0.13) (layer "In2.Cu") (net 648))
  (segment (start 255.453781 98.903) (end 254.112368 98.903) (width 0.13) (layer "In2.Cu") (net 648))
  (segment (start 252.882345 98.163057) (end 252.882345 98.163056) (width 0.13) (layer "In2.Cu") (net 648))
  (segment (start 198.826837 90.726056) (end 198.18 90.726056) (width 0.13) (layer "In2.Cu") (net 648))
  (segment (start 194.251618 90.770006) (end 194.331335 90.690289) (width 0.082) (layer "In2.Cu") (net 648))
  (segment (start 253.208612 98.473187) (end 253.200544 98.481256) (width 0.13) (layer "In2.Cu") (net 648))
  (segment (start 254.81 104.746) (end 254.945066 104.881066) (width 0.13) (layer "In2.Cu") (net 648))
  (segment (start 195.661 90.776095) (end 195.661 90.761) (width 0.082) (layer "In2.Cu") (net 648))
  (segment (start 238.945346 91.893829) (end 200.357461 91.893829) (width 0.13) (layer "In2.Cu") (net 648))
  (segment (start 194.330718 91.030718) (end 194.251617 90.951617) (width 0.082) (layer "In2.Cu") (net 648))
  (segment (start 251.903781 96.933) (end 250.532368 96.933) (width 0.13) (layer "In2.Cu") (net 648))
  (segment (start 249.713781 96.353) (end 243.891632 96.353) (width 0.13) (layer "In2.Cu") (net 648))
  (segment (start 250.266496 96.822872) (end 249.855203 96.411579) (width 0.13) (layer "In2.Cu") (net 648))
  (arc (start 253.200544 98.481256) (mid 253.041445 98.547157) (end 252.882346 98.481256) (width 0.13) (layer "In2.Cu") (net 648))
  (arc (start 198.968258 90.784634) (mid 198.903373 90.74128) (end 198.826837 90.726056) (width 0.13) (layer "In2.Cu") (net 648))
  (arc (start 194.331335 90.690289) (mid 194.363777 90.668612) (end 194.402045 90.661) (width 0.082) (layer "In2.Cu") (net 648))
  (arc (start 195.661 90.761) (mid 195.690289 90.690289) (end 195.761 90.661) (width 0.082) (layer "In2.Cu") (net 648))
  (arc (start 194.251617 90.951617) (mid 194.22994 90.919175) (end 194.222328 90.880907) (width 0.082) (layer "In2.Cu") (net 648))
  (arc (start 195.361 90.661) (mid 195.431711 90.690289) (end 195.461 90.761) (width 0.082) (layer "In2.Cu") (net 648))
  (arc (start 256.628067 104.305558) (mid 256.660582 104.256895) (end 256.672 104.199493) (width 0.13) (layer "In2.Cu") (net 648))
  (arc (start 195.261 90.761) (mid 195.290289 90.690289) (end 195.361 90.661) (width 0.082) (layer "In2.Cu") (net 648))
  (arc (start 250.532368 96.933) (mid 250.388479 96.904379) (end 250.266496 96.822872) (width 0.13) (layer "In2.Cu") (net 648))
  (arc (start 256.066812 104.65468) (mid 256.022879 104.548612) (end 256.066813 104.442547) (width 0.13) (layer "In2.Cu") (net 648))
  (arc (start 198.032101 90.661) (mid 198.108638 90.676224) (end 198.173523 90.719579) (width 0.082) (layer "In2.Cu") (net 648))
  (arc (start 239.2989 92.040276) (mid 239.136688 91.931889) (end 238.945346 91.893829) (width 0.13) (layer "In2.Cu") (net 648))
  (arc (start 256.066812 104.866812) (mid 256.110746 104.760746) (end 256.066812 104.65468) (width 0.13) (layer "In2.Cu") (net 648))
  (arc (start 252.882346 98.481256) (mid 252.816443 98.322156) (end 252.882345 98.163057) (width 0.13) (layer "In2.Cu") (net 648))
  (arc (start 253.526812 98.473188) (mid 253.367712 98.407285) (end 253.208613 98.473187) (width 0.13) (layer "In2.Cu") (net 648))
  (arc (start 255.946492 104.925) (mid 256.003895 104.913582) (end 256.052558 104.881066) (width 0.13) (layer "In2.Cu") (net 648))
  (arc (start 249.855203 96.411579) (mid 249.790318 96.368224) (end 249.713781 96.353) (width 0.13) (layer "In2.Cu") (net 648))
  (arc (start 255.595203 98.961579) (mid 255.530318 98.918224) (end 255.453781 98.903) (width 0.13) (layer "In2.Cu") (net 648))
  (arc (start 254.945066 104.881066) (mid 254.993729 104.913582) (end 255.051132 104.925) (width 0.13) (layer "In2.Cu") (net 648))
  (arc (start 243.891632 96.353) (mid 243.632938 96.301542) (end 243.413628 96.155004) (width 0.13) (layer "In2.Cu") (net 648))
  (arc (start 256.102169 104.407192) (mid 256.208235 104.363258) (end 256.314301 104.407192) (width 0.13) (layer "In2.Cu") (net 648))
  (arc (start 200.357461 91.893829) (mid 200.098767 91.842371) (end 199.879457 91.695833) (width 0.13) (layer "In2.Cu") (net 648))
  (arc (start 252.890414 98.154988) (mid 252.956315 97.995889) (end 252.890414 97.83679) (width 0.13) (layer "In2.Cu") (net 648))
  (arc (start 254.112368 98.903) (mid 253.968479 98.874379) (end 253.846496 98.792872) (width 0.13) (layer "In2.Cu") (net 648))
  (arc (start 195.561 90.876095) (mid 195.631711 90.846806) (end 195.661 90.776095) (width 0.082) (layer "In2.Cu") (net 648))
  (arc (start 195.161 90.876095) (mid 195.231711 90.846806) (end 195.261 90.776095) (width 0.082) (layer "In2.Cu") (net 648))
  (arc (start 252.045203 96.991579) (mid 251.980318 96.948224) (end 251.903781 96.933) (width 0.13) (layer "In2.Cu") (net 648))
  (arc (start 195.461 90.776095) (mid 195.490289 90.846806) (end 195.561 90.876095) (width 0.082) (layer "In2.Cu") (net 648))
  (arc (start 256.314301 104.407192) (mid 256.420366 104.451128) (end 256.526434 104.407193) (width 0.13) (layer "In2.Cu") (net 648))
  (arc (start 194.961 90.661) (mid 195.031711 90.690289) (end 195.061 90.761) (width 0.082) (layer "In2.Cu") (net 648))
  (arc (start 194.222328 90.840717) (mid 194.22994 90.802448) (end 194.251618 90.770006) (width 0.082) (layer "In2.Cu") (net 648))
  (arc (start 256.465203 99.261579) (mid 256.400318 99.218224) (end 256.323781 99.203) (width 0.13) (layer "In2.Cu") (net 648))
  (arc (start 195.061 90.776095) (mid 195.090289 90.846806) (end 195.161 90.876095) (width 0.082) (layer "In2.Cu") (net 648))
  (arc (start 255.919467 99.203) (mid 255.842931 99.187776) (end 255.778046 99.144422) (width 0.13) (layer "In2.Cu") (net 648))
  (arc (start 194.401429 91.060008) (mid 194.36316 91.052396) (end 194.330718 91.030718) (width 0.082) (layer "In2.Cu") (net 648))
  (arc (start 256.672 99.551219) (mid 256.656776 99.474683) (end 256.613422 99.409798) (width 0.13) (layer "In2.Cu") (net 648))
  (segment (start 254.81 104.746) (end 254.939922 104.875922) (width 0.122) (layer "B.Cu") (net 648))
  (segment (start 255.445 104.788579) (end 255.445 104.445) (width 0.122) (layer "B.Cu") (net 648))
  (segment (start 255.399079 104.875921) (end 255.415711 104.859289) (width 0.122) (layer "B.Cu") (net 648))
  (segment (start 255.081343 104.9345) (end 255.257657 104.9345) (width 0.122) (layer "B.Cu") (net 648))
  (arc (start 255.081343 104.9345) (mid 255.004807 104.919276) (end 254.939922 104.875922) (width 0.122) (layer "B.Cu") (net 648))
  (arc (start 255.415711 104.859289) (mid 255.437388 104.826847) (end 255.445 104.788579) (width 0.122) (layer "B.Cu") (net 648))
  (arc (start 255.257657 104.9345) (mid 255.334194 104.919276) (end 255.399079 104.875921) (width 0.122) (layer "B.Cu") (net 648))
  (segment (start 136.015 98.25) (end 136.015 96.484143) (width 0.2) (layer "F.Cu") (net 649))
  (segment (start 234.987 119.541) (end 233.9255 119.541) (width 0.1) (layer "F.Cu") (net 650))
  (segment (start 235.282 119.541) (end 234.987 119.541) (width 0.1) (layer "F.Cu") (net 650))
  (segment (start 224.8855 117.001) (end 226.1785 117.001) (width 0.1) (layer "F.Cu") (net 651))
  (segment (start 155.009179 98.797157) (end 151.778477 98.797157) (width 0.15) (layer "F.Cu") (net 652))
  (segment (start 139.776328 113.132157) (end 140 112.908485) (width 0.15) (layer "F.Cu") (net 654))
  (segment (start 140 111.0875) (end 140.03 111.0575) (width 0.15) (layer "F.Cu") (net 654))
  (segment (start 140 112.908485) (end 140 111.0875) (width 0.15) (layer "F.Cu") (net 654))
  (segment (start 139.776328 114.142157) (end 139.776328 113.132157) (width 0.15) (layer "F.Cu") (net 654))
  (segment (start 191.636328 102.060008) (end 191.136328 101.560008) (width 0.127) (layer "F.Cu") (net 655))
  (via blind (at 191.636328 102.060008) (size 0.5) (drill 0.2) (layers "F.Cu" "In2.Cu") (net 655))
  (via (at 253.54 118.11) (size 0.5) (drill 0.2) (layers "F.Cu" "B.Cu") (net 655))
  (segment (start 253.878342 115.722) (end 249.621219 115.722) (width 0.13) (layer "In2.Cu") (net 655))
  (segment (start 237.705004 102.238628) (end 236.299446 100.83307) (width 0.13) (layer "In2.Cu") (net 655))
  (segment (start 248.757632 115.097) (end 245.020483 115.097) (width 0.13) (layer "In2.Cu") (net 655))
  (segment (start 254.257517 115.966141) (end 254.108859 115.817483) (width 0.13) (layer "In2.Cu") (net 655))
  (segment (start 197.669937 101.111181) (end 197.977976 101.111181) (width 0.082) (layer "In2.Cu") (net 655))
  (segment (start 254.080859 117.835517) (end 254.257517 117.658859) (width 0.13) (layer "In2.Cu") (net 655))
  (segment (start 235.955004 99.638628) (end 234.486372 98.169996) (width 0.13) (layer "In2.Cu") (net 655))
  (segment (start 240.955297 109.488921) (end 239.799446 108.33307) (width 0.13) (layer "In2.Cu") (net 655))
  (segment (start 192.120623 100.807753) (end 192.394082 100.534294) (width 0.082) (layer "In2.Cu") (net 655))
  (segment (start 254.353 117.428342) (end 254.353 116.196658) (width 0.13) (layer "In2.Cu") (net 655))
  (segment (start 234.008368 97.972) (end 206.391632 97.972) (width 0.13) (layer "In2.Cu") (net 655))
  (segment (start 205.913628 98.169996) (end 203.18307 100.900554) (width 0.13) (layer "In2.Cu") (net 655))
  (segment (start 198.119398 101.052602) (end 198.125 101.047) (width 0.082) (layer "In2.Cu") (net 655))
  (segment (start 239.455297 105.488921) (end 238.049446 104.08307) (width 0.13) (layer "In2.Cu") (net 655))
  (segment (start 192.563787 100.464) (end 196.861213 100.464) (width 0.082) (layer "In2.Cu") (net 655))
  (segment (start 237.903 103.729517) (end 237.903 102.716632) (width 0.13) (layer "In2.Cu") (net 655))
  (segment (start 192.050328 101.88754) (end 192.050328 100.977459) (width 0.082) (layer "In2.Cu") (net 655))
  (segment (start 253.781132 117.931) (end 253.850342 117.931) (width 0.13) (layer "In2.Cu") (net 655))
  (segment (start 236.153 100.479517) (end 236.153 100.116632) (width 0.13) (layer "In2.Cu") (net 655))
  (segment (start 241.153 111.229517) (end 241.153 109.966218) (width 0.13) (layer "In2.Cu") (net 655))
  (segment (start 191.983926 102.016074) (end 192.006394 101.993606) (width 0.082) (layer "In2.Cu") (net 655))
  (segment (start 197.030919 100.534295) (end 197.563871 101.067247) (width 0.082) (layer "In2.Cu") (net 655))
  (segment (start 239.653 107.979517) (end 239.653 105.966218) (width 0.13) (layer "In2.Cu") (net 655))
  (segment (start 202.829517 101.047) (end 198.125 101.047) (width 0.13) (layer "In2.Cu") (net 655))
  (segment (start 244.666929 114.950553) (end 241.299446 111.58307) (width 0.13) (layer "In2.Cu") (net 655))
  (segment (start 191.636328 102.060008) (end 191.87786 102.060008) (width 0.082) (layer "In2.Cu") (net 655))
  (segment (start 253.54 118.11) (end 253.675066 117.974934) (width 0.13) (layer "In2.Cu") (net 655))
  (segment (start 249.479797 115.663421) (end 249.023504 115.207128) (width 0.13) (layer "In2.Cu") (net 655))
  (arc (start 192.006394 101.993606) (mid 192.03891 101.944943) (end 192.050328 101.88754) (width 0.082) (layer "In2.Cu") (net 655))
  (arc (start 237.705004 102.238628) (mid 237.851542 102.457938) (end 237.903 102.716632) (width 0.13) (layer "In2.Cu") (net 655))
  (arc (start 248.757632 115.097) (mid 248.901521 115.125621) (end 249.023504 115.207128) (width 0.13) (layer "In2.Cu") (net 655))
  (arc (start 197.977976 101.111181) (mid 198.054513 101.095957) (end 198.119398 101.052602) (width 0.082) (layer "In2.Cu") (net 655))
  (arc (start 206.391632 97.972) (mid 206.132938 98.023457) (end 205.913628 98.169996) (width 0.13) (layer "In2.Cu") (net 655))
  (arc (start 253.878342 115.722) (mid 254.003097 115.746815) (end 254.108859 115.817483) (width 0.13) (layer "In2.Cu") (net 655))
  (arc (start 249.621219 115.722) (mid 249.544682 115.706776) (end 249.479797 115.663421) (width 0.13) (layer "In2.Cu") (net 655))
  (arc (start 192.050328 100.977459) (mid 192.068597 100.885615) (end 192.120623 100.807753) (width 0.082) (layer "In2.Cu") (net 655))
  (arc (start 203.18307 100.900554) (mid 203.020858 101.00894) (end 202.829517 101.047) (width 0.13) (layer "In2.Cu") (net 655))
  (arc (start 254.257517 115.966141) (mid 254.328185 116.071903) (end 254.353 116.196658) (width 0.13) (layer "In2.Cu") (net 655))
  (arc (start 239.455297 105.488921) (mid 239.601619 105.707907) (end 239.653 105.966218) (width 0.13) (layer "In2.Cu") (net 655))
  (arc (start 254.257517 117.658859) (mid 254.328185 117.553097) (end 254.353 117.428342) (width 0.13) (layer "In2.Cu") (net 655))
  (arc (start 239.799446 108.33307) (mid 239.69106 108.170858) (end 239.653 107.979517) (width 0.13) (layer "In2.Cu") (net 655))
  (arc (start 196.861213 100.464) (mid 196.953057 100.482269) (end 197.030919 100.534295) (width 0.082) (layer "In2.Cu") (net 655))
  (arc (start 241.299446 111.58307) (mid 241.19106 111.420858) (end 241.153 111.229517) (width 0.13) (layer "In2.Cu") (net 655))
  (arc (start 254.080859 117.835517) (mid 253.975097 117.906185) (end 253.850342 117.931) (width 0.13) (layer "In2.Cu") (net 655))
  (arc (start 237.903 103.729517) (mid 237.94106 103.920858) (end 238.049446 104.08307) (width 0.13) (layer "In2.Cu") (net 655))
  (arc (start 253.781132 117.931) (mid 253.723729 117.942418) (end 253.675066 117.974934) (width 0.13) (layer "In2.Cu") (net 655))
  (arc (start 197.563871 101.067247) (mid 197.612534 101.099763) (end 197.669937 101.111181) (width 0.082) (layer "In2.Cu") (net 655))
  (arc (start 234.486372 98.169996) (mid 234.267062 98.023458) (end 234.008368 97.972) (width 0.13) (layer "In2.Cu") (net 655))
  (arc (start 244.666929 114.950553) (mid 244.829141 115.05894) (end 245.020483 115.097) (width 0.13) (layer "In2.Cu") (net 655))
  (arc (start 235.955004 99.638628) (mid 236.101542 99.857938) (end 236.153 100.116632) (width 0.13) (layer "In2.Cu") (net 655))
  (arc (start 236.299446 100.83307) (mid 236.19106 100.670858) (end 236.153 100.479517) (width 0.13) (layer "In2.Cu") (net 655))
  (arc (start 240.955297 109.488921) (mid 241.101619 109.707907) (end 241.153 109.966218) (width 0.13) (layer "In2.Cu") (net 655))
  (arc (start 192.563787 100.464) (mid 192.471943 100.482269) (end 192.394082 100.534294) (width 0.082) (layer "In2.Cu") (net 655))
  (arc (start 191.87786 102.060008) (mid 191.935263 102.04859) (end 191.983926 102.016074) (width 0.082) (layer "In2.Cu") (net 655))
  (segment (start 253.54 118.11) (end 253.669922 117.980078) (width 0.122) (layer "B.Cu") (net 655))
  (segment (start 254.175 118.051421) (end 254.175 118.415) (width 0.122) (layer "B.Cu") (net 655))
  (segment (start 253.811343 117.9215) (end 254.003657 117.9215) (width 0.122) (layer "B.Cu") (net 655))
  (segment (start 254.145079 117.980079) (end 254.145711 117.980711) (width 0.122) (layer "B.Cu") (net 655))
  (arc (start 254.003657 117.9215) (mid 254.080194 117.936724) (end 254.145079 117.980079) (width 0.122) (layer "B.Cu") (net 655))
  (arc (start 253.811343 117.9215) (mid 253.734807 117.936724) (end 253.669922 117.980078) (width 0.122) (layer "B.Cu") (net 655))
  (arc (start 254.175 118.051421) (mid 254.167388 118.013153) (end 254.145711 117.980711) (width 0.122) (layer "B.Cu") (net 655))
  (segment (start 192.636328 102.060008) (end 192.136328 101.560008) (width 0.127) (layer "F.Cu") (net 656))
  (via blind (at 192.636328 102.060008) (size 0.5) (drill 0.2) (layers "F.Cu" "In2.Cu") (net 656))
  (via (at 253.54 117.446) (size 0.5) (drill 0.2) (layers "F.Cu" "B.Cu") (net 656))
  (segment (start 202.883368 101.353) (end 198.125 101.353) (width 0.13) (layer "In2.Cu") (net 656))
  (segment (start 249.567368 116.028) (end 251.028 116.028) (width 0.13) (layer "In2.Cu") (net 656))
  (segment (start 251.253 116.278277) (end 251.253 116.253) (width 0.13) (layer "In2.Cu") (net 656))
  (segment (start 197.635968 101.283181) (end 197.972338 101.283181) (width 0.082) (layer "In2.Cu") (net 656))
  (segment (start 237.450553 102.416929) (end 236.044996 101.011372) (width 0.13) (layer "In2.Cu") (net 656))
  (segment (start 235.700553 99.816929) (end 234.30807 98.424446) (width 0.13) (layer "In2.Cu") (net 656))
  (segment (start 192.286074 102.016074) (end 192.266262 101.996262) (width 0.082) (layer "In2.Cu") (net 656))
  (segment (start 235.847 100.533368) (end 235.847 100.170483) (width 0.13) (layer "In2.Cu") (net 656))
  (segment (start 240.700553 109.666929) (end 239.544996 108.511372) (width 0.13) (layer "In2.Cu") (net 656))
  (segment (start 240.847 111.283368) (end 240.847 110.020483) (width 0.13) (layer "In2.Cu") (net 656))
  (segment (start 251.703 116.253) (end 251.703 116.278277) (width 0.13) (layer "In2.Cu") (net 656))
  (segment (start 192.222328 101.890196) (end 192.222328 101.847672) (width 0.082) (layer "In2.Cu") (net 656))
  (segment (start 252.472 116.028) (end 251.928 116.028) (width 0.13) (layer "In2.Cu") (net 656))
  (segment (start 253.781132 117.625) (end 253.796492 117.625) (width 0.13) (layer "In2.Cu") (net 656))
  (segment (start 244.488628 115.205004) (end 241.044996 111.761372) (width 0.13) (layer "In2.Cu") (net 656))
  (segment (start 233.954517 98.278) (end 206.445483 98.278) (width 0.13) (layer "In2.Cu") (net 656))
  (segment (start 192.222328 101.197672) (end 192.222328 101.011428) (width 0.082) (layer "In2.Cu") (net 656))
  (segment (start 196.93331 100.679934) (end 197.466263 101.212887) (width 0.082) (layer "In2.Cu") (net 656))
  (segment (start 239.200553 105.666929) (end 237.794996 104.261372) (width 0.13) (layer "In2.Cu") (net 656))
  (segment (start 192.636328 102.060008) (end 192.39214 102.060008) (width 0.082) (layer "In2.Cu") (net 656))
  (segment (start 192.372328 101.697672) (end 192.374458 101.697672) (width 0.082) (layer "In2.Cu") (net 656))
  (segment (start 254.047 117.374492) (end 254.047 116.250508) (width 0.13) (layer "In2.Cu") (net 656))
  (segment (start 239.347 108.033368) (end 239.347 106.020483) (width 0.13) (layer "In2.Cu") (net 656))
  (segment (start 192.597756 100.636) (end 196.827244 100.636) (width 0.082) (layer "In2.Cu") (net 656))
  (segment (start 206.091929 98.424447) (end 203.361372 101.155004) (width 0.13) (layer "In2.Cu") (net 656))
  (segment (start 198.11376 101.34176) (end 198.125 101.353) (width 0.082) (layer "In2.Cu") (net 656))
  (segment (start 237.597 103.783368) (end 237.597 102.770483) (width 0.13) (layer "In2.Cu") (net 656))
  (segment (start 253.824492 116.028) (end 253.272 116.028) (width 0.13) (layer "In2.Cu") (net 656))
  (segment (start 249.301496 115.917872) (end 248.845202 115.461578) (width 0.13) (layer "In2.Cu") (net 656))
  (segment (start 254.003066 116.144442) (end 253.930558 116.071934) (width 0.13) (layer "In2.Cu") (net 656))
  (segment (start 253.902558 117.581066) (end 254.003066 117.480558) (width 0.13) (layer "In2.Cu") (net 656))
  (segment (start 248.703781 115.403) (end 244.966632 115.403) (width 0.13) (layer "In2.Cu") (net 656))
  (segment (start 192.266262 100.905362) (end 192.49169 100.679934) (width 0.082) (layer "In2.Cu") (net 656))
  (segment (start 192.374458 101.397672) (end 192.372328 101.397672) (width 0.082) (layer "In2.Cu") (net 656))
  (segment (start 192.222328 101.247672) (end 192.222328 101.197672) (width 0.082) (layer "In2.Cu") (net 656))
  (segment (start 253.54 117.446) (end 253.675066 117.581066) (width 0.13) (layer "In2.Cu") (net 656))
  (arc (start 253.072 116.228) (mid 253.013421 116.369421) (end 252.872 116.428) (width 0.13) (layer "In2.Cu") (net 656))
  (arc (start 192.222328 101.847672) (mid 192.266262 101.741606) (end 192.372328 101.697672) (width 0.082) (layer "In2.Cu") (net 656))
  (arc (start 252.672 116.228) (mid 252.613421 116.086579) (end 252.472 116.028) (width 0.13) (layer "In2.Cu") (net 656))
  (arc (start 237.597 102.770483) (mid 237.55894 102.579141) (end 237.450553 102.416929) (width 0.13) (layer "In2.Cu") (net 656))
  (arc (start 192.266262 100.905362) (mid 192.233746 100.954025) (end 192.222328 101.011428) (width 0.082) (layer "In2.Cu") (net 656))
  (arc (start 203.361372 101.155004) (mid 203.142062 101.301543) (end 202.883368 101.353) (width 0.13) (layer "In2.Cu") (net 656))
  (arc (start 251.928 116.028) (mid 251.768901 116.093901) (end 251.703 116.253) (width 0.13) (layer "In2.Cu") (net 656))
  (arc (start 251.478 116.503277) (mid 251.318901 116.437376) (end 251.253 116.278277) (width 0.13) (layer "In2.Cu") (net 656))
  (arc (start 248.845202 115.461578) (mid 248.780317 115.418224) (end 248.703781 115.403) (width 0.13) (layer "In2.Cu") (net 656))
  (arc (start 192.39214 102.060008) (mid 192.334737 102.04859) (end 192.286074 102.016074) (width 0.082) (layer "In2.Cu") (net 656))
  (arc (start 192.374458 101.697672) (mid 192.480524 101.653738) (end 192.524458 101.547672) (width 0.082) (layer "In2.Cu") (net 656))
  (arc (start 192.372328 101.397672) (mid 192.266262 101.353738) (end 192.222328 101.247672) (width 0.082) (layer "In2.Cu") (net 656))
  (arc (start 235.847 100.170483) (mid 235.80894 99.979141) (end 235.700553 99.816929) (width 0.13) (layer "In2.Cu") (net 656))
  (arc (start 254.047 116.250508) (mid 254.035582 116.193105) (end 254.003066 116.144442) (width 0.13) (layer "In2.Cu") (net 656))
  (arc (start 254.003066 117.480558) (mid 254.035582 117.431895) (end 254.047 117.374492) (width 0.13) (layer "In2.Cu") (net 656))
  (arc (start 253.675066 117.581066) (mid 253.723729 117.613582) (end 253.781132 117.625) (width 0.13) (layer "In2.Cu") (net 656))
  (arc (start 197.972338 101.283181) (mid 198.048875 101.298405) (end 198.11376 101.34176) (width 0.082) (layer "In2.Cu") (net 656))
  (arc (start 206.445483 98.278) (mid 206.254141 98.31606) (end 206.091929 98.424447) (width 0.13) (layer "In2.Cu") (net 656))
  (arc (start 234.30807 98.424446) (mid 234.145858 98.31606) (end 233.954517 98.278) (width 0.13) (layer "In2.Cu") (net 656))
  (arc (start 253.272 116.028) (mid 253.130579 116.086579) (end 253.072 116.228) (width 0.13) (layer "In2.Cu") (net 656))
  (arc (start 253.930558 116.071934) (mid 253.881895 116.039418) (end 253.824492 116.028) (width 0.13) (layer "In2.Cu") (net 656))
  (arc (start 253.796492 117.625) (mid 253.853895 117.613582) (end 253.902558 117.581066) (width 0.13) (layer "In2.Cu") (net 656))
  (arc (start 252.872 116.428) (mid 252.730579 116.369421) (end 252.672 116.228) (width 0.13) (layer "In2.Cu") (net 656))
  (arc (start 251.703 116.278277) (mid 251.637099 116.437376) (end 251.478 116.503277) (width 0.13) (layer "In2.Cu") (net 656))
  (arc (start 192.266262 101.996262) (mid 192.233746 101.947599) (end 192.222328 101.890196) (width 0.082) (layer "In2.Cu") (net 656))
  (arc (start 251.253 116.253) (mid 251.187099 116.093901) (end 251.028 116.028) (width 0.13) (layer "In2.Cu") (net 656))
  (arc (start 249.567368 116.028) (mid 249.423479 115.999379) (end 249.301496 115.917872) (width 0.13) (layer "In2.Cu") (net 656))
  (arc (start 236.044996 101.011372) (mid 235.898457 100.792062) (end 235.847 100.533368) (width 0.13) (layer "In2.Cu") (net 656))
  (arc (start 192.49169 100.679934) (mid 192.540353 100.647418) (end 192.597756 100.636) (width 0.082) (layer "In2.Cu") (net 656))
  (arc (start 240.847 110.020483) (mid 240.80894 109.829141) (end 240.700553 109.666929) (width 0.13) (layer "In2.Cu") (net 656))
  (arc (start 192.524458 101.547672) (mid 192.480524 101.441606) (end 192.374458 101.397672) (width 0.082) (layer "In2.Cu") (net 656))
  (arc (start 239.544996 108.511372) (mid 239.398457 108.292062) (end 239.347 108.033368) (width 0.13) (layer "In2.Cu") (net 656))
  (arc (start 237.794996 104.261372) (mid 237.648457 104.042062) (end 237.597 103.783368) (width 0.13) (layer "In2.Cu") (net 656))
  (arc (start 196.827244 100.636) (mid 196.884647 100.647418) (end 196.93331 100.679934) (width 0.082) (layer "In2.Cu") (net 656))
  (arc (start 241.044996 111.761372) (mid 240.898457 111.542062) (end 240.847 111.283368) (width 0.13) (layer "In2.Cu") (net 656))
  (arc (start 244.966632 115.403) (mid 244.707938 115.351543) (end 244.488628 115.205004) (width 0.13) (layer "In2.Cu") (net 656))
  (arc (start 197.466263 101.212887) (mid 197.544124 101.264912) (end 197.635968 101.283181) (width 0.082) (layer "In2.Cu") (net 656))
  (arc (start 239.347 106.020483) (mid 239.30894 105.829141) (end 239.200553 105.666929) (width 0.13) (layer "In2.Cu") (net 656))
  (segment (start 254.175 117.488579) (end 254.175 117.145) (width 0.122) (layer "B.Cu") (net 656))
  (segment (start 253.54 117.446) (end 253.669922 117.575922) (width 0.122) (layer "B.Cu") (net 656))
  (segment (start 254.129079 117.575921) (end 254.145711 117.559289) (width 0.122) (layer "B.Cu") (net 656))
  (segment (start 253.811343 117.6345) (end 253.987657 117.6345) (width 0.122) (layer "B.Cu") (net 656))
  (arc (start 253.987657 117.6345) (mid 254.064194 117.619276) (end 254.129079 117.575921) (width 0.122) (layer "B.Cu") (net 656))
  (arc (start 254.145711 117.559289) (mid 254.167388 117.526847) (end 254.175 117.488579) (width 0.122) (layer "B.Cu") (net 656))
  (arc (start 253.811343 117.6345) (mid 253.734807 117.619276) (end 253.669922 117.575922) (width 0.122) (layer "B.Cu") (net 656))
  (segment (start 145.046328 113.667157) (end 144.179171 112.8) (width 0.15) (layer "F.Cu") (net 657))
  (segment (start 143.45 112.8) (end 142.53 111.88) (width 0.15) (layer "F.Cu") (net 657))
  (segment (start 142.53 111.88) (end 142.53 111.0575) (width 0.15) (layer "F.Cu") (net 657))
  (segment (start 145.046328 114.112157) (end 145.046328 113.667157) (width 0.15) (layer "F.Cu") (net 657))
  (segment (start 144.179171 112.8) (end 143.45 112.8) (width 0.15) (layer "F.Cu") (net 657))
  (segment (start 178.04 63.54) (end 178.04 63.95) (width 0.2) (layer "F.Cu") (net 658))
  (segment (start 190.136328 83.560008) (end 189.636328 84.060008) (width 0.127) (layer "F.Cu") (net 658))
  (segment (start 178.04 63.95) (end 178.4 64.31) (width 0.2) (layer "F.Cu") (net 658))
  (via (at 178.4 64.31) (size 0.5) (drill 0.2) (layers "F.Cu" "B.Cu") (net 658))
  (via blind (at 189.636328 84.060008) (size 0.5) (drill 0.2) (layers "F.Cu" "In2.Cu") (net 658))
  (segment (start 185.087 79.540158) (end 185.087 78.842) (width 0.1) (layer "In2.Cu") (net 658))
  (segment (start 184.056328 77.443672) (end 184.056328 76.861429) (width 0.1) (layer "In2.Cu") (net 658))
  (segment (start 189.14 83.56368) (end 189.14 82.94) (width 0.1) (layer "In2.Cu") (net 658))
  (segment (start 189.636328 84.060008) (end 189.14 83.56368) (width 0.1) (layer "In2.Cu") (net 658))
  (segment (start 185.199 82.217) (end 185.199 81.959) (width 0.1) (layer "In2.Cu") (net 658))
  (segment (start 183.725 68.625) (end 183.725 75.545) (width 0.16) (layer "In2.Cu") (net 658))
  (segment (start 184.828688 78.583688) (end 184.483688 78.583688) (width 0.1) (layer "In2.Cu") (net 658))
  (segment (start 185.503 82.521) (end 185.199 82.217) (width 0.1) (layer "In2.Cu") (net 658))
  (segment (start 188.721 82.521) (end 185.503 82.521) (width 0.1) (layer "In2.Cu") (net 658))
  (segment (start 178.4 64.31) (end 179.41 64.31) (width 0.16) (layer "In2.Cu") (net 658))
  (segment (start 189.14 82.94) (end 188.721 82.521) (width 0.1) (layer "In2.Cu") (net 658))
  (segment (start 184.8 79.827158) (end 185.087 79.540158) (width 0.1) (layer "In2.Cu") (net 658))
  (segment (start 183.95 77.55) (end 184.056328 77.443672) (width 0.1) (layer "In2.Cu") (net 658))
  (segment (start 183.95 78.05) (end 183.95 77.55) (width 0.1) (layer "In2.Cu") (net 658))
  (segment (start 184.8 81.56) (end 184.8 79.827158) (width 0.1) (layer "In2.Cu") (net 658))
  (segment (start 185.087 78.842) (end 184.828688 78.583688) (width 0.1) (layer "In2.Cu") (net 658))
  (segment (start 179.41 64.31) (end 183.725 68.625) (width 0.16) (layer "In2.Cu") (net 658))
  (segment (start 184.483688 78.583688) (end 183.95 78.05) (width 0.1) (layer "In2.Cu") (net 658))
  (segment (start 185.199 81.959) (end 184.8 81.56) (width 0.1) (layer "In2.Cu") (net 658))
  (segment (start 183.73 76.535101) (end 183.73 75.55) (width 0.1) (layer "In2.Cu") (net 658))
  (segment (start 183.725 75.545) (end 183.73 75.55) (width 0.16) (layer "In2.Cu") (net 658))
  (segment (start 184.056328 76.861429) (end 183.73 76.535101) (width 0.1) (layer "In2.Cu") (net 658))
  (segment (start 177.1 127.3) (end 176.93 127.3) (width 0.2) (layer "B.Cu") (net 659))
  (segment (start 177.755 127.955) (end 177.1 127.3) (width 0.2) (layer "B.Cu") (net 659))
  (segment (start 178.64 127.955) (end 177.755 127.955) (width 0.2) (layer "B.Cu") (net 659))
  (segment (start 176.93 127.3) (end 176.735 127.105) (width 0.2) (layer "B.Cu") (net 659))
  (segment (start 122.095 89.2675) (end 122.26 89.4325) (width 0.1) (layer "B.Cu") (net 660))
  (segment (start 121.0225 89.2675) (end 122.095 89.2675) (width 0.1) (layer "B.Cu") (net 660))
  (segment (start 125.3375 90.05) (end 124.246 90.05) (width 0.1) (layer "B.Cu") (net 661))
  (segment (start 124.246 90.05) (end 124.2 90.096) (width 0.1) (layer "B.Cu") (net 661))
  (segment (start 162.47 102.72) (end 162.545 102.795) (width 0.15) (layer "B.Cu") (net 662))
  (segment (start 162.47 102.72) (end 162.89 102.3) (width 0.15) (layer "B.Cu") (net 662))
  (segment (start 165.7 102.3) (end 165.715 102.285) (width 0.15) (layer "B.Cu") (net 662))
  (segment (start 165.715 101.8) (end 165.715 102.285) (width 0.15) (layer "B.Cu") (net 662))
  (segment (start 162.545 103.545) (end 162.414499 103.675501) (width 0.15) (layer "B.Cu") (net 662))
  (segment (start 162.414499 103.675501) (end 162.414499 104.195501) (width 0.15) (layer "B.Cu") (net 662))
  (segment (start 162.545 102.795) (end 162.545 103.545) (width 0.15) (layer "B.Cu") (net 662))
  (segment (start 162.89 102.3) (end 165.7 102.3) (width 0.15) (layer "B.Cu") (net 662))
  (segment (start 165.715 102.285) (end 165.715 102.8) (width 0.15) (layer "B.Cu") (net 662))
  (segment (start 191.136328 91.560008) (end 191.636328 92.060008) (width 0.1) (layer "F.Cu") (net 663))
  (via (at 191.636328 92.060008) (size 0.5) (drill 0.2) (layers "F.Cu" "B.Cu") (net 663))
  (segment (start 192.24 92.66368) (end 191.636328 92.060008) (width 0.2) (layer "B.Cu") (net 663))
  (segment (start 192.24 92.675) (end 192.24 92.66368) (width 0.2) (layer "B.Cu") (net 663))
  (segment (start 231.8 123.8) (end 230.9 123.8) (width 0.2) (layer "F.Cu") (net 664))
  (segment (start 230.9 123.8) (end 230.85 123.75) (width 0.2) (layer "F.Cu") (net 664))
  (via (at 231.8 123.8) (size 0.5) (drill 0.2) (layers "F.Cu" "B.Cu") (net 664))
  (segment (start 234.15 131.6725) (end 234.9 130.9225) (width 0.2) (layer "B.Cu") (net 664))
  (segment (start 234.9 130.9225) (end 234.9 125.9) (width 0.2) (layer "B.Cu") (net 664))
  (segment (start 232.8 123.8) (end 231.8 123.8) (width 0.2) (layer "B.Cu") (net 664))
  (segment (start 234.9 125.9) (end 232.8 123.8) (width 0.2) (layer "B.Cu") (net 664))
  (segment (start 145.5769 108.87) (end 146.1159 108.331) (width 0.11) (layer "F.Cu") (net 665))
  (segment (start 144.7175 108.87) (end 145.5769 108.87) (width 0.11) (layer "F.Cu") (net 665))
  (segment (start 146.1159 108.331) (end 146.8628 108.331) (width 0.11) (layer "F.Cu") (net 665))
  (via (at 146.8628 108.331) (size 0.5) (drill 0.2) (layers "F.Cu" "B.Cu") (net 665))
  (segment (start 147.4724 107.7214) (end 148.082 107.7214) (width 0.15) (layer "B.Cu") (net 665))
  (segment (start 146.8628 108.331) (end 147.4724 107.7214) (width 0.15) (layer "B.Cu") (net 665))
  (segment (start 118.964728 72.140008) (end 120.555128 72.140008) (width 0.15) (layer "F.Cu") (net 666))
  (segment (start 251.824343 120.4835) (end 251.995657 120.4835) (width 0.122) (layer "F.Cu") (net 668))
  (segment (start 252.137079 120.542079) (end 252.27 120.675) (width 0.122) (layer "F.Cu") (net 668))
  (segment (start 251.385 120.84) (end 251.682922 120.542078) (width 0.122) (layer "F.Cu") (net 668))
  (via (at 252.27 120.65) (size 0.5) (drill 0.2) (layers "F.Cu" "B.Cu") (net 668))
  (arc (start 251.995657 120.4835) (mid 252.072194 120.498724) (end 252.137079 120.542079) (width 0.122) (layer "F.Cu") (net 668))
  (arc (start 251.824343 120.4835) (mid 251.747807 120.498724) (end 251.682922 120.542078) (width 0.122) (layer "F.Cu") (net 668))
  (segment (start 252.541343 120.4615) (end 252.733657 120.4615) (width 0.122) (layer "B.Cu") (net 668))
  (segment (start 252.905 120.591421) (end 252.905 120.955) (width 0.122) (layer "B.Cu") (net 668))
  (segment (start 252.875079 120.520079) (end 252.875711 120.520711) (width 0.122) (layer "B.Cu") (net 668))
  (segment (start 252.27 120.65) (end 252.399922 120.520078) (width 0.122) (layer "B.Cu") (net 668))
  (arc (start 252.905 120.591421) (mid 252.897388 120.553153) (end 252.875711 120.520711) (width 0.122) (layer "B.Cu") (net 668))
  (arc (start 252.733657 120.4615) (mid 252.810194 120.476724) (end 252.875079 120.520079) (width 0.122) (layer "B.Cu") (net 668))
  (arc (start 252.541343 120.4615) (mid 252.464807 120.476724) (end 252.399922 120.520078) (width 0.122) (layer "B.Cu") (net 668))
  (segment (start 251.824343 120.1965) (end 252.001657 120.1965) (width 0.122) (layer "F.Cu") (net 669))
  (segment (start 251.385 119.84) (end 251.682922 120.137922) (width 0.122) (layer "F.Cu") (net 669))
  (segment (start 252.143079 120.137921) (end 252.27 120.011) (width 0.122) (layer "F.Cu") (net 669))
  (via (at 252.27 119.986) (size 0.5) (drill 0.2) (layers "F.Cu" "B.Cu") (net 669))
  (arc (start 252.001657 120.1965) (mid 252.078194 120.181276) (end 252.143079 120.137921) (width 0.122) (layer "F.Cu") (net 669))
  (arc (start 251.824343 120.1965) (mid 251.747807 120.181276) (end 251.682922 120.137922) (width 0.122) (layer "F.Cu") (net 669))
  (segment (start 252.905 120.028579) (end 252.905 119.685) (width 0.122) (layer "B.Cu") (net 669))
  (segment (start 252.27 119.986) (end 252.399922 120.115922) (width 0.122) (layer "B.Cu") (net 669))
  (segment (start 252.859079 120.115921) (end 252.875711 120.099289) (width 0.122) (layer "B.Cu") (net 669))
  (segment (start 252.541343 120.1745) (end 252.717657 120.1745) (width 0.122) (layer "B.Cu") (net 669))
  (arc (start 252.541343 120.1745) (mid 252.464807 120.159276) (end 252.399922 120.115922) (width 0.122) (layer "B.Cu") (net 669))
  (arc (start 252.875711 120.099289) (mid 252.897388 120.066847) (end 252.905 120.028579) (width 0.122) (layer "B.Cu") (net 669))
  (arc (start 252.717657 120.1745) (mid 252.794194 120.159276) (end 252.859079 120.115921) (width 0.122) (layer "B.Cu") (net 669))
  (via (at 248.46 118.11) (size 0.5) (drill 0.2) (layers "F.Cu" "B.Cu") (net 736))
  (via (at 172.65 119.675) (size 0.5) (drill 0.2) (layers "F.Cu" "B.Cu") (net 736))
  (segment (start 184.05 120.8) (end 192.94 120.8) (width 0.15) (layer "In7.Cu") (net 736))
  (segment (start 200.615 114.845) (end 202.455 114.845) (width 0.15) (layer "In7.Cu") (net 736))
  (segment (start 197.34 116.4) (end 199.06 116.4) (width 0.15) (layer "In7.Cu") (net 736))
  (segment (start 245.7 117.9) (end 246.4 118.6) (width 0.15) (layer "In7.Cu") (net 736))
  (segment (start 180.72 120.8) (end 181.22 120.3) (width 0.15) (layer "In7.Cu") (net 736))
  (segment (start 175.8875 120.8) (end 180.72 120.8) (width 0.15) (layer "In7.Cu") (net 736))
  (segment (start 246.4 118.6) (end 247.97 118.6) (width 0.15) (layer "In7.Cu") (net 736))
  (segment (start 203.875 113.425) (end 237.15 113.425) (width 0.15) (layer "In7.Cu") (net 736))
  (segment (start 172.65 119.675) (end 174.7625 119.675) (width 0.15) (layer "In7.Cu") (net 736))
  (segment (start 183.55 120.3) (end 184.05 120.8) (width 0.15) (layer "In7.Cu") (net 736))
  (segment (start 174.7625 119.675) (end 175.8875 120.8) (width 0.15) (layer "In7.Cu") (net 736))
  (segment (start 247.97 118.6) (end 248.46 118.11) (width 0.15) (layer "In7.Cu") (net 736))
  (segment (start 202.455 114.845) (end 203.875 113.425) (width 0.15) (layer "In7.Cu") (net 736))
  (segment (start 181.22 120.3) (end 183.55 120.3) (width 0.15) (layer "In7.Cu") (net 736))
  (segment (start 199.06 116.4) (end 200.615 114.845) (width 0.15) (layer "In7.Cu") (net 736))
  (segment (start 237.15 113.425) (end 241.625 117.9) (width 0.15) (layer "In7.Cu") (net 736))
  (segment (start 241.625 117.9) (end 245.7 117.9) (width 0.15) (layer "In7.Cu") (net 736))
  (segment (start 192.94 120.8) (end 197.34 116.4) (width 0.15) (layer "In7.Cu") (net 736))
  (segment (start 166.195311 105.920311) (end 173.05 112.775) (width 0.15) (layer "B.Cu") (net 736))
  (segment (start 249.095 118) (end 249.095 118.415) (width 0.1) (layer "B.Cu") (net 736))
  (segment (start 248.46 118.11) (end 248.641999 117.928001) (width 0.1) (layer "B.Cu") (net 736))
  (segment (start 173.05 112.775) (end 173.05 119.275) (width 0.15) (layer "B.Cu") (net 736))
  (segment (start 249.023001 117.928001) (end 249.095 118) (width 0.1) (layer "B.Cu") (net 736))
  (segment (start 173.05 119.275) (end 172.65 119.675) (width 0.15) (layer "B.Cu") (net 736))
  (segment (start 164.6395 105.920311) (end 166.195311 105.920311) (width 0.15) (layer "B.Cu") (net 736))
  (segment (start 248.641999 117.928001) (end 249.023001 117.928001) (width 0.1) (layer "B.Cu") (net 736))
  (via (at 152.2745 106.795764) (size 0.5) (drill 0.2) (layers "F.Cu" "B.Cu") (net 737))
  (via (at 248.46 117.446) (size 0.5) (drill 0.2) (layers "F.Cu" "B.Cu") (net 737))
  (segment (start 172.425 116.3) (end 176.075 119.95) (width 0.15) (layer "In7.Cu") (net 737))
  (segment (start 203.56 113.06) (end 237.41 113.06) (width 0.15) (layer "In7.Cu") (net 737))
  (segment (start 166.025 115.875) (end 167.50052 115.875) (width 0.15) (layer "In7.Cu") (net 737))
  (segment (start 237.41 113.06) (end 241.84 117.49) (width 0.15) (layer "In7.Cu") (net 737))
  (segment (start 197.06 115.69) (end 198.84 115.69) (width 0.15) (layer "In7.Cu") (net 737))
  (segment (start 165.6 116.3) (end 166.025 115.875) (width 0.15) (layer "In7.Cu") (net 737))
  (segment (start 247.691 118.215) (end 248.46 117.446) (width 0.15) (layer "In7.Cu") (net 737))
  (segment (start 200.345 114.185) (end 202.435 114.185) (width 0.15) (layer "In7.Cu") (net 737))
  (segment (start 245.99 117.49) (end 246.715 118.215) (width 0.15) (layer "In7.Cu") (net 737))
  (segment (start 241.84 117.49) (end 245.99 117.49) (width 0.15) (layer "In7.Cu") (net 737))
  (segment (start 192.8 119.95) (end 197.06 115.69) (width 0.15) (layer "In7.Cu") (net 737))
  (segment (start 153.38 107.04) (end 154.01 107.67) (width 0.15) (layer "In7.Cu") (net 737))
  (segment (start 167.92552 116.3) (end 172.425 116.3) (width 0.15) (layer "In7.Cu") (net 737))
  (segment (start 152.2745 106.795764) (end 152.518736 107.04) (width 0.15) (layer "In7.Cu") (net 737))
  (segment (start 157.98 116.3) (end 165.6 116.3) (width 0.15) (layer "In7.Cu") (net 737))
  (segment (start 152.518736 107.04) (end 153.38 107.04) (width 0.15) (layer "In7.Cu") (net 737))
  (segment (start 154.01 107.67) (end 154.01 113.85) (width 0.15) (layer "In7.Cu") (net 737))
  (segment (start 202.435 114.185) (end 203.56 113.06) (width 0.15) (layer "In7.Cu") (net 737))
  (segment (start 156.24 114.56) (end 157.98 116.3) (width 0.15) (layer "In7.Cu") (net 737))
  (segment (start 176.075 119.95) (end 192.8 119.95) (width 0.15) (layer "In7.Cu") (net 737))
  (segment (start 154.01 113.85) (end 154.72 114.56) (width 0.15) (layer "In7.Cu") (net 737))
  (segment (start 198.84 115.69) (end 200.345 114.185) (width 0.15) (layer "In7.Cu") (net 737))
  (segment (start 246.715 118.215) (end 247.691 118.215) (width 0.15) (layer "In7.Cu") (net 737))
  (segment (start 154.72 114.56) (end 156.24 114.56) (width 0.15) (layer "In7.Cu") (net 737))
  (segment (start 167.50052 115.875) (end 167.92552 116.3) (width 0.15) (layer "In7.Cu") (net 737))
  (segment (start 153.6895 106.920563) (end 152.399299 106.920563) (width 0.15) (layer "B.Cu") (net 737))
  (segment (start 248.992001 117.627999) (end 249.095 117.525) (width 0.1) (layer "B.Cu") (net 737))
  (segment (start 152.399299 106.920563) (end 152.2745 106.795764) (width 0.15) (layer "B.Cu") (net 737))
  (segment (start 249.095 117.525) (end 249.095 117.145) (width 0.1) (layer "B.Cu") (net 737))
  (segment (start 248.46 117.446) (end 248.641999 117.627999) (width 0.1) (layer "B.Cu") (net 737))
  (segment (start 248.641999 117.627999) (end 248.992001 117.627999) (width 0.1) (layer "B.Cu") (net 737))
  (via (at 157.095798 111.698761) (size 0.5) (drill 0.2) (layers "F.Cu" "B.Cu") (net 738))
  (via (at 248.46 114.3) (size 0.5) (drill 0.2) (layers "F.Cu" "B.Cu") (net 738))
  (segment (start 202.182134 110.9) (end 239.375866 110.9) (width 0.1) (layer "In7.Cu") (net 738))
  (segment (start 186.91 116.87) (end 190.702134 116.87) (width 0.1) (layer "In7.Cu") (net 738))
  (segment (start 244.218866 114.723) (end 245.263866 114.723) (width 0.1) (layer "In7.Cu") (net 738))
  (segment (start 186.385 116.187134) (end 186.385 116.345) (width 0.1) (layer "In7.Cu") (net 738))
  (segment (start 196.397134 111.175) (end 201.907134 111.175) (width 0.1) (layer "In7.Cu") (net 738))
  (segment (start 190.702134 116.87) (end 196.397134 111.175) (width 0.1) (layer "In7.Cu") (net 738))
  (segment (start 157.095798 111.698761) (end 157.378641 111.698761) (width 0.1) (layer "In7.Cu") (net 738))
  (segment (start 245.567866 115.027) (end 247.185134 115.027) (width 0.1) (layer "In7.Cu") (net 738))
  (segment (start 243.404866 113.909) (end 244.218866 114.723) (width 0.1) (layer "In7.Cu") (net 738))
  (segment (start 242.384866 113.909) (end 243.404866 113.909) (width 0.1) (layer "In7.Cu") (net 738))
  (segment (start 177.747866 116.87) (end 184.66 116.87) (width 0.1) (layer "In7.Cu") (net 738))
  (segment (start 159.30988 113.63) (end 174.507866 113.63) (width 0.1) (layer "In7.Cu") (net 738))
  (segment (start 185.935 117.252866) (end 185.935 116.187134) (width 0.1) (layer "In7.Cu") (net 738))
  (segment (start 248.278001 114.118001) (end 248.46 114.3) (width 0.1) (layer "In7.Cu") (net 738))
  (segment (start 247.185134 115.027) (end 248.094133 114.118001) (width 0.1) (layer "In7.Cu") (net 738))
  (segment (start 184.885 117.095) (end 184.885 117.252866) (width 0.1) (layer "In7.Cu") (net 738))
  (segment (start 248.094133 114.118001) (end 248.278001 114.118001) (width 0.1) (layer "In7.Cu") (net 738))
  (segment (start 245.263866 114.723) (end 245.567866 115.027) (width 0.1) (layer "In7.Cu") (net 738))
  (segment (start 157.378641 111.698761) (end 159.30988 113.63) (width 0.1) (layer "In7.Cu") (net 738))
  (segment (start 174.507866 113.63) (end 177.747866 116.87) (width 0.1) (layer "In7.Cu") (net 738))
  (segment (start 239.375866 110.9) (end 242.384866 113.909) (width 0.1) (layer "In7.Cu") (net 738))
  (segment (start 201.907134 111.175) (end 202.182134 110.9) (width 0.1) (layer "In7.Cu") (net 738))
  (arc (start 184.885 117.252866) (mid 185.038769 117.624097) (end 185.41 117.777866) (width 0.1) (layer "In7.Cu") (net 738))
  (arc (start 186.385 116.345) (mid 186.538769 116.716231) (end 186.91 116.87) (width 0.1) (layer "In7.Cu") (net 738))
  (arc (start 185.41 117.777866) (mid 185.781231 117.624097) (end 185.935 117.252866) (width 0.1) (layer "In7.Cu") (net 738))
  (arc (start 186.16 115.962134) (mid 186.319099 116.028035) (end 186.385 116.187134) (width 0.1) (layer "In7.Cu") (net 738))
  (arc (start 184.66 116.87) (mid 184.819099 116.935901) (end 184.885 117.095) (width 0.1) (layer "In7.Cu") (net 738))
  (arc (start 185.935 116.187134) (mid 186.000901 116.028035) (end 186.16 115.962134) (width 0.1) (layer "In7.Cu") (net 738))
  (segment (start 157.095798 111.415918) (end 157.095798 111.698761) (width 0.1) (layer "B.Cu") (net 738))
  (segment (start 156.700038 110.397828) (end 156.700038 111.020158) (width 0.1) (layer "B.Cu") (net 738))
  (segment (start 249.095 114.19) (end 249.095 114.605) (width 0.1) (layer "B.Cu") (net 738))
  (segment (start 249.023001 114.118001) (end 249.095 114.19) (width 0.1) (layer "B.Cu") (net 738))
  (segment (start 156.914499 110.183367) (end 156.700038 110.397828) (width 0.1) (layer "B.Cu") (net 738))
  (segment (start 156.700038 111.020158) (end 157.095798 111.415918) (width 0.1) (layer "B.Cu") (net 738))
  (segment (start 156.914499 109.145499) (end 156.914499 110.183367) (width 0.1) (layer "B.Cu") (net 738))
  (segment (start 248.641999 114.118001) (end 249.023001 114.118001) (width 0.1) (layer "B.Cu") (net 738))
  (segment (start 248.46 114.3) (end 248.641999 114.118001) (width 0.1) (layer "B.Cu") (net 738))
  (via (at 157.590774 111.203785) (size 0.5) (drill 0.2) (layers "F.Cu" "B.Cu") (net 739))
  (via (at 248.46 113.636) (size 0.5) (drill 0.2) (layers "F.Cu" "B.Cu") (net 739))
  (segment (start 243.529134 113.609) (end 242.509134 113.609) (width 0.1) (layer "In7.Cu") (net 739))
  (segment (start 244.343134 114.423) (end 243.529134 113.609) (width 0.1) (layer "In7.Cu") (net 739))
  (segment (start 157.590774 111.486628) (end 157.590774 111.203785) (width 0.1) (layer "In7.Cu") (net 739))
  (segment (start 247.969867 113.817999) (end 247.060866 114.727) (width 0.1) (layer "In7.Cu") (net 739))
  (segment (start 248.278001 113.817999) (end 247.969867 113.817999) (width 0.1) (layer "In7.Cu") (net 739))
  (segment (start 158.159862 111.69369) (end 158.159863 111.69369) (width 0.1) (layer "In7.Cu") (net 739))
  (segment (start 201.782866 110.875) (end 196.272866 110.875) (width 0.1) (layer "In7.Cu") (net 739))
  (segment (start 157.802073 111.697927) (end 157.590774 111.486628) (width 0.1) (layer "In7.Cu") (net 739))
  (segment (start 185.185 117.252866) (end 185.185 117.095) (width 0.1) (layer "In7.Cu") (net 739))
  (segment (start 239.500134 110.6) (end 202.057866 110.6) (width 0.1) (layer "In7.Cu") (net 739))
  (segment (start 190.577866 116.57) (end 186.91 116.57) (width 0.1) (layer "In7.Cu") (net 739))
  (segment (start 196.272866 110.875) (end 190.577866 116.57) (width 0.1) (layer "In7.Cu") (net 739))
  (segment (start 177.872134 116.57) (end 174.632134 113.33) (width 0.1) (layer "In7.Cu") (net 739))
  (segment (start 245.388134 114.423) (end 244.343134 114.423) (width 0.1) (layer "In7.Cu") (net 739))
  (segment (start 247.060866 114.727) (end 245.692134 114.727) (width 0.1) (layer "In7.Cu") (net 739))
  (segment (start 185.635 116.187134) (end 185.635 117.252866) (width 0.1) (layer "In7.Cu") (net 739))
  (segment (start 245.692134 114.727) (end 245.388134 114.423) (width 0.1) (layer "In7.Cu") (net 739))
  (segment (start 248.46 113.636) (end 248.278001 113.817999) (width 0.1) (layer "In7.Cu") (net 739))
  (segment (start 158.155626 111.874703) (end 158.159861 111.870467) (width 0.1) (layer "In7.Cu") (net 739))
  (segment (start 242.509134 113.609) (end 239.500134 110.6) (width 0.1) (layer "In7.Cu") (net 739))
  (segment (start 157.983086 111.693691) (end 157.97885 111.697926) (width 0.1) (layer "In7.Cu") (net 739))
  (segment (start 174.632134 113.33) (end 159.434146 113.33) (width 0.1) (layer "In7.Cu") (net 739))
  (segment (start 184.66 116.57) (end 177.872134 116.57) (width 0.1) (layer "In7.Cu") (net 739))
  (segment (start 186.685 116.345) (end 186.685 116.187134) (width 0.1) (layer "In7.Cu") (net 739))
  (segment (start 159.434146 113.33) (end 158.155625 112.05148) (width 0.1) (layer "In7.Cu") (net 739))
  (segment (start 202.057866 110.6) (end 201.782866 110.875) (width 0.1) (layer "In7.Cu") (net 739))
  (arc (start 185.635 117.252866) (mid 185.569099 117.411965) (end 185.41 117.477866) (width 0.1) (layer "In7.Cu") (net 739))
  (arc (start 158.159863 111.69369) (mid 158.071474 111.657079) (end 157.983086 111.693691) (width 0.1) (layer "In7.Cu") (net 739))
  (arc (start 186.16 115.662134) (mid 185.788769 115.815903) (end 185.635 116.187134) (width 0.1) (layer "In7.Cu") (net 739))
  (arc (start 158.159861 111.870467) (mid 158.196473 111.782079) (end 158.159862 111.69369) (width 0.1) (layer "In7.Cu") (net 739))
  (arc (start 157.97885 111.697926) (mid 157.890462 111.734538) (end 157.802073 111.697927) (width 0.1) (layer "In7.Cu") (net 739))
  (arc (start 185.41 117.477866) (mid 185.250901 117.411965) (end 185.185 117.252866) (width 0.1) (layer "In7.Cu") (net 739))
  (arc (start 186.685 116.187134) (mid 186.531231 115.815903) (end 186.16 115.662134) (width 0.1) (layer "In7.Cu") (net 739))
  (arc (start 185.185 117.095) (mid 185.031231 116.723769) (end 184.66 116.57) (width 0.1) (layer "In7.Cu") (net 739))
  (arc (start 158.155625 112.05148) (mid 158.119014 111.963091) (end 158.155626 111.874703) (width 0.1) (layer "In7.Cu") (net 739))
  (arc (start 186.91 116.57) (mid 186.750901 116.504099) (end 186.685 116.345) (width 0.1) (layer "In7.Cu") (net 739))
  (segment (start 157.000038 110.522096) (end 157.000038 110.895892) (width 0.1) (layer "B.Cu") (net 739))
  (segment (start 157.000038 110.895892) (end 157.307931 111.203785) (width 0.1) (layer "B.Cu") (net 739))
  (segment (start 249.095 113.715) (end 249.095 113.335) (width 0.1) (layer "B.Cu") (net 739))
  (segment (start 157.414501 109.145499) (end 157.414501 109.455499) (width 0.1) (layer "B.Cu") (net 739))
  (segment (start 157.2145 110.1145) (end 157.2145 110.307634) (width 0.1) (layer "B.Cu") (net 739))
  (segment (start 157.414501 109.455499) (end 157.2145 109.6555) (width 0.1) (layer "B.Cu") (net 739))
  (segment (start 248.641999 113.817999) (end 248.992001 113.817999) (width 0.1) (layer "B.Cu") (net 739))
  (segment (start 157.2145 109.6555) (end 157.2145 109.7145) (width 0.1) (layer "B.Cu") (net 739))
  (segment (start 157.2145 110.0645) (end 157.2145 110.1145) (width 0.1) (layer "B.Cu") (net 739))
  (segment (start 157.3645 109.8645) (end 157.3645 109.9145) (width 0.1) (layer "B.Cu") (net 739))
  (segment (start 248.46 113.636) (end 248.641999 113.817999) (width 0.1) (layer "B.Cu") (net 739))
  (segment (start 248.992001 113.817999) (end 249.095 113.715) (width 0.1) (layer "B.Cu") (net 739))
  (segment (start 157.2145 110.307634) (end 157.000038 110.522096) (width 0.1) (layer "B.Cu") (net 739))
  (segment (start 157.307931 111.203785) (end 157.590774 111.203785) (width 0.1) (layer "B.Cu") (net 739))
  (arc (start 157.2145 109.7145) (mid 157.236467 109.767533) (end 157.2895 109.7895) (width 0.1) (layer "B.Cu") (net 739))
  (arc (start 157.3645 109.9145) (mid 157.342533 109.967533) (end 157.2895 109.9895) (width 0.1) (layer "B.Cu") (net 739))
  (arc (start 157.2895 109.7895) (mid 157.342533 109.811467) (end 157.3645 109.8645) (width 0.1) (layer "B.Cu") (net 739))
  (arc (start 157.2895 109.9895) (mid 157.236467 110.011467) (end 157.2145 110.0645) (width 0.1) (layer "B.Cu") (net 739))
  (via (at 162.5958 111.698761) (size 0.5) (drill 0.2) (layers "F.Cu" "B.Cu") (net 740))
  (via (at 248.46 110.49) (size 0.5) (drill 0.2) (layers "F.Cu" "B.Cu") (net 740))
  (segment (start 181.54 110.508199) (end 181.54 108.991801) (width 0.1) (layer "In7.Cu") (net 740))
  (segment (start 162.878643 111.698761) (end 163.079882 111.9) (width 0.1) (layer "In7.Cu") (net 740))
  (segment (start 245.106866 110.896) (end 245.435866 111.225) (width 0.1) (layer "In7.Cu") (net 740))
  (segment (start 178.877866 109.9) (end 179.64 109.9) (width 0.1) (layer "In7.Cu") (net 740))
  (segment (start 185.947134 109.075) (end 201.047134 109.075) (width 0.1) (layer "In7.Cu") (net 740))
  (segment (start 247.237134 111.225) (end 248.154133 110.308001) (width 0.1) (layer "In7.Cu") (net 740))
  (segment (start 175.222134 109.08) (end 178.057866 109.08) (width 0.1) (layer "In7.Cu") (net 740))
  (segment (start 248.154133 110.308001) (end 248.278001 110.308001) (width 0.1) (layer "In7.Cu") (net 740))
  (segment (start 241.444866 108.51) (end 243.830866 110.896) (width 0.1) (layer "In7.Cu") (net 740))
  (segment (start 181.94 108.991801) (end 181.94 110.508199) (width 0.1) (layer "In7.Cu") (net 740))
  (segment (start 165.712134 111.45) (end 172.852134 111.45) (width 0.1) (layer "In7.Cu") (net 740))
  (segment (start 163.079882 111.9) (end 165.262134 111.9) (width 0.1) (layer "In7.Cu") (net 740))
  (segment (start 184.54 109.9) (end 185.122134 109.9) (width 0.1) (layer "In7.Cu") (net 740))
  (segment (start 172.852134 111.45) (end 175.222134 109.08) (width 0.1) (layer "In7.Cu") (net 740))
  (segment (start 165.262134 111.9) (end 165.712134 111.45) (width 0.1) (layer "In7.Cu") (net 740))
  (segment (start 180.54 108.991801) (end 180.54 110.508199) (width 0.1) (layer "In7.Cu") (net 740))
  (segment (start 182.94 110.508199) (end 182.94 108.991801) (width 0.1) (layer "In7.Cu") (net 740))
  (segment (start 183.34 108.991801) (end 183.34 110.508199) (width 0.1) (layer "In7.Cu") (net 740))
  (segment (start 248.278001 110.308001) (end 248.46 110.49) (width 0.1) (layer "In7.Cu") (net 740))
  (segment (start 184.34 110.508199) (end 184.34 110.1) (width 0.1) (layer "In7.Cu") (net 740))
  (segment (start 180.14 109.4) (end 180.14 108.991801) (width 0.1) (layer "In7.Cu") (net 740))
  (segment (start 178.057866 109.08) (end 178.877866 109.9) (width 0.1) (layer "In7.Cu") (net 740))
  (segment (start 201.047134 109.075) (end 201.612134 108.51) (width 0.1) (layer "In7.Cu") (net 740))
  (segment (start 162.5958 111.698761) (end 162.878643 111.698761) (width 0.1) (layer "In7.Cu") (net 740))
  (segment (start 243.830866 110.896) (end 245.106866 110.896) (width 0.1) (layer "In7.Cu") (net 740))
  (segment (start 245.435866 111.225) (end 247.237134 111.225) (width 0.1) (layer "In7.Cu") (net 740))
  (segment (start 201.612134 108.51) (end 241.444866 108.51) (width 0.1) (layer "In7.Cu") (net 740))
  (segment (start 185.122134 109.9) (end 185.947134 109.075) (width 0.1) (layer "In7.Cu") (net 740))
  (arc (start 181.94 110.508199) (mid 182.086447 110.861752) (end 182.44 111.008199) (width 0.1) (layer "In7.Cu") (net 740))
  (arc (start 181.54 108.991801) (mid 181.598579 108.85038) (end 181.74 108.791801) (width 0.1) (layer "In7.Cu") (net 740))
  (arc (start 183.84 111.008199) (mid 184.193553 110.861752) (end 184.34 110.508199) (width 0.1) (layer "In7.Cu") (net 740))
  (arc (start 180.54 110.508199) (mid 180.686447 110.861752) (end 181.04 111.008199) (width 0.1) (layer "In7.Cu") (net 740))
  (arc (start 183.14 108.791801) (mid 183.281421 108.85038) (end 183.34 108.991801) (width 0.1) (layer "In7.Cu") (net 740))
  (arc (start 179.64 109.9) (mid 179.993553 109.753553) (end 180.14 109.4) (width 0.1) (layer "In7.Cu") (net 740))
  (arc (start 180.14 108.991801) (mid 180.198579 108.85038) (end 180.34 108.791801) (width 0.1) (layer "In7.Cu") (net 740))
  (arc (start 180.34 108.791801) (mid 180.481421 108.85038) (end 180.54 108.991801) (width 0.1) (layer "In7.Cu") (net 740))
  (arc (start 183.34 110.508199) (mid 183.486447 110.861752) (end 183.84 111.008199) (width 0.1) (layer "In7.Cu") (net 740))
  (arc (start 181.04 111.008199) (mid 181.393553 110.861752) (end 181.54 110.508199) (width 0.1) (layer "In7.Cu") (net 740))
  (arc (start 182.94 108.991801) (mid 182.998579 108.85038) (end 183.14 108.791801) (width 0.1) (layer "In7.Cu") (net 740))
  (arc (start 181.74 108.791801) (mid 181.881421 108.85038) (end 181.94 108.991801) (width 0.1) (layer "In7.Cu") (net 740))
  (arc (start 184.34 110.1) (mid 184.398579 109.958579) (end 184.54 109.9) (width 0.1) (layer "In7.Cu") (net 740))
  (arc (start 182.44 111.008199) (mid 182.793553 110.861752) (end 182.94 110.508199) (width 0.1) (layer "In7.Cu") (net 740))
  (segment (start 162.20004 110.397828) (end 162.20004 111.020158) (width 0.1) (layer "B.Cu") (net 740))
  (segment (start 248.641999 110.308001) (end 249.023001 110.308001) (width 0.1) (layer "B.Cu") (net 740))
  (segment (start 162.414501 110.183367) (end 162.20004 110.397828) (width 0.1) (layer "B.Cu") (net 740))
  (segment (start 162.20004 111.020158) (end 162.5958 111.415918) (width 0.1) (layer "B.Cu") (net 740))
  (segment (start 162.5958 111.415918) (end 162.5958 111.698761) (width 0.1) (layer "B.Cu") (net 740))
  (segment (start 248.46 110.49) (end 248.641999 110.308001) (width 0.1) (layer "B.Cu") (net 740))
  (segment (start 249.023001 110.308001) (end 249.095 110.38) (width 0.1) (layer "B.Cu") (net 740))
  (segment (start 249.095 110.38) (end 249.095 110.795) (width 0.1) (layer "B.Cu") (net 740))
  (segment (start 162.414501 109.145499) (end 162.414501 110.183367) (width 0.1) (layer "B.Cu") (net 740))
  (via (at 248.46 109.826) (size 0.5) (drill 0.2) (layers "F.Cu" "B.Cu") (net 741))
  (via (at 163.090776 111.203785) (size 0.5) (drill 0.2) (layers "F.Cu" "B.Cu") (net 741))
  (segment (start 248.029867 110.007999) (end 248.278001 110.007999) (width 0.1) (layer "In7.Cu") (net 741))
  (segment (start 245.560134 110.925) (end 247.112866 110.925) (width 0.1) (layer "In7.Cu") (net 741))
  (segment (start 245.231134 110.596) (end 245.560134 110.925) (width 0.1) (layer "In7.Cu") (net 741))
  (segment (start 180.84 108.991801) (end 180.84 110.508199) (width 0.1) (layer "In7.Cu") (net 741))
  (segment (start 172.727866 111.15) (end 175.097866 108.78) (width 0.1) (layer "In7.Cu") (net 741))
  (segment (start 243.955134 110.596) (end 245.231134 110.596) (width 0.1) (layer "In7.Cu") (net 741))
  (segment (start 183.64 108.991801) (end 183.64 110.508199) (width 0.1) (layer "In7.Cu") (net 741))
  (segment (start 247.112866 110.925) (end 248.029867 110.007999) (width 0.1) (layer "In7.Cu") (net 741))
  (segment (start 248.278001 110.007999) (end 248.46 109.826) (width 0.1) (layer "In7.Cu") (net 741))
  (segment (start 179.002134 109.6) (end 179.64 109.6) (width 0.1) (layer "In7.Cu") (net 741))
  (segment (start 201.487866 108.21) (end 241.569134 108.21) (width 0.1) (layer "In7.Cu") (net 741))
  (segment (start 200.922866 108.775) (end 201.487866 108.21) (width 0.1) (layer "In7.Cu") (net 741))
  (segment (start 178.182134 108.78) (end 179.002134 109.6) (width 0.1) (layer "In7.Cu") (net 741))
  (segment (start 182.24 108.991801) (end 182.24 110.508199) (width 0.1) (layer "In7.Cu") (net 741))
  (segment (start 175.097866 108.78) (end 178.182134 108.78) (width 0.1) (layer "In7.Cu") (net 741))
  (segment (start 163.55 111.5) (end 163.55 111.481567) (width 0.1) (layer "In7.Cu") (net 741))
  (segment (start 241.569134 108.21) (end 243.955134 110.596) (width 0.1) (layer "In7.Cu") (net 741))
  (segment (start 184.54 109.6) (end 184.997866 109.6) (width 0.1) (layer "In7.Cu") (net 741))
  (segment (start 165.587866 111.15) (end 172.727866 111.15) (width 0.1) (layer "In7.Cu") (net 741))
  (segment (start 184.04 110.508199) (end 184.04 110.1) (width 0.1) (layer "In7.Cu") (net 741))
  (segment (start 181.24 110.508199) (end 181.24 108.991801) (width 0.1) (layer "In7.Cu") (net 741))
  (segment (start 182.64 110.508199) (end 182.64 108.991801) (width 0.1) (layer "In7.Cu") (net 741))
  (segment (start 163.090776 111.486628) (end 163.204148 111.6) (width 0.1) (layer "In7.Cu") (net 741))
  (segment (start 163.204148 111.6) (end 163.45 111.6) (width 0.1) (layer "In7.Cu") (net 741))
  (segment (start 163.85 111.6) (end 165.137866 111.6) (width 0.1) (layer "In7.Cu") (net 741))
  (segment (start 163.75 111.481567) (end 163.75 111.5) (width 0.1) (layer "In7.Cu") (net 741))
  (segment (start 179.84 109.4) (end 179.84 108.991801) (width 0.1) (layer "In7.Cu") (net 741))
  (segment (start 185.822866 108.775) (end 200.922866 108.775) (width 0.1) (layer "In7.Cu") (net 741))
  (segment (start 184.997866 109.6) (end 185.822866 108.775) (width 0.1) (layer "In7.Cu") (net 741))
  (segment (start 163.090776 111.203785) (end 163.090776 111.486628) (width 0.1) (layer "In7.Cu") (net 741))
  (segment (start 165.137866 111.6) (end 165.587866 111.15) (width 0.1) (layer "In7.Cu") (net 741))
  (arc (start 163.55 111.481567) (mid 163.579289 111.410856) (end 163.65 111.381567) (width 0.1) (layer "In7.Cu") (net 741))
  (arc (start 181.04 110.708199) (mid 181.181421 110.64962) (end 181.24 110.508199) (width 0.1) (layer "In7.Cu") (net 741))
  (arc (start 184.04 110.1) (mid 184.186447 109.746447) (end 184.54 109.6) (width 0.1) (layer "In7.Cu") (net 741))
  (arc (start 179.84 108.991801) (mid 179.986447 108.638248) (end 180.34 108.491801) (width 0.1) (layer "In7.Cu") (net 741))
  (arc (start 179.64 109.6) (mid 179.781421 109.541421) (end 179.84 109.4) (width 0.1) (layer "In7.Cu") (net 741))
  (arc (start 163.65 111.381567) (mid 163.720711 111.410856) (end 163.75 111.481567) (width 0.1) (layer "In7.Cu") (net 741))
  (arc (start 182.44 110.708199) (mid 182.581421 110.64962) (end 182.64 110.508199) (width 0.1) (layer "In7.Cu") (net 741))
  (arc (start 181.24 108.991801) (mid 181.386447 108.638248) (end 181.74 108.491801) (width 0.1) (layer "In7.Cu") (net 741))
  (arc (start 183.84 110.708199) (mid 183.981421 110.64962) (end 184.04 110.508199) (width 0.1) (layer "In7.Cu") (net 741))
  (arc (start 183.64 110.508199) (mid 183.698579 110.64962) (end 183.84 110.708199) (width 0.1) (layer "In7.Cu") (net 741))
  (arc (start 182.24 110.508199) (mid 182.298579 110.64962) (end 182.44 110.708199) (width 0.1) (layer "In7.Cu") (net 741))
  (arc (start 182.64 108.991801) (mid 182.786447 108.638248) (end 183.14 108.491801) (width 0.1) (layer "In7.Cu") (net 741))
  (arc (start 183.14 108.491801) (mid 183.493553 108.638248) (end 183.64 108.991801) (width 0.1) (layer "In7.Cu") (net 741))
  (arc (start 180.34 108.491801) (mid 180.693553 108.638248) (end 180.84 108.991801) (width 0.1) (layer "In7.Cu") (net 741))
  (arc (start 163.45 111.6) (mid 163.520711 111.570711) (end 163.55 111.5) (width 0.1) (layer "In7.Cu") (net 741))
  (arc (start 180.84 110.508199) (mid 180.898579 110.64962) (end 181.04 110.708199) (width 0.1) (layer "In7.Cu") (net 741))
  (arc (start 181.74 108.491801) (mid 182.093553 108.638248) (end 182.24 108.991801) (width 0.1) (layer "In7.Cu") (net 741))
  (arc (start 163.75 111.5) (mid 163.779289 111.570711) (end 163.85 111.6) (width 0.1) (layer "In7.Cu") (net 741))
  (segment (start 162.714502 110.1145) (end 162.714502 110.307634) (width 0.1) (layer "B.Cu") (net 741))
  (segment (start 162.714502 110.0645) (end 162.714502 110.1145) (width 0.1) (layer "B.Cu") (net 741))
  (segment (start 162.914503 109.455499) (end 162.714502 109.6555) (width 0.1) (layer "B.Cu") (net 741))
  (segment (start 248.641999 110.007999) (end 248.992001 110.007999) (width 0.1) (layer "B.Cu") (net 741))
  (segment (start 249.095 109.905) (end 249.095 109.525) (width 0.1) (layer "B.Cu") (net 741))
  (segment (start 162.714502 110.307634) (end 162.50004 110.522096) (width 0.1) (layer "B.Cu") (net 741))
  (segment (start 162.807933 111.203785) (end 163.090776 111.203785) (width 0.1) (layer "B.Cu") (net 741))
  (segment (start 248.46 109.826) (end 248.641999 110.007999) (width 0.1) (layer "B.Cu") (net 741))
  (segment (start 162.50004 110.895892) (end 162.807933 111.203785) (width 0.1) (layer "B.Cu") (net 741))
  (segment (start 162.914503 109.145499) (end 162.914503 109.455499) (width 0.1) (layer "B.Cu") (net 741))
  (segment (start 248.992001 110.007999) (end 249.095 109.905) (width 0.1) (layer "B.Cu") (net 741))
  (segment (start 162.50004 110.522096) (end 162.50004 110.895892) (width 0.1) (layer "B.Cu") (net 741))
  (segment (start 162.714502 109.6555) (end 162.714502 109.7145) (width 0.1) (layer "B.Cu") (net 741))
  (segment (start 162.864502 109.8645) (end 162.864502 109.9145) (width 0.1) (layer "B.Cu") (net 741))
  (arc (start 162.789502 109.7895) (mid 162.842535 109.811467) (end 162.864502 109.8645) (width 0.1) (layer "B.Cu") (net 741))
  (arc (start 162.864502 109.9145) (mid 162.842535 109.967533) (end 162.789502 109.9895) (width 0.1) (layer "B.Cu") (net 741))
  (arc (start 162.789502 109.9895) (mid 162.736469 110.011467) (end 162.714502 110.0645) (width 0.1) (layer "B.Cu") (net 741))
  (arc (start 162.714502 109.7145) (mid 162.736469 109.767533) (end 162.789502 109.7895) (width 0.1) (layer "B.Cu") (net 741))
  (segment (start 174.136328 98.536328) (end 173.674581 98.074581) (width 0.1) (layer "F.Cu") (net 751))
  (segment (start 174.136328 98.560008) (end 174.136328 98.536328) (width 0.1) (layer "F.Cu") (net 751))
  (via (at 170.45 107) (size 0.5) (drill 0.2) (layers "F.Cu" "B.Cu") (net 751))
  (via (at 240.775 119.4) (size 0.5) (drill 0.2) (layers "F.Cu" "B.Cu") (net 751))
  (via (at 173.674581 98.074581) (size 0.5) (drill 0.2) (layers "F.Cu" "B.Cu") (net 751))
  (via (at 219.22 114.32) (size 0.5) (drill 0.2) (layers "F.Cu" "B.Cu") (net 751))
  (segment (start 173.15 104.3) (end 173.15 98.599162) (width 0.1) (layer "In2.Cu") (net 751))
  (segment (start 173.15 98.599162) (end 173.674581 98.074581) (width 0.1) (layer "In2.Cu") (net 751))
  (segment (start 170.45 107) (end 173.15 104.3) (width 0.1) (layer "In2.Cu") (net 751))
  (segment (start 220.22 114.32) (end 220.4 114.5) (width 0.127) (layer "In7.Cu") (net 751))
  (segment (start 220.4 114.5) (end 222.3 114.5) (width 0.127) (layer "In7.Cu") (net 751))
  (segment (start 236.303636 114.3) (end 240.775 118.771364) (width 0.127) (layer "In7.Cu") (net 751))
  (segment (start 222.5 114.3) (end 236.303636 114.3) (width 0.127) (layer "In7.Cu") (net 751))
  (segment (start 240.775 118.771364) (end 240.775 119.4) (width 0.127) (layer "In7.Cu") (net 751))
  (segment (start 222.3 114.5) (end 222.5 114.3) (width 0.127) (layer "In7.Cu") (net 751))
  (segment (start 219.22 114.32) (end 220.22 114.32) (width 0.127) (layer "In7.Cu") (net 751))
  (segment (start 245.9 123.7) (end 246.3 124.1) (width 0.1) (layer "B.Cu") (net 751))
  (segment (start 179.567136 108.7965) (end 179.770636 109) (width 0.127) (layer "B.Cu") (net 751))
  (segment (start 246.734314 124.1) (end 247.034314 123.8) (width 0.12) (layer "B.Cu") (net 751))
  (segment (start 167.67 102.8) (end 169.19 104.32) (width 0.127) (layer "B.Cu") (net 751))
  (segment (start 240.885 119.4) (end 241.585 120.1) (width 0.12) (layer "B.Cu") (net 751))
  (segment (start 169.19 104.32) (end 169.19 105.73) (width 0.127) (layer "B.Cu") (net 751))
  (segment (start 179.770636 109) (end 209.4 109) (width 0.127) (layer "B.Cu") (net 751))
  (segment (start 247.52 123.8) (end 247.825 123.495) (width 0.12) (layer "B.Cu") (net 751))
  (segment (start 213.975 113.575) (end 217.125 113.575) (width 0.127) (layer "B.Cu") (net 751))
  (segment (start 219 114.1) (end 219.22 114.32) (width 0.127) (layer "B.Cu") (net 751))
  (segment (start 179.029364 109) (end 179.232864 108.7965) (width 0.127) (layer "B.Cu") (net 751))
  (segment (start 245.9 123.1) (end 245.9 123.7) (width 0.1) (layer "B.Cu") (net 751))
  (segment (start 246.3 124.1) (end 246.734314 124.1) (width 0.12) (layer "B.Cu") (net 751))
  (segment (start 247.034314 123.8) (end 247.52 123.8) (width 0.12) (layer "B.Cu") (net 751))
  (segment (start 166.685 102.8) (end 167.67 102.8) (width 0.127) (layer "B.Cu") (net 751))
  (segment (start 169.19 105.73) (end 172.46 109) (width 0.127) (layer "B.Cu") (net 751))
  (segment (start 244.135 122.85) (end 243.7 122.415) (width 0.12) (layer "B.Cu") (net 751))
  (segment (start 243.7 122.415) (end 243.7 121.3) (width 0.12) (layer "B.Cu") (net 751))
  (segment (start 245.65 122.85) (end 245.9 123.1) (width 0.1) (layer "B.Cu") (net 751))
  (segment (start 217.65 114.1) (end 219 114.1) (width 0.127) (layer "B.Cu") (net 751))
  (segment (start 245.25 122.85) (end 244.135 122.85) (width 0.11) (layer "B.Cu") (net 751))
  (segment (start 209.4 109) (end 213.975 113.575) (width 0.127) (layer "B.Cu") (net 751))
  (segment (start 172.46 109) (end 179.029364 109) (width 0.127) (layer "B.Cu") (net 751))
  (segment (start 217.125 113.575) (end 217.65 114.1) (width 0.127) (layer "B.Cu") (net 751))
  (segment (start 242.5 120.1) (end 241.585 120.1) (width 0.12) (layer "B.Cu") (net 751))
  (segment (start 243.7 121.3) (end 242.5 120.1) (width 0.12) (layer "B.Cu") (net 751))
  (segment (start 245.25 122.85) (end 245.65 122.85) (width 0.1) (layer "B.Cu") (net 751))
  (segment (start 179.232864 108.7965) (end 179.567136 108.7965) (width 0.127) (layer "B.Cu") (net 751))
  (segment (start 240.775 119.4) (end 240.885 119.4) (width 0.12) (layer "B.Cu") (net 751))
  (via (at 154.595798 111.698761) (size 0.5) (drill 0.2) (layers "F.Cu" "B.Cu") (net 754))
  (via (at 247.19 116.84) (size 0.5) (drill 0.2) (layers "F.Cu" "B.Cu") (net 754))
  (segment (start 247.008001 116.658001) (end 247.19 116.84) (width 0.1) (layer "In7.Cu") (net 754))
  (segment (start 198.442134 114.9) (end 200.052134 113.29) (width 0.1) (layer "In7.Cu") (net 754))
  (segment (start 203.312134 111.93) (end 238.817866 111.93) (width 0.1) (layer "In7.Cu") (net 754))
  (segment (start 190.884828 119.357306) (end 195.342134 114.9) (width 0.1) (layer "In7.Cu") (net 754))
  (segment (start 158.39988 115.22) (end 173.887866 115.22) (width 0.1) (layer "In7.Cu") (net 754))
  (segment (start 154.595798 111.698761) (end 154.878641 111.698761) (width 0.1) (layer "In7.Cu") (net 754))
  (segment (start 245.807302 115.75) (end 246.715303 116.658001) (width 0.1) (layer "In7.Cu") (net 754))
  (segment (start 173.887866 115.22) (end 178.025172 119.357306) (width 0.1) (layer "In7.Cu") (net 754))
  (segment (start 242.637866 115.75) (end 245.807302 115.75) (width 0.1) (layer "In7.Cu") (net 754))
  (segment (start 178.025172 119.357306) (end 190.884828 119.357306) (width 0.1) (layer "In7.Cu") (net 754))
  (segment (start 201.952134 113.29) (end 203.312134 111.93) (width 0.1) (layer "In7.Cu") (net 754))
  (segment (start 195.342134 114.9) (end 198.442134 114.9) (width 0.1) (layer "In7.Cu") (net 754))
  (segment (start 246.715303 116.658001) (end 247.008001 116.658001) (width 0.1) (layer "In7.Cu") (net 754))
  (segment (start 238.817866 111.93) (end 242.637866 115.75) (width 0.1) (layer "In7.Cu") (net 754))
  (segment (start 154.878641 111.698761) (end 158.39988 115.22) (width 0.1) (layer "In7.Cu") (net 754))
  (segment (start 200.052134 113.29) (end 201.952134 113.29) (width 0.1) (layer "In7.Cu") (net 754))
  (segment (start 154.200038 111.020158) (end 154.595798 111.415918) (width 0.1) (layer "B.Cu") (net 754))
  (segment (start 247.753001 116.658001) (end 247.825 116.73) (width 0.1) (layer "B.Cu") (net 754))
  (segment (start 154.414499 109.145499) (end 154.414499 110.183367) (width 0.1) (layer "B.Cu") (net 754))
  (segment (start 154.595798 111.415918) (end 154.595798 111.698761) (width 0.1) (layer "B.Cu") (net 754))
  (segment (start 247.19 116.84) (end 247.371999 116.658001) (width 0.1) (layer "B.Cu") (net 754))
  (segment (start 247.825 116.73) (end 247.825 117.145) (width 0.1) (layer "B.Cu") (net 754))
  (segment (start 154.414499 110.183367) (end 154.200038 110.397828) (width 0.1) (layer "B.Cu") (net 754))
  (segment (start 247.371999 116.658001) (end 247.753001 116.658001) (width 0.1) (layer "B.Cu") (net 754))
  (segment (start 154.200038 110.397828) (end 154.200038 111.020158) (width 0.1) (layer "B.Cu") (net 754))
  (via (at 155.090774 111.203785) (size 0.5) (drill 0.2) (layers "F.Cu" "B.Cu") (net 755))
  (via (at 247.19 116.176) (size 0.5) (drill 0.2) (layers "F.Cu" "B.Cu") (net 755))
  (segment (start 155.090774 111.486628) (end 155.212073 111.607927) (width 0.1) (layer "In7.Cu") (net 755))
  (segment (start 155.38885 111.607926) (end 155.388849 111.607927) (width 0.1) (layer "In7.Cu") (net 755))
  (segment (start 199.927866 112.99) (end 201.827866 112.99) (width 0.1) (layer "In7.Cu") (net 755))
  (segment (start 198.317866 114.6) (end 199.927866 112.99) (width 0.1) (layer "In7.Cu") (net 755))
  (segment (start 155.568398 111.78193) (end 155.565626 111.784703) (width 0.1) (layer "In7.Cu") (net 755))
  (segment (start 155.388849 111.607927) (end 155.391622 111.605155) (width 0.1) (layer "In7.Cu") (net 755))
  (segment (start 201.827866 112.99) (end 203.187866 111.63) (width 0.1) (layer "In7.Cu") (net 755))
  (segment (start 178.14944 119.057306) (end 190.76056 119.057306) (width 0.1) (layer "In7.Cu") (net 755))
  (segment (start 195.217866 114.6) (end 198.317866 114.6) (width 0.1) (layer "In7.Cu") (net 755))
  (segment (start 247.008001 116.357999) (end 247.19 116.176) (width 0.1) (layer "In7.Cu") (net 755))
  (segment (start 238.942134 111.63) (end 242.762134 115.45) (width 0.1) (layer "In7.Cu") (net 755))
  (segment (start 242.762134 115.45) (end 245.93157 115.45) (width 0.1) (layer "In7.Cu") (net 755))
  (segment (start 203.187866 111.63) (end 238.942134 111.63) (width 0.1) (layer "In7.Cu") (net 755))
  (segment (start 190.76056 119.057306) (end 195.217866 114.6) (width 0.1) (layer "In7.Cu") (net 755))
  (segment (start 155.568398 111.605155) (end 155.568398 111.605154) (width 0.1) (layer "In7.Cu") (net 755))
  (segment (start 174.012134 114.92) (end 178.14944 119.057306) (width 0.1) (layer "In7.Cu") (net 755))
  (segment (start 155.568397 111.781931) (end 155.568398 111.78193) (width 0.1) (layer "In7.Cu") (net 755))
  (segment (start 155.565626 111.961479) (end 155.565625 111.961479) (width 0.1) (layer "In7.Cu") (net 755))
  (segment (start 158.524146 114.92) (end 174.012134 114.92) (width 0.1) (layer "In7.Cu") (net 755))
  (segment (start 155.565625 111.961479) (end 158.524146 114.92) (width 0.1) (layer "In7.Cu") (net 755))
  (segment (start 245.93157 115.45) (end 246.839569 116.357999) (width 0.1) (layer "In7.Cu") (net 755))
  (segment (start 155.090774 111.203785) (end 155.090774 111.486628) (width 0.1) (layer "In7.Cu") (net 755))
  (segment (start 246.839569 116.357999) (end 247.008001 116.357999) (width 0.1) (layer "In7.Cu") (net 755))
  (arc (start 155.212073 111.607927) (mid 155.300462 111.644538) (end 155.38885 111.607926) (width 0.1) (layer "In7.Cu") (net 755))
  (arc (start 155.391622 111.605155) (mid 155.48001 111.568543) (end 155.568398 111.605155) (width 0.1) (layer "In7.Cu") (net 755))
  (arc (start 155.568398 111.605154) (mid 155.605009 111.693543) (end 155.568397 111.781931) (width 0.1) (layer "In7.Cu") (net 755))
  (arc (start 155.565626 111.784703) (mid 155.529014 111.873091) (end 155.565626 111.961479) (width 0.1) (layer "In7.Cu") (net 755))
  (segment (start 154.914501 109.455499) (end 154.7145 109.6555) (width 0.1) (layer "B.Cu") (net 755))
  (segment (start 154.807931 111.203785) (end 155.090774 111.203785) (width 0.1) (layer "B.Cu") (net 755))
  (segment (start 247.371999 116.357999) (end 247.722001 116.357999) (width 0.1) (layer "B.Cu") (net 755))
  (segment (start 247.19 116.176) (end 247.371999 116.357999) (width 0.1) (layer "B.Cu") (net 755))
  (segment (start 154.8645 109.8645) (end 154.8645 109.9145) (width 0.1) (layer "B.Cu") (net 755))
  (segment (start 247.722001 116.357999) (end 247.825 116.255) (width 0.1) (layer "B.Cu") (net 755))
  (segment (start 154.7145 110.1145) (end 154.7145 110.307634) (width 0.1) (layer "B.Cu") (net 755))
  (segment (start 154.7145 109.6555) (end 154.7145 109.7145) (width 0.1) (layer "B.Cu") (net 755))
  (segment (start 247.825 116.255) (end 247.825 115.875) (width 0.1) (layer "B.Cu") (net 755))
  (segment (start 154.500038 110.522096) (end 154.500038 110.895892) (width 0.1) (layer "B.Cu") (net 755))
  (segment (start 154.7145 110.307634) (end 154.500038 110.522096) (width 0.1) (layer "B.Cu") (net 755))
  (segment (start 154.914501 109.145499) (end 154.914501 109.455499) (width 0.1) (layer "B.Cu") (net 755))
  (segment (start 154.500038 110.895892) (end 154.807931 111.203785) (width 0.1) (layer "B.Cu") (net 755))
  (segment (start 154.7145 110.0645) (end 154.7145 110.1145) (width 0.1) (layer "B.Cu") (net 755))
  (arc (start 154.8645 109.9145) (mid 154.842533 109.967533) (end 154.7895 109.9895) (width 0.1) (layer "B.Cu") (net 755))
  (arc (start 154.7145 109.7145) (mid 154.736467 109.767533) (end 154.7895 109.7895) (width 0.1) (layer "B.Cu") (net 755))
  (arc (start 154.7895 109.9895) (mid 154.736467 110.011467) (end 154.7145 110.0645) (width 0.1) (layer "B.Cu") (net 755))
  (arc (start 154.7895 109.7895) (mid 154.842533 109.811467) (end 154.8645 109.8645) (width 0.1) (layer "B.Cu") (net 755))
  (via (at 160.095798 111.698761) (size 0.5) (drill 0.2) (layers "F.Cu" "B.Cu") (net 756))
  (via (at 247.19 113.03) (size 0.5) (drill 0.2) (layers "F.Cu" "B.Cu") (net 756))
  (segment (start 184.24 113.26) (end 185.242134 113.26) (width 0.1) (layer "In7.Cu") (net 756))
  (segment (start 246.275 112.412134) (end 246.710867 112.848001) (width 0.1) (layer "In7.Cu") (net 756))
  (segment (start 166.012134 112.43) (end 174.182134 112.43) (width 0.1) (layer "In7.Cu") (net 756))
  (segment (start 194.962134 110.1) (end 201.312134 110.1) (width 0.1) (layer "In7.Cu") (net 756))
  (segment (start 178.75 112.932134) (end 179.077866 113.26) (width 0.1) (layer "In7.Cu") (net 756))
  (segment (start 176.032134 110.58) (end 177.817866 110.58) (width 0.1) (layer "In7.Cu") (net 756))
  (segment (start 160.095798 111.698761) (end 160.378641 111.698761) (width 0.1) (layer "In7.Cu") (net 756))
  (segment (start 177.817866 110.58) (end 178.75 111.512134) (width 0.1) (layer "In7.Cu") (net 756))
  (segment (start 185.73 112.772134) (end 185.73 111.982134) (width 0.1) (layer "In7.Cu") (net 756))
  (segment (start 201.632134 109.78) (end 240.567866 109.78) (width 0.1) (layer "In7.Cu") (net 756))
  (segment (start 185.73 111.982134) (end 187.132134 110.58) (width 0.1) (layer "In7.Cu") (net 756))
  (segment (start 174.182134 112.43) (end 176.032134 110.58) (width 0.1) (layer "In7.Cu") (net 756))
  (segment (start 185.242134 113.26) (end 185.73 112.772134) (width 0.1) (layer "In7.Cu") (net 756))
  (segment (start 160.378641 111.698761) (end 161.35988 112.68) (width 0.1) (layer "In7.Cu") (net 756))
  (segment (start 181.415 113.798298) (end 181.415 112.421702) (width 0.1) (layer "In7.Cu") (net 756))
  (segment (start 247.008001 112.848001) (end 247.19 113.03) (width 0.1) (layer "In7.Cu") (net 756))
  (segment (start 240.567866 109.78) (end 242.712866 111.925) (width 0.1) (layer "In7.Cu") (net 756))
  (segment (start 161.35988 112.68) (end 165.762134 112.68) (width 0.1) (layer "In7.Cu") (net 756))
  (segment (start 180.265 113.535) (end 180.265 113.798298) (width 0.1) (layer "In7.Cu") (net 756))
  (segment (start 201.312134 110.1) (end 201.632134 109.78) (width 0.1) (layer "In7.Cu") (net 756))
  (segment (start 187.132134 110.58) (end 194.482134 110.58) (width 0.1) (layer "In7.Cu") (net 756))
  (segment (start 246.710867 112.848001) (end 247.008001 112.848001) (width 0.1) (layer "In7.Cu") (net 756))
  (segment (start 194.482134 110.58) (end 194.962134 110.1) (width 0.1) (layer "In7.Cu") (net 756))
  (segment (start 246.062866 111.925) (end 246.275 112.137134) (width 0.1) (layer "In7.Cu") (net 756))
  (segment (start 178.75 111.512134) (end 178.75 112.932134) (width 0.1) (layer "In7.Cu") (net 756))
  (segment (start 246.275 112.137134) (end 246.275 112.412134) (width 0.1) (layer "In7.Cu") (net 756))
  (segment (start 183.115 113.798298) (end 183.115 112.421702) (width 0.1) (layer "In7.Cu") (net 756))
  (segment (start 181.965 112.421702) (end 181.965 113.798298) (width 0.1) (layer "In7.Cu") (net 756))
  (segment (start 165.762134 112.68) (end 166.012134 112.43) (width 0.1) (layer "In7.Cu") (net 756))
  (segment (start 242.712866 111.925) (end 246.062866 111.925) (width 0.1) (layer "In7.Cu") (net 756))
  (segment (start 183.665 112.421702) (end 183.665 112.685) (width 0.1) (layer "In7.Cu") (net 756))
  (segment (start 179.077866 113.26) (end 179.99 113.26) (width 0.1) (layer "In7.Cu") (net 756))
  (arc (start 179.99 113.26) (mid 180.184454 113.340546) (end 180.265 113.535) (width 0.1) (layer "In7.Cu") (net 756))
  (arc (start 183.115 112.421702) (mid 183.195546 112.227248) (end 183.39 112.146702) (width 0.1) (layer "In7.Cu") (net 756))
  (arc (start 181.415 112.421702) (mid 181.495546 112.227248) (end 181.69 112.146702) (width 0.1) (layer "In7.Cu") (net 756))
  (arc (start 183.665 112.685) (mid 183.833414 113.091586) (end 184.24 113.26) (width 0.1) (layer "In7.Cu") (net 756))
  (arc (start 180.265 113.798298) (mid 180.433414 114.204884) (end 180.84 114.373298) (width 0.1) (layer "In7.Cu") (net 756))
  (arc (start 181.69 112.146702) (mid 181.884454 112.227248) (end 181.965 112.421702) (width 0.1) (layer "In7.Cu") (net 756))
  (arc (start 183.39 112.146702) (mid 183.584454 112.227248) (end 183.665 112.421702) (width 0.1) (layer "In7.Cu") (net 756))
  (arc (start 182.54 114.373298) (mid 182.946586 114.204884) (end 183.115 113.798298) (width 0.1) (layer "In7.Cu") (net 756))
  (arc (start 181.965 113.798298) (mid 182.133414 114.204884) (end 182.54 114.373298) (width 0.1) (layer "In7.Cu") (net 756))
  (arc (start 180.84 114.373298) (mid 181.246586 114.204884) (end 181.415 113.798298) (width 0.1) (layer "In7.Cu") (net 756))
  (segment (start 159.914499 109.145499) (end 159.914499 110.183367) (width 0.1) (layer "B.Cu") (net 756))
  (segment (start 247.19 113.03) (end 247.371999 112.848001) (width 0.1) (layer "B.Cu") (net 756))
  (segment (start 159.914499 110.183367) (end 159.700038 110.397828) (width 0.1) (layer "B.Cu") (net 756))
  (segment (start 159.700038 110.397828) (end 159.700038 111.020158) (width 0.1) (layer "B.Cu") (net 756))
  (segment (start 247.371999 112.848001) (end 247.753001 112.848001) (width 0.1) (layer "B.Cu") (net 756))
  (segment (start 247.825 112.92) (end 247.825 113.335) (width 0.1) (layer "B.Cu") (net 756))
  (segment (start 160.095798 111.415918) (end 160.095798 111.698761) (width 0.1) (layer "B.Cu") (net 756))
  (segment (start 159.700038 111.020158) (end 160.095798 111.415918) (width 0.1) (layer "B.Cu") (net 756))
  (segment (start 247.753001 112.848001) (end 247.825 112.92) (width 0.1) (layer "B.Cu") (net 756))
  (via (at 160.590774 111.203785) (size 0.5) (drill 0.2) (layers "F.Cu" "B.Cu") (net 757))
  (via (at 247.19 112.366) (size 0.5) (drill 0.2) (layers "F.Cu" "B.Cu") (net 757))
  (segment (start 160.943494 111.697926) (end 160.943495 111.697928) (width 0.1) (layer "In7.Cu") (net 757))
  (segment (start 181.115 113.798298) (end 181.115 112.421702) (width 0.1) (layer "In7.Cu") (net 757))
  (segment (start 246.187134 111.625) (end 246.575 112.012866) (width 0.1) (layer "In7.Cu") (net 757))
  (segment (start 177.942134 110.28) (end 179.05 111.387866) (width 0.1) (layer "In7.Cu") (net 757))
  (segment (start 161.484146 112.38) (end 165.637866 112.38) (width 0.1) (layer "In7.Cu") (net 757))
  (segment (start 247.008001 112.547999) (end 247.19 112.366) (width 0.1) (layer "In7.Cu") (net 757))
  (segment (start 160.943495 111.697928) (end 160.956501 111.684919) (width 0.1) (layer "In7.Cu") (net 757))
  (segment (start 182.265 112.421702) (end 182.265 113.798298) (width 0.1) (layer "In7.Cu") (net 757))
  (segment (start 179.05 112.807866) (end 179.202134 112.96) (width 0.1) (layer "In7.Cu") (net 757))
  (segment (start 161.084914 111.980768) (end 161.484146 112.38) (width 0.1) (layer "In7.Cu") (net 757))
  (segment (start 161.097922 111.82634) (end 161.097924 111.826341) (width 0.1) (layer "In7.Cu") (net 757))
  (segment (start 180.565 113.535) (end 180.565 113.798298) (width 0.1) (layer "In7.Cu") (net 757))
  (segment (start 161.097924 111.826341) (end 161.084915 111.839347) (width 0.1) (layer "In7.Cu") (net 757))
  (segment (start 240.692134 109.48) (end 242.837134 111.625) (width 0.1) (layer "In7.Cu") (net 757))
  (segment (start 242.837134 111.625) (end 246.187134 111.625) (width 0.1) (layer "In7.Cu") (net 757))
  (segment (start 184.24 112.96) (end 185.117866 112.96) (width 0.1) (layer "In7.Cu") (net 757))
  (segment (start 246.575 112.012866) (end 246.575 112.287866) (width 0.1) (layer "In7.Cu") (net 757))
  (segment (start 246.835133 112.547999) (end 247.008001 112.547999) (width 0.1) (layer "In7.Cu") (net 757))
  (segment (start 194.357866 110.28) (end 194.837866 109.8) (width 0.1) (layer "In7.Cu") (net 757))
  (segment (start 160.590774 111.486628) (end 160.802073 111.697927) (width 0.1) (layer "In7.Cu") (net 757))
  (segment (start 201.187866 109.8) (end 201.507866 109.48) (width 0.1) (layer "In7.Cu") (net 757))
  (segment (start 179.05 111.387866) (end 179.05 112.807866) (width 0.1) (layer "In7.Cu") (net 757))
  (segment (start 160.590774 111.203785) (end 160.590774 111.486628) (width 0.1) (layer "In7.Cu") (net 757))
  (segment (start 185.43 112.647866) (end 185.43 111.857866) (width 0.1) (layer "In7.Cu") (net 757))
  (segment (start 185.43 111.857866) (end 187.007866 110.28) (width 0.1) (layer "In7.Cu") (net 757))
  (segment (start 175.907866 110.28) (end 177.942134 110.28) (width 0.1) (layer "In7.Cu") (net 757))
  (segment (start 194.837866 109.8) (end 201.187866 109.8) (width 0.1) (layer "In7.Cu") (net 757))
  (segment (start 201.507866 109.48) (end 240.692134 109.48) (width 0.1) (layer "In7.Cu") (net 757))
  (segment (start 182.815 113.798298) (end 182.815 112.421702) (width 0.1) (layer "In7.Cu") (net 757))
  (segment (start 187.007866 110.28) (end 194.357866 110.28) (width 0.1) (layer "In7.Cu") (net 757))
  (segment (start 165.637866 112.38) (end 165.887866 112.13) (width 0.1) (layer "In7.Cu") (net 757))
  (segment (start 174.057866 112.13) (end 175.907866 110.28) (width 0.1) (layer "In7.Cu") (net 757))
  (segment (start 179.202134 112.96) (end 179.99 112.96) (width 0.1) (layer "In7.Cu") (net 757))
  (segment (start 183.965 112.421702) (end 183.965 112.685) (width 0.1) (layer "In7.Cu") (net 757))
  (segment (start 185.117866 112.96) (end 185.43 112.647866) (width 0.1) (layer "In7.Cu") (net 757))
  (segment (start 246.575 112.287866) (end 246.835133 112.547999) (width 0.1) (layer "In7.Cu") (net 757))
  (segment (start 165.887866 112.13) (end 174.057866 112.13) (width 0.1) (layer "In7.Cu") (net 757))
  (segment (start 161.097922 111.684918) (end 161.097923 111.684919) (width 0.1) (layer "In7.Cu") (net 757))
  (arc (start 182.265 113.798298) (mid 182.345546 113.992752) (end 182.54 114.073298) (width 0.1) (layer "In7.Cu") (net 757))
  (arc (start 160.802073 111.697927) (mid 160.872784 111.727216) (end 160.943494 111.697926) (width 0.1) (layer "In7.Cu") (net 757))
  (arc (start 181.69 111.846702) (mid 182.096586 112.015116) (end 182.265 112.421702) (width 0.1) (layer "In7.Cu") (net 757))
  (arc (start 182.815 112.421702) (mid 182.983414 112.015116) (end 183.39 111.846702) (width 0.1) (layer "In7.Cu") (net 757))
  (arc (start 180.84 114.073298) (mid 181.034454 113.992752) (end 181.115 113.798298) (width 0.1) (layer "In7.Cu") (net 757))
  (arc (start 181.115 112.421702) (mid 181.283414 112.015116) (end 181.69 111.846702) (width 0.1) (layer "In7.Cu") (net 757))
  (arc (start 161.097923 111.684919) (mid 161.127212 111.75563) (end 161.097922 111.82634) (width 0.1) (layer "In7.Cu") (net 757))
  (arc (start 160.956501 111.684919) (mid 161.027211 111.655629) (end 161.097922 111.684918) (width 0.1) (layer "In7.Cu") (net 757))
  (arc (start 183.39 111.846702) (mid 183.796586 112.015116) (end 183.965 112.421702) (width 0.1) (layer "In7.Cu") (net 757))
  (arc (start 179.99 112.96) (mid 180.396586 113.128414) (end 180.565 113.535) (width 0.1) (layer "In7.Cu") (net 757))
  (arc (start 182.54 114.073298) (mid 182.734454 113.992752) (end 182.815 113.798298) (width 0.1) (layer "In7.Cu") (net 757))
  (arc (start 180.565 113.798298) (mid 180.645546 113.992752) (end 180.84 114.073298) (width 0.1) (layer "In7.Cu") (net 757))
  (arc (start 183.965 112.685) (mid 184.045546 112.879454) (end 184.24 112.96) (width 0.1) (layer "In7.Cu") (net 757))
  (arc (start 161.084915 111.839347) (mid 161.055625 111.910057) (end 161.084914 111.980768) (width 0.1) (layer "In7.Cu") (net 757))
  (segment (start 247.825 112.445) (end 247.825 112.065) (width 0.1) (layer "B.Cu") (net 757))
  (segment (start 160.2145 110.307634) (end 160.000038 110.522096) (width 0.1) (layer "B.Cu") (net 757))
  (segment (start 247.371999 112.547999) (end 247.722001 112.547999) (width 0.1) (layer "B.Cu") (net 757))
  (segment (start 160.3645 109.8645) (end 160.3645 109.9145) (width 0.1) (layer "B.Cu") (net 757))
  (segment (start 160.000038 110.895892) (end 160.307931 111.203785) (width 0.1) (layer "B.Cu") (net 757))
  (segment (start 160.414501 109.455499) (end 160.2145 109.6555) (width 0.1) (layer "B.Cu") (net 757))
  (segment (start 160.2145 110.1145) (end 160.2145 110.307634) (width 0.1) (layer "B.Cu") (net 757))
  (segment (start 247.19 112.366) (end 247.371999 112.547999) (width 0.1) (layer "B.Cu") (net 757))
  (segment (start 247.722001 112.547999) (end 247.825 112.445) (width 0.1) (layer "B.Cu") (net 757))
  (segment (start 160.2145 109.6555) (end 160.2145 109.7145) (width 0.1) (layer "B.Cu") (net 757))
  (segment (start 160.414501 109.145499) (end 160.414501 109.455499) (width 0.1) (layer "B.Cu") (net 757))
  (segment (start 160.000038 110.522096) (end 160.000038 110.895892) (width 0.1) (layer "B.Cu") (net 757))
  (segment (start 160.2145 110.0645) (end 160.2145 110.1145) (width 0.1) (layer "B.Cu") (net 757))
  (segment (start 160.307931 111.203785) (end 160.590774 111.203785) (width 0.1) (layer "B.Cu") (net 757))
  (arc (start 160.2145 109.7145) (mid 160.236467 109.767533) (end 160.2895 109.7895) (width 0.1) (layer "B.Cu") (net 757))
  (arc (start 160.3645 109.9145) (mid 160.342533 109.967533) (end 160.2895 109.9895) (width 0.1) (layer "B.Cu") (net 757))
  (arc (start 160.2895 109.7895) (mid 160.342533 109.811467) (end 160.3645 109.8645) (width 0.1) (layer "B.Cu") (net 757))
  (arc (start 160.2895 109.9895) (mid 160.236467 110.011467) (end 160.2145 110.0645) (width 0.1) (layer "B.Cu") (net 757))
  (segment (start 177.136328 102.560008) (end 176.636328 103.060008) (width 0.1) (layer "F.Cu") (net 784))
  (via (at 176.636328 103.060008) (size 0.5) (drill 0.2) (layers "F.Cu" "B.Cu") (net 784))
  (segment (start 186.85 105.2) (end 188.9 107.25) (width 0.1) (layer "B.Cu") (net 784))
  (segment (start 188.9 107.25) (end 210.5 107.25) (width 0.1) (layer "B.Cu") (net 784))
  (segment (start 177.360008 103.060008) (end 179.5 105.2) (width 0.1) (layer "B.Cu") (net 784))
  (segment (start 179.5 105.2) (end 186.85 105.2) (width 0.1) (layer "B.Cu") (net 784))
  (segment (start 210.5 107.25) (end 234 83.75) (width 0.1) (layer "B.Cu") (net 784))
  (segment (start 234 83.75) (end 237.95 83.75) (width 0.1) (layer "B.Cu") (net 784))
  (segment (start 176.636328 103.060008) (end 177.360008 103.060008) (width 0.1) (layer "B.Cu") (net 784))
  (segment (start 174.136328 99.560008) (end 173.636328 100.060008) (width 0.1) (layer "F.Cu") (net 786))
  (via (at 173.636328 100.060008) (size 0.5) (drill 0.2) (layers "F.Cu" "B.Cu") (net 786))
  (segment (start 233.6 82.5) (end 235.7 82.5) (width 0.1) (layer "B.Cu") (net 786))
  (segment (start 175.840008 100.640008) (end 176.056328 100.856328) (width 0.1) (layer "B.Cu") (net 786))
  (segment (start 176.540008 101.640008) (end 176.850008 101.640008) (width 0.1) (layer "B.Cu") (net 786))
  (segment (start 189.65 106.9) (end 209.2 106.9) (width 0.1) (layer "B.Cu") (net 786))
  (segment (start 176.056328 100.856328) (end 176.056328 101.156328) (width 0.1) (layer "B.Cu") (net 786))
  (segment (start 174.216328 100.640008) (end 175.840008 100.640008) (width 0.1) (layer "B.Cu") (net 786))
  (segment (start 180.4 104.6) (end 187.35 104.6) (width 0.1) (layer "B.Cu") (net 786))
  (segment (start 177.94 102.73) (end 178.53 102.73) (width 0.1) (layer "B.Cu") (net 786))
  (segment (start 235.7 82.5) (end 237.15 81.05) (width 0.1) (layer "B.Cu") (net 786))
  (segment (start 237.15 81.05) (end 237.95 81.05) (width 0.1) (layer "B.Cu") (net 786))
  (segment (start 209.2 106.9) (end 233.6 82.5) (width 0.1) (layer "B.Cu") (net 786))
  (segment (start 176.056328 101.156328) (end 176.540008 101.640008) (width 0.1) (layer "B.Cu") (net 786))
  (segment (start 176.850008 101.640008) (end 177.94 102.73) (width 0.1) (layer "B.Cu") (net 786))
  (segment (start 178.53 102.73) (end 180.4 104.6) (width 0.1) (layer "B.Cu") (net 786))
  (segment (start 187.35 104.6) (end 189.65 106.9) (width 0.1) (layer "B.Cu") (net 786))
  (segment (start 173.636328 100.060008) (end 174.216328 100.640008) (width 0.1) (layer "B.Cu") (net 786))
  (segment (start 176.136328 98.560008) (end 175.636328 99.060008) (width 0.1) (layer "F.Cu") (net 788))
  (via (at 175.636328 99.060008) (size 0.5) (drill 0.2) (layers "F.Cu" "B.Cu") (net 788))
  (segment (start 233.38 81.07) (end 235.23 81.07) (width 0.1) (layer "B.Cu") (net 788))
  (segment (start 207.95 106.5) (end 233.38 81.07) (width 0.1) (layer "B.Cu") (net 788))
  (segment (start 178.720153 100.533825) (end 179.056328 100.87) (width 0.1) (layer "B.Cu") (net 788))
  (segment (start 179.056328 100.87) (end 179.056328 102.073978) (width 0.1) (layer "B.Cu") (net 788))
  (segment (start 179.056328 102.073978) (end 180.966175 103.983825) (width 0.1) (layer "B.Cu") (net 788))
  (segment (start 190.35 106.5) (end 207.95 106.5) (width 0.1) (layer "B.Cu") (net 788))
  (segment (start 175.636328 99.060008) (end 176.216328 99.640008) (width 0.1) (layer "B.Cu") (net 788))
  (segment (start 176.810298 99.640008) (end 177.216328 100.046038) (width 0.1) (layer "B.Cu") (net 788))
  (segment (start 180.966175 103.983825) (end 187.833825 103.983825) (width 0.1) (layer "B.Cu") (net 788))
  (segment (start 176.216328 99.640008) (end 176.810298 99.640008) (width 0.1) (layer "B.Cu") (net 788))
  (segment (start 177.516175 100.533825) (end 178.720153 100.533825) (width 0.1) (layer "B.Cu") (net 788))
  (segment (start 177.216328 100.046038) (end 177.216328 100.233978) (width 0.1) (layer "B.Cu") (net 788))
  (segment (start 187.833825 103.983825) (end 190.35 106.5) (width 0.1) (layer "B.Cu") (net 788))
  (segment (start 235.23 81.07) (end 237.95 78.35) (width 0.1) (layer "B.Cu") (net 788))
  (segment (start 177.216328 100.233978) (end 177.516175 100.533825) (width 0.1) (layer "B.Cu") (net 788))
  (segment (start 194.9 73.9) (end 197.125 71.675) (width 0.127) (layer "F.Cu") (net 789))
  (segment (start 174.59 76.766833) (end 173.898667 76.0755) (width 0.127) (layer "F.Cu") (net 789))
  (segment (start 197.125 64.5525) (end 198.4 63.2775) (width 0.127) (layer "F.Cu") (net 789))
  (segment (start 173.898667 76.0755) (end 173.898667 74.551333) (width 0.127) (layer "F.Cu") (net 789))
  (segment (start 175.136328 77.560008) (end 174.59 77.01368) (width 0.127) (layer "F.Cu") (net 789))
  (segment (start 197.125 71.675) (end 197.125 64.5525) (width 0.127) (layer "F.Cu") (net 789))
  (segment (start 199.036328 55.060008) (end 199.036328 57.010008) (width 0.2) (layer "F.Cu") (net 789))
  (segment (start 174.59 77.01368) (end 174.59 76.766833) (width 0.127) (layer "F.Cu") (net 789))
  (segment (start 173.898667 74.551333) (end 174.55 73.9) (width 0.127) (layer "F.Cu") (net 789))
  (segment (start 174.55 73.9) (end 194.9 73.9) (width 0.127) (layer "F.Cu") (net 789))
  (via (at 173.898667 76.0755) (size 0.5) (drill 0.2) (layers "F.Cu" "B.Cu") (net 789))
  (via (at 199.036328 57.010008) (size 0.5) (drill 0.2) (layers "F.Cu" "B.Cu") (net 789))
  (via (at 198.4 63.2775) (size 0.5) (drill 0.2) (layers "F.Cu" "B.Cu") (net 789))
  (segment (start 173.774167 76.2) (end 173.898667 76.0755) (width 0.127) (layer "B.Cu") (net 789))
  (segment (start 172.385 76.2) (end 173.774167 76.2) (width 0.127) (layer "B.Cu") (net 789))
  (segment (start 199.75 57.72368) (end 199.75 61.9275) (width 0.1) (layer "B.Cu") (net 789))
  (segment (start 199.75 61.9275) (end 198.4 63.2775) (width 0.1) (layer "B.Cu") (net 789))
  (segment (start 199.05 56.996336) (end 199.036328 57.010008) (width 0.2) (layer "B.Cu") (net 789))
  (segment (start 199.036328 57.010008) (end 199.75 57.72368) (width 0.1) (layer "B.Cu") (net 789))
  (segment (start 199.05 55.235) (end 199.05 56.996336) (width 0.2) (layer "B.Cu") (net 789))
  (segment (start 135.3795 95.175) (end 136.024143 95.175) (width 0.127) (layer "F.Cu") (net 790))
  (segment (start 134.8 95.7545) (end 135.3795 95.175) (width 0.127) (layer "F.Cu") (net 790))
  (via (at 134.8 95.7545) (size 0.5) (drill 0.2) (layers "F.Cu" "B.Cu") (net 790))
  (segment (start 131.36 104.2) (end 130.125 104.2) (width 0.127) (layer "B.Cu") (net 790))
  (segment (start 137.08 97) (end 137.08 97.92) (width 0.127) (layer "B.Cu") (net 790))
  (segment (start 131.425 104.135) (end 131.36 104.2) (width 0.127) (layer "B.Cu") (net 790))
  (segment (start 129.8 104.2) (end 130.125 104.2) (width 0.127) (layer "B.Cu") (net 790))
  (segment (start 135.8345 95.7545) (end 137.08 97) (width 0.127) (layer "B.Cu") (net 790))
  (segment (start 137.08 97.92) (end 136.47 98.53) (width 0.127) (layer "B.Cu") (net 790))
  (segment (start 133.739343 104.190657) (end 131.480657 104.190657) (width 0.127) (layer "B.Cu") (net 790))
  (segment (start 129.26 102.8) (end 129.26 103.66) (width 0.127) (layer "B.Cu") (net 790))
  (segment (start 133.857186 104.3085) (end 133.739343 104.190657) (width 0.127) (layer "B.Cu") (net 790))
  (segment (start 131.480657 104.190657) (end 131.425 104.135) (width 0.127) (layer "B.Cu") (net 790))
  (segment (start 136.47 98.53) (end 136.47 103.54) (width 0.127) (layer "B.Cu") (net 790))
  (segment (start 134.8 95.7545) (end 135.8345 95.7545) (width 0.127) (layer "B.Cu") (net 790))
  (segment (start 136.47 103.54) (end 135.7015 104.3085) (width 0.127) (layer "B.Cu") (net 790))
  (segment (start 129.26 103.66) (end 129.8 104.2) (width 0.127) (layer "B.Cu") (net 790))
  (segment (start 135.7015 104.3085) (end 133.857186 104.3085) (width 0.127) (layer "B.Cu") (net 790))
  (segment (start 122.144467 101.182529) (end 121.491946 100.530008) (width 0.127) (layer "F.Cu") (net 793))
  (segment (start 122.286828 101.182529) (end 122.144467 101.182529) (width 0.127) (layer "F.Cu") (net 793))
  (segment (start 121.491946 100.530008) (end 121.006328 100.530008) (width 0.127) (layer "F.Cu") (net 793))
  (via (at 122.286828 101.182529) (size 0.5) (drill 0.2) (layers "F.Cu" "B.Cu") (net 793))
  (segment (start 122.490328 102.382276) (end 122.490328 101.386029) (width 0.127) (layer "B.Cu") (net 793))
  (segment (start 135.985 102.12) (end 135.985 100.965) (width 0.127) (layer "B.Cu") (net 793))
  (segment (start 121.492828 103.379776) (end 122.490328 102.382276) (width 0.127) (layer "B.Cu") (net 793))
  (segment (start 135.71 100.69) (end 134.95 100.69) (width 0.127) (layer "B.Cu") (net 793))
  (segment (start 122.490328 101.386029) (end 122.286828 101.182529) (width 0.127) (layer "B.Cu") (net 793))
  (segment (start 133.37 100.69) (end 132.46 101.6) (width 0.127) (layer "B.Cu") (net 793))
  (segment (start 126.61 101.6) (end 123.39 104.82) (width 0.127) (layer "B.Cu") (net 793))
  (segment (start 121.92 104.82) (end 121.492828 104.392828) (width 0.127) (layer "B.Cu") (net 793))
  (segment (start 135.985 100.965) (end 135.71 100.69) (width 0.127) (layer "B.Cu") (net 793))
  (segment (start 121.492828 104.392828) (end 121.492828 103.379776) (width 0.127) (layer "B.Cu") (net 793))
  (segment (start 123.39 104.82) (end 121.92 104.82) (width 0.127) (layer "B.Cu") (net 793))
  (segment (start 134.98 102.105) (end 134.95 102.075) (width 0.127) (layer "B.Cu") (net 793))
  (segment (start 134.95 100.69) (end 133.37 100.69) (width 0.127) (layer "B.Cu") (net 793))
  (segment (start 134.95 102.075) (end 134.95 100.69) (width 0.127) (layer "B.Cu") (net 793))
  (segment (start 132.46 101.6) (end 126.61 101.6) (width 0.127) (layer "B.Cu") (net 793))
  (segment (start 121.859611 99.993154) (end 121.043183 99.993154) (width 0.127) (layer "F.Cu") (net 794))
  (segment (start 121.043183 99.993154) (end 121.006328 100.030009) (width 0.127) (layer "F.Cu") (net 794))
  (via (at 121.859611 99.993154) (size 0.5) (drill 0.2) (layers "F.Cu" "B.Cu") (net 794))
  (segment (start 121.075 98) (end 121.075 99.208543) (width 0.127) (layer "B.Cu") (net 794))
  (segment (start 122.465 98) (end 122.515 97.95) (width 0.127) (layer "B.Cu") (net 794))
  (segment (start 122.515 97.95) (end 122.515 96.945) (width 0.127) (layer "B.Cu") (net 794))
  (segment (start 121.075 99.208543) (end 121.859611 99.993154) (width 0.127) (layer "B.Cu") (net 794))
  (segment (start 122.515 96.945) (end 122.525 96.935) (width 0.127) (layer "B.Cu") (net 794))
  (segment (start 121.075 98) (end 122.465 98) (width 0.127) (layer "B.Cu") (net 794))
  (segment (start 167.1005 90.6495) (end 167.1005 98.8) (width 0.1) (layer "F.Cu") (net 796))
  (segment (start 171.05 87.05) (end 169.9 88.2) (width 0.1) (layer "F.Cu") (net 796))
  (segment (start 169.9 88.2) (end 169.9 89.3) (width 0.1) (layer "F.Cu") (net 796))
  (segment (start 169.025 90.175) (end 167.575 90.175) (width 0.1) (layer "F.Cu") (net 796))
  (segment (start 169.9 89.3) (end 169.025 90.175) (width 0.1) (layer "F.Cu") (net 796))
  (segment (start 172.646336 87.05) (end 171.05 87.05) (width 0.1) (layer "F.Cu") (net 796))
  (segment (start 167.575 90.175) (end 167.1005 90.6495) (width 0.1) (layer "F.Cu") (net 796))
  (segment (start 173.136328 86.560008) (end 172.646336 87.05) (width 0.1) (layer "F.Cu") (net 796))
  (via (at 167.1005 98.8) (size 0.5) (drill 0.2) (layers "F.Cu" "B.Cu") (net 796))
  (segment (start 166.685 101.765) (end 166.685 101.8) (width 0.1) (layer "B.Cu") (net 796))
  (segment (start 167.1005 98.8) (end 167.1005 101.3495) (width 0.1) (layer "B.Cu") (net 796))
  (segment (start 167.1005 101.3495) (end 166.685 101.765) (width 0.1) (layer "B.Cu") (net 796))
  (segment (start 127.525 107.94) (end 127.425 107.84) (width 0.127) (layer "B.Cu") (net 798))
  (segment (start 129.075 107.9) (end 127.565 107.9) (width 0.127) (layer "B.Cu") (net 798))
  (segment (start 127.425 107.84) (end 127.425 106.1) (width 0.127) (layer "B.Cu") (net 798))
  (segment (start 127.565 107.9) (end 127.525 107.94) (width 0.127) (layer "B.Cu") (net 798))
  (segment (start 171.136328 94.560008) (end 170.460008 94.560008) (width 0.127) (layer "F.Cu") (net 799))
  (segment (start 170.460008 94.560008) (end 170.45 94.55) (width 0.127) (layer "F.Cu") (net 799))
  (via (at 118.5 95) (size 0.5) (drill 0.2) (layers "F.Cu" "B.Cu") (net 799))
  (via (at 170.45 94.55) (size 0.5) (drill 0.2) (layers "F.Cu" "B.Cu") (net 799))
  (segment (start 119.965 94.565) (end 120.2635 94.2665) (width 0.127) (layer "In9.Cu") (net 799))
  (segment (start 122.354562 94.2665) (end 123.11157 95.023508) (width 0.127) (layer "In9.Cu") (net 799))
  (segment (start 119.965 94.565) (end 119.53 95) (width 0.127) (layer "In9.Cu") (net 799))
  (segment (start 119.965 94.565) (end 119.715 94.815) (width 0.127) (layer "In9.Cu") (net 799))
  (segment (start 120.2635 94.2665) (end 122.354562 94.2665) (width 0.127) (layer "In9.Cu") (net 799))
  (segment (start 143.8 90.8) (end 146.7 90.8) (width 0.127) (layer "In9.Cu") (net 799))
  (segment (start 155.8 90.3) (end 156.15 89.95) (width 0.127) (layer "In9.Cu") (net 799))
  (segment (start 147 91.1) (end 148.45 91.1) (width 0.127) (layer "In9.Cu") (net 799))
  (segment (start 156.15 89.95) (end 163.9 89.95) (width 0.127) (layer "In9.Cu") (net 799))
  (segment (start 119.715 94.815) (end 119.67 94.86) (width 0.127) (layer "In9.Cu") (net 799))
  (segment (start 148.45 91.1) (end 148.75 90.8) (width 0.127) (layer "In9.Cu") (net 799))
  (segment (start 150.35 90.8) (end 150.85 90.3) (width 0.127) (layer "In9.Cu") (net 799))
  (segment (start 150.85 90.3) (end 155.8 90.3) (width 0.127) (layer "In9.Cu") (net 799))
  (segment (start 148.75 90.8) (end 150.35 90.8) (width 0.127) (layer "In9.Cu") (net 799))
  (segment (start 163.9 89.95) (end 168.5 94.55) (width 0.127) (layer "In9.Cu") (net 799))
  (segment (start 119.53 95) (end 118.5 95) (width 0.127) (layer "In9.Cu") (net 799))
  (segment (start 139.576492 95.023508) (end 143.8 90.8) (width 0.127) (layer "In9.Cu") (net 799))
  (segment (start 168.5 94.55) (end 170.45 94.55) (width 0.127) (layer "In9.Cu") (net 799))
  (segment (start 146.7 90.8) (end 147 91.1) (width 0.127) (layer "In9.Cu") (net 799))
  (segment (start 123.11157 95.023508) (end 139.576492 95.023508) (width 0.127) (layer "In9.Cu") (net 799))
  (segment (start 118.5 95) (end 118.875 95) (width 0.127) (layer "B.Cu") (net 799))
  (segment (start 118.465 94.965) (end 118.5 95) (width 0.127) (layer "B.Cu") (net 799))
  (segment (start 117.725 94.965) (end 118.465 94.965) (width 0.127) (layer "B.Cu") (net 799))
  (segment (start 118.875 95) (end 119.175 95.3) (width 0.127) (layer "B.Cu") (net 799))
  (segment (start 170.460008 95.560008) (end 170.45 95.55) (width 0.127) (layer "F.Cu") (net 800))
  (segment (start 171.136328 95.560008) (end 170.460008 95.560008) (width 0.127) (layer "F.Cu") (net 800))
  (via (at 170.45 95.55) (size 0.5) (drill 0.2) (layers "F.Cu" "B.Cu") (net 800))
  (via (at 139.75 98.97) (size 0.5) (drill 0.2) (layers "F.Cu" "B.Cu") (net 800))
  (segment (start 163.541542 90.8) (end 166.08805 93.346508) (width 0.127) (layer "In9.Cu") (net 800))
  (segment (start 146.792049 91.773508) (end 147.015557 91.55) (width 0.127) (layer "In9.Cu") (net 800))
  (segment (start 166.08805 93.346508) (end 166.407606 93.346508) (width 0.127) (layer "In9.Cu") (net 800))
  (segment (start 161.276492 91.073508) (end 161.55 90.8) (width 0.127) (layer "In9.Cu") (net 800))
  (segment (start 148.623508 91.773508) (end 150.626492 91.773508) (width 0.127) (layer "In9.Cu") (net 800))
  (segment (start 166.407606 93.346508) (end 168.551098 95.49) (width 0.127) (layer "In9.Cu") (net 800))
  (segment (start 144.026492 91.773508) (end 146.792049 91.773508) (width 0.127) (layer "In9.Cu") (net 800))
  (segment (start 158.23805 90.873508) (end 158.46505 90.646508) (width 0.127) (layer "In9.Cu") (net 800))
  (segment (start 150.626492 91.773508) (end 151.526492 90.873508) (width 0.127) (layer "In9.Cu") (net 800))
  (segment (start 159.896508 90.646508) (end 160.323508 91.073508) (width 0.127) (layer "In9.Cu") (net 800))
  (segment (start 170.39 95.49) (end 170.45 95.55) (width 0.127) (layer "In9.Cu") (net 800))
  (segment (start 148.4 91.55) (end 148.623508 91.773508) (width 0.127) (layer "In9.Cu") (net 800))
  (segment (start 160.323508 91.073508) (end 161.276492 91.073508) (width 0.127) (layer "In9.Cu") (net 800))
  (segment (start 151.526492 90.873508) (end 158.23805 90.873508) (width 0.127) (layer "In9.Cu") (net 800))
  (segment (start 139.75 96.05) (end 144.026492 91.773508) (width 0.127) (layer "In9.Cu") (net 800))
  (segment (start 147.015557 91.55) (end 148.4 91.55) (width 0.127) (layer "In9.Cu") (net 800))
  (segment (start 161.55 90.8) (end 163.541542 90.8) (width 0.127) (layer "In9.Cu") (net 800))
  (segment (start 139.75 98.97) (end 139.75 96.05) (width 0.127) (layer "In9.Cu") (net 800))
  (segment (start 168.551098 95.49) (end 170.39 95.49) (width 0.127) (layer "In9.Cu") (net 800))
  (segment (start 158.46505 90.646508) (end 159.896508 90.646508) (width 0.127) (layer "In9.Cu") (net 800))
  (segment (start 139.515 99.205) (end 139.75 98.97) (width 0.127) (layer "B.Cu") (net 800))
  (segment (start 137.65 98.79) (end 138.545 98.79) (width 0.127) (layer "B.Cu") (net 800))
  (segment (start 138.545 98.79) (end 138.96 99.205) (width 0.127) (layer "B.Cu") (net 800))
  (segment (start 138.96 99.205) (end 139.515 99.205) (width 0.127) (layer "B.Cu") (net 800))
  (segment (start 171.136328 96.560008) (end 170.510508 96.560008) (width 0.127) (layer "F.Cu") (net 804))
  (segment (start 170.510508 96.560008) (end 170.5005 96.55) (width 0.127) (layer "F.Cu") (net 804))
  (via (at 170.5005 96.55) (size 0.5) (drill 0.2) (layers "F.Cu" "B.Cu") (net 804))
  (via (at 135.85 106.9) (size 0.5) (drill 0.2) (layers "F.Cu" "B.Cu") (net 804))
  (segment (start 144.071343 99.303657) (end 137.75 105.625) (width 0.127) (layer "In5.Cu") (net 804))
  (segment (start 164.689617 99.303657) (end 144.071343 99.303657) (width 0.127) (layer "In5.Cu") (net 804))
  (segment (start 170.5005 96.55) (end 169.4505 95.5) (width 0.127) (layer "In5.Cu") (net 804))
  (segment (start 135.85 106.9) (end 137.125 105.625) (width 0.127) (layer "In5.Cu") (net 804))
  (segment (start 137.125 105.625) (end 137.75 105.625) (width 0.127) (layer "In5.Cu") (net 804))
  (segment (start 169.4505 95.5) (end 168.493274 95.5) (width 0.127) (layer "In5.Cu") (net 804))
  (segment (start 168.493274 95.5) (end 164.689617 99.303657) (width 0.127) (layer "In5.Cu") (net 804))
  (segment (start 136.6 108.615) (end 136.6 107.65) (width 0.127) (layer "B.Cu") (net 804))
  (segment (start 136.6 108.615) (end 135.585 108.615) (width 0.127) (layer "B.Cu") (net 804))
  (segment (start 135.585 108.615) (end 135.55 108.65) (width 0.127) (layer "B.Cu") (net 804))
  (segment (start 136.6 107.65) (end 135.85 106.9) (width 0.127) (layer "B.Cu") (net 804))
  (segment (start 151.6 121.7) (end 151.9 122) (width 0.1) (layer "F.Cu") (net 805))
  (segment (start 151.557 121.7) (end 151.6 121.7) (width 0.1) (layer "F.Cu") (net 805))
  (segment (start 151.9 122) (end 151.9 122.35) (width 0.1) (layer "F.Cu") (net 805))
  (via (at 151.9 122.35) (size 0.5) (drill 0.2) (layers "F.Cu" "B.Cu") (net 805))
  (segment (start 143.823222 113.45) (end 147.2 116.826778) (width 0.1) (layer "B.Cu") (net 805))
  (segment (start 111.448222 109.825) (end 113.598222 109.825) (width 0.1) (layer "B.Cu") (net 805))
  (segment (start 119.31 87.055) (end 119.31 86.585) (width 0.1) (layer "B.Cu") (net 805))
  (segment (start 118.801778 85.825) (end 111.798222 85.825) (width 0.1) (layer "B.Cu") (net 805))
  (segment (start 147.2 118.651778) (end 149.373222 120.825) (width 0.1) (layer "B.Cu") (net 805))
  (segment (start 115.825 112.051778) (end 115.825 114.526778) (width 0.1) (layer "B.Cu") (net 805))
  (segment (start 152.175 121.426778) (end 152.175 122.075) (width 0.1) (layer "B.Cu") (net 805))
  (segment (start 119.31 86.585) (end 119.185 86.46) (width 0.1) (layer "B.Cu") (net 805))
  (segment (start 149.373222 120.825) (end 151.573222 120.825) (width 0.1) (layer "B.Cu") (net 805))
  (segment (start 152.175 122.075) (end 151.9 122.35) (width 0.1) (layer "B.Cu") (net 805))
  (segment (start 119.185 86.46) (end 119.185 86.208222) (width 0.1) (layer "B.Cu") (net 805))
  (segment (start 147.2 116.826778) (end 147.2 118.651778) (width 0.1) (layer "B.Cu") (net 805))
  (segment (start 124.526778 113.45) (end 143.823222 113.45) (width 0.1) (layer "B.Cu") (net 805))
  (segment (start 118.523222 117.225) (end 120.751778 117.225) (width 0.1) (layer "B.Cu") (net 805))
  (segment (start 113.598222 109.825) (end 115.825 112.051778) (width 0.1) (layer "B.Cu") (net 805))
  (segment (start 119.185 86.208222) (end 118.801778 85.825) (width 0.1) (layer "B.Cu") (net 805))
  (segment (start 120.751778 117.225) (end 124.526778 113.45) (width 0.1) (layer "B.Cu") (net 805))
  (segment (start 109.325 88.298222) (end 109.325 107.701778) (width 0.1) (layer "B.Cu") (net 805))
  (segment (start 115.825 114.526778) (end 118.523222 117.225) (width 0.1) (layer "B.Cu") (net 805))
  (segment (start 109.325 107.701778) (end 111.448222 109.825) (width 0.1) (layer "B.Cu") (net 805))
  (segment (start 111.798222 85.825) (end 109.325 88.298222) (width 0.1) (layer "B.Cu") (net 805))
  (segment (start 151.573222 120.825) (end 152.175 121.426778) (width 0.1) (layer "B.Cu") (net 805))
  (segment (start 153.043 121.7) (end 153 121.7) (width 0.1) (layer "F.Cu") (net 806))
  (segment (start 152.7 122) (end 152.7 122.35) (width 0.1) (layer "F.Cu") (net 806))
  (segment (start 153 121.7) (end 152.7 122) (width 0.1) (layer "F.Cu") (net 806))
  (via (at 152.7 122.35) (size 0.5) (drill 0.2) (layers "F.Cu" "B.Cu") (net 806))
  (segment (start 111.456086 87.026062) (end 111.456086 87.026063) (width 0.1) (layer "B.Cu") (net 806))
  (segment (start 152.425 122.075) (end 152.7 122.35) (width 0.1) (layer "B.Cu") (net 806))
  (segment (start 110.460939 87.515842) (end 109.575 88.401778) (width 0.1) (layer "B.Cu") (net 806))
  (segment (start 124.423222 113.2) (end 143.926778 113.2) (width 0.1) (layer "B.Cu") (net 806))
  (segment (start 111.551778 109.575) (end 113.701778 109.575) (width 0.1) (layer "B.Cu") (net 806))
  (segment (start 110.713624 87.521038) (end 110.708427 87.515841) (width 0.1) (layer "B.Cu") (net 806))
  (segment (start 110.955915 87.020866) (end 110.955913 87.020865) (width 0.1) (layer "B.Cu") (net 806))
  (segment (start 110.713624 87.521039) (end 110.713624 87.521038) (width 0.1) (layer "B.Cu") (net 806))
  (segment (start 116.075 111.948222) (end 116.075 114.423222) (width 0.1) (layer "B.Cu") (net 806))
  (segment (start 143.926778 113.2) (end 147.45 116.723222) (width 0.1) (layer "B.Cu") (net 806))
  (segment (start 120.648222 116.975) (end 124.423222 113.2) (width 0.1) (layer "B.Cu") (net 806))
  (segment (start 116.075 114.423222) (end 118.626778 116.975) (width 0.1) (layer "B.Cu") (net 806))
  (segment (start 110.96111 87.521038) (end 110.96111 87.521039) (width 0.1) (layer "B.Cu") (net 806))
  (segment (start 111.2086 87.026063) (end 111.2086 87.026062) (width 0.1) (layer "B.Cu") (net 806))
  (segment (start 113.701778 109.575) (end 116.075 111.948222) (width 0.1) (layer "B.Cu") (net 806))
  (segment (start 151.676778 120.575) (end 152.425 121.323222) (width 0.1) (layer "B.Cu") (net 806))
  (segment (start 118.935 86.311778) (end 118.698222 86.075) (width 0.1) (layer "B.Cu") (net 806))
  (segment (start 147.45 116.723222) (end 147.45 118.548222) (width 0.1) (layer "B.Cu") (net 806))
  (segment (start 111.2086 87.026062) (end 111.203403 87.020865) (width 0.1) (layer "B.Cu") (net 806))
  (segment (start 149.476778 120.575) (end 151.676778 120.575) (width 0.1) (layer "B.Cu") (net 806))
  (segment (start 110.46094 87.515842) (end 110.460939 87.515842) (width 0.1) (layer "B.Cu") (net 806))
  (segment (start 118.626778 116.975) (end 120.648222 116.975) (width 0.1) (layer "B.Cu") (net 806))
  (segment (start 109.575 88.401778) (end 109.575 107.598222) (width 0.1) (layer "B.Cu") (net 806))
  (segment (start 110.955913 87.268353) (end 110.961111 87.273551) (width 0.1) (layer "B.Cu") (net 806))
  (segment (start 118.935 86.465) (end 118.935 86.311778) (width 0.1) (layer "B.Cu") (net 806))
  (segment (start 118.81 86.59) (end 118.935 86.465) (width 0.1) (layer "B.Cu") (net 806))
  (segment (start 111.901778 86.075) (end 111.450889 86.525889) (width 0.1) (layer "B.Cu") (net 806))
  (segment (start 118.81 87.055) (end 118.81 86.59) (width 0.1) (layer "B.Cu") (net 806))
  (segment (start 118.698222 86.075) (end 111.901778 86.075) (width 0.1) (layer "B.Cu") (net 806))
  (segment (start 109.575 107.598222) (end 111.551778 109.575) (width 0.1) (layer "B.Cu") (net 806))
  (segment (start 152.425 121.323222) (end 152.425 122.075) (width 0.1) (layer "B.Cu") (net 806))
  (segment (start 147.45 118.548222) (end 149.476778 120.575) (width 0.1) (layer "B.Cu") (net 806))
  (segment (start 111.450889 86.773377) (end 111.456087 86.778575) (width 0.1) (layer "B.Cu") (net 806))
  (segment (start 110.955916 87.020866) (end 110.955915 87.020866) (width 0.1) (layer "B.Cu") (net 806))
  (arc (start 110.96111 87.521039) (mid 110.837368 87.572294) (end 110.713624 87.521039) (width 0.1) (layer "B.Cu") (net 806))
  (arc (start 110.708427 87.515841) (mid 110.584683 87.464585) (end 110.46094 87.515842) (width 0.1) (layer "B.Cu") (net 806))
  (arc (start 111.450889 86.525889) (mid 111.399633 86.649633) (end 111.450889 86.773377) (width 0.1) (layer "B.Cu") (net 806))
  (arc (start 111.203403 87.020865) (mid 111.079659 86.969609) (end 110.955916 87.020866) (width 0.1) (layer "B.Cu") (net 806))
  (arc (start 110.955913 87.020865) (mid 110.904657 87.144609) (end 110.955913 87.268353) (width 0.1) (layer "B.Cu") (net 806))
  (arc (start 111.456086 87.026063) (mid 111.332344 87.077318) (end 111.2086 87.026063) (width 0.1) (layer "B.Cu") (net 806))
  (arc (start 110.961111 87.273551) (mid 111.012367 87.397295) (end 110.96111 87.521038) (width 0.1) (layer "B.Cu") (net 806))
  (arc (start 111.456087 86.778575) (mid 111.507343 86.902319) (end 111.456086 87.026062) (width 0.1) (layer "B.Cu") (net 806))
  (segment (start 184.31 121.095) (end 184.095 121.095) (width 0.4) (layer "B.Cu") (net 807))
  (segment (start 184.095 121.095) (end 183.175 120.175) (width 0.4) (layer "B.Cu") (net 807))
  (segment (start 179.06 120.425) (end 179.06 120.945) (width 0.4) (layer "B.Cu") (net 807))
  (segment (start 184.31 122.525) (end 184.31 121.095) (width 0.4) (layer "B.Cu") (net 807))
  (segment (start 183.175 120.175) (end 179.31 120.175) (width 0.4) (layer "B.Cu") (net 807))
  (segment (start 179.31 120.175) (end 179.06 120.425) (width 0.4) (layer "B.Cu") (net 807))
  (segment (start 179.06 118.405) (end 179.06 118.925) (width 0.4) (layer "B.Cu") (net 808))
  (segment (start 178.08 118.405) (end 179.06 118.405) (width 0.4) (layer "B.Cu") (net 808))
  (segment (start 183.18 119.22) (end 183.995 118.405) (width 0.4) (layer "B.Cu") (net 808))
  (segment (start 179.06 118.925) (end 179.355 119.22) (width 0.4) (layer "B.Cu") (net 808))
  (segment (start 179.355 119.22) (end 183.18 119.22) (width 0.4) (layer "B.Cu") (net 808))
  (segment (start 183.995 118.405) (end 184.46 118.405) (width 0.4) (layer "B.Cu") (net 808))
  (segment (start 177.51 122.525) (end 177.51 118.975) (width 0.4) (layer "B.Cu") (net 808))
  (segment (start 177.51 118.975) (end 178.08 118.405) (width 0.4) (layer "B.Cu") (net 808))
  (segment (start 178.636328 94.060008) (end 179.136328 93.560008) (width 0.1) (layer "F.Cu") (net 809))
  (via (at 245.92 90.776) (size 0.5) (drill 0.2) (layers "F.Cu" "B.Cu") (net 809))
  (via (at 178.636328 94.060008) (size 0.5) (drill 0.2) (layers "F.Cu" "B.Cu") (net 809))
  (segment (start 195.461326 98.113748) (end 198.087327 98.113748) (width 0.09) (layer "In7.Cu") (net 809))
  (segment (start 191.38055 97.664981) (end 193.179981 97.66498) (width 0.09) (layer "In7.Cu") (net 809))
  (segment (start 203.068134 94.65) (end 199.555134 98.163) (width 0.1) (layer "In7.Cu") (net 809))
  (segment (start 240.456169 92.553881) (end 240.456168 92.553881) (width 0.1) (layer "In7.Cu") (net 809))
  (segment (start 241.110243 94.091839) (end 241.110242 94.091841) (width 0.1) (layer "In7.Cu") (net 809))
  (segment (start 194.379981 97.66498) (end 195.012559 97.664981) (width 0.09) (layer "In7.Cu") (net 809))
  (segment (start 245.92 90.776) (end 246.101999 90.957999) (width 0.1) (layer "In7.Cu") (net 809))
  (segment (start 240.120294 94.091842) (end 239.562134 94.65) (width 0.1) (layer "In7.Cu") (net 809))
  (segment (start 240.403136 94.197906) (end 240.297071 94.091841) (width 0.1) (layer "In7.Cu") (net 809))
  (segment (start 180.315898 94.881) (end 181.299 94.881) (width 0.09) (layer "In7.Cu") (net 809))
  (segment (start 182.399 94.881) (end 182.922578 94.881) (width 0.09) (layer "In7.Cu") (net 809))
  (segment (start 179.001336 93.695) (end 179.132807 93.695) (width 0.09) (layer "In7.Cu") (net 809))
  (segment (start 244.067866 91.67) (end 242.542133 91.669999) (width 0.1) (layer "In7.Cu") (net 809))
  (segment (start 241.835026 91.669999) (end 241.728959 91.563932) (width 0.1) (layer "In7.Cu") (net 809))
  (segment (start 239.562134 94.65) (end 203.068134 94.65) (width 0.1) (layer "In7.Cu") (net 809))
  (segment (start 246.81 91.889643) (end 246.349643 92.35) (width 0.1) (layer "In7.Cu") (net 809))
  (segment (start 241.110242 94.091841) (end 241.004177 94.197907) (width 0.1) (layer "In7.Cu") (net 809))
  (segment (start 246.349643 92.35) (end 245.537866 92.35) (width 0.1) (layer "In7.Cu") (net 809))
  (segment (start 190.326 97.472) (end 191.187569 97.472) (width 0.09) (layer "In7.Cu") (net 809))
  (segment (start 179.95278 93.987551) (end 180.235621 93.704707) (width 0.09) (layer "In7.Cu") (net 809))
  (segment (start 180.483108 93.952194) (end 180.48311 93.952195) (width 0.09) (layer "In7.Cu") (net 809))
  (segment (start 180.200266 94.765368) (end 180.315898 94.881) (width 0.09) (layer "In7.Cu") (net 809))
  (segment (start 190.151 97.797) (end 190.151 97.647) (width 0.09) (layer "In7.Cu") (net 809))
  (segment (start 246.460133 90.957999) (end 246.81 91.307866) (width 0.1) (layer "In7.Cu") (net 809))
  (segment (start 198.158038 98.143038) (end 198.178 98.163) (width 0.09) (layer "In7.Cu") (net 809))
  (segment (start 195.012559 97.664981) (end 195.461326 98.113748) (width 0.09) (layer "In7.Cu") (net 809))
  (segment (start 245.337866 92.15) (end 244.547866 92.15) (width 0.1) (layer "In7.Cu") (net 809))
  (segment (start 241.393086 93.207956) (end 240.739011 92.553881) (width 0.1) (layer "In7.Cu") (net 809))
  (segment (start 182.922578 94.881) (end 183.363578 95.322) (width 0.09) (layer "In7.Cu") (net 809))
  (segment (start 246.101999 90.957999) (end 246.460133 90.957999) (width 0.1) (layer "In7.Cu") (net 809))
  (segment (start 181.674 94.506) (end 181.674 93.806) (width 0.09) (layer "In7.Cu") (net 809))
  (segment (start 246.81 91.307866) (end 246.81 91.889643) (width 0.1) (layer "In7.Cu") (net 809))
  (segment (start 242.100192 93.101891) (end 241.994127 93.207957) (width 0.1) (layer "In7.Cu") (net 809))
  (segment (start 240.456168 92.836723) (end 241.110243 93.490799) (width 0.1) (layer "In7.Cu") (net 809))
  (segment (start 189.051 97.797) (end 189.051 97.647) (width 0.09) (layer "In7.Cu") (net 809))
  (segment (start 241.835025 91.669999) (end 241.835026 91.669999) (width 0.1) (layer "In7.Cu") (net 809))
  (segment (start 188.301 97.647) (end 188.301 97.797) (width 0.09) (layer "In7.Cu") (net 809))
  (segment (start 183.363578 95.322) (end 183.692578 95.322) (width 0.09) (layer "In7.Cu") (net 809))
  (segment (start 178.636328 94.060008) (end 179.001336 93.695) (width 0.09) (layer "In7.Cu") (net 809))
  (segment (start 185.842578 97.472) (end 188.126 97.472) (width 0.09) (layer "In7.Cu") (net 809))
  (segment (start 244.547866 92.15) (end 244.067866 91.67) (width 0.1) (layer "In7.Cu") (net 809))
  (segment (start 241.799674 92.200327) (end 242.100193 92.500849) (width 0.1) (layer "In7.Cu") (net 809))
  (segment (start 180.483108 93.704706) (end 180.483109 93.704707) (width 0.09) (layer "In7.Cu") (net 809))
  (segment (start 241.446116 91.563933) (end 241.446117 91.563932) (width 0.1) (layer "In7.Cu") (net 809))
  (segment (start 182.024 93.806) (end 182.024 94.506) (width 0.09) (layer "In7.Cu") (net 809))
  (segment (start 199.555134 98.163) (end 198.178 98.163) (width 0.1) (layer "In7.Cu") (net 809))
  (segment (start 241.79967 92.200327) (end 241.799674 92.200327) (width 0.1) (layer "In7.Cu") (net 809))
  (segment (start 180.200266 94.765366) (end 180.200266 94.765368) (width 0.09) (layer "In7.Cu") (net 809))
  (segment (start 242.100193 93.101889) (end 242.100192 93.101891) (width 0.1) (layer "In7.Cu") (net 809))
  (segment (start 194.179971 98.070338) (end 194.179971 97.86499) (width 0.09) (layer "In7.Cu") (net 809))
  (segment (start 179.132807 93.695) (end 179.465669 94.027862) (width 0.09) (layer "In7.Cu") (net 809))
  (segment (start 193.379991 97.86499) (end 193.379991 98.070338) (width 0.09) (layer "In7.Cu") (net 809))
  (segment (start 245.537866 92.35) (end 245.337866 92.15) (width 0.1) (layer "In7.Cu") (net 809))
  (segment (start 189.401 97.647) (end 189.401 97.797) (width 0.09) (layer "In7.Cu") (net 809))
  (segment (start 183.692578 95.322) (end 185.842578 97.472) (width 0.09) (layer "In7.Cu") (net 809))
  (segment (start 191.187569 97.472) (end 191.38055 97.664981) (width 0.09) (layer "In7.Cu") (net 809))
  (segment (start 241.446117 91.846774) (end 241.79967 92.200327) (width 0.1) (layer "In7.Cu") (net 809))
  (segment (start 180.48311 93.952195) (end 180.200266 94.235036) (width 0.09) (layer "In7.Cu") (net 809))
  (arc (start 193.779981 98.470328) (mid 194.062817 98.353174) (end 194.179971 98.070338) (width 0.09) (layer "In7.Cu") (net 809))
  (arc (start 181.674 93.806) (mid 181.725256 93.682256) (end 181.849 93.631) (width 0.09) (layer "In7.Cu") (net 809))
  (arc (start 188.676 98.172) (mid 188.941165 98.062165) (end 189.051 97.797) (width 0.09) (layer "In7.Cu") (net 809))
  (arc (start 180.483109 93.704707) (mid 180.534365 93.828451) (end 180.483108 93.952194) (width 0.09) (layer "In7.Cu") (net 809))
  (arc (start 188.126 97.472) (mid 188.249744 97.523256) (end 188.301 97.647) (width 0.09) (layer "In7.Cu") (net 809))
  (arc (start 240.456168 92.553881) (mid 240.39759 92.695302) (end 240.456168 92.836723) (width 0.1) (layer "In7.Cu") (net 809))
  (arc (start 240.297071 94.091841) (mid 240.208682 94.05523) (end 240.120294 94.091842) (width 0.1) (layer "In7.Cu") (net 809))
  (arc (start 241.446117 91.563932) (mid 241.387539 91.705353) (end 241.446117 91.846774) (width 0.1) (layer "In7.Cu") (net 809))
  (arc (start 189.226 97.472) (mid 189.349744 97.523256) (end 189.401 97.647) (width 0.09) (layer "In7.Cu") (net 809))
  (arc (start 189.776 98.172) (mid 190.041165 98.062165) (end 190.151 97.797) (width 0.09) (layer "In7.Cu") (net 809))
  (arc (start 194.179971 97.86499) (mid 194.238553 97.723562) (end 194.379981 97.66498) (width 0.09) (layer "In7.Cu") (net 809))
  (arc (start 193.179981 97.66498) (mid 193.321409 97.723562) (end 193.379991 97.86499) (width 0.09) (layer "In7.Cu") (net 809))
  (arc (start 188.301 97.797) (mid 188.410835 98.062165) (end 188.676 98.172) (width 0.09) (layer "In7.Cu") (net 809))
  (arc (start 189.051 97.647) (mid 189.102256 97.523256) (end 189.226 97.472) (width 0.09) (layer "In7.Cu") (net 809))
  (arc (start 240.739011 92.553881) (mid 240.59759 92.495303) (end 240.456169 92.553881) (width 0.1) (layer "In7.Cu") (net 809))
  (arc (start 182.024 94.506) (mid 182.133835 94.771165) (end 182.399 94.881) (width 0.09) (layer "In7.Cu") (net 809))
  (arc (start 190.151 97.647) (mid 190.202256 97.523256) (end 190.326 97.472) (width 0.09) (layer "In7.Cu") (net 809))
  (arc (start 241.110243 93.490799) (mid 241.234723 93.791318) (end 241.110243 94.091839) (width 0.1) (layer "In7.Cu") (net 809))
  (arc (start 241.994127 93.207957) (mid 241.693606 93.332436) (end 241.393086 93.207956) (width 0.1) (layer "In7.Cu") (net 809))
  (arc (start 242.100193 92.500849) (mid 242.224673 92.801368) (end 242.100193 93.101889) (width 0.1) (layer "In7.Cu") (net 809))
  (arc (start 198.087327 98.113748) (mid 198.125596 98.12136) (end 198.158038 98.143038) (width 0.09) (layer "In7.Cu") (net 809))
  (arc (start 189.401 97.797) (mid 189.510835 98.062165) (end 189.776 98.172) (width 0.09) (layer "In7.Cu") (net 809))
  (arc (start 241.728959 91.563932) (mid 241.587537 91.505354) (end 241.446116 91.563933) (width 0.1) (layer "In7.Cu") (net 809))
  (arc (start 193.379991 98.070338) (mid 193.497145 98.353174) (end 193.779981 98.470328) (width 0.09) (layer "In7.Cu") (net 809))
  (arc (start 181.299 94.881) (mid 181.564165 94.771165) (end 181.674 94.506) (width 0.09) (layer "In7.Cu") (net 809))
  (arc (start 181.849 93.631) (mid 181.972744 93.682256) (end 182.024 93.806) (width 0.09) (layer "In7.Cu") (net 809))
  (arc (start 241.004177 94.197907) (mid 240.703656 94.322386) (end 240.403136 94.197906) (width 0.1) (layer "In7.Cu") (net 809))
  (arc (start 180.235621 93.704707) (mid 180.359364 93.65345) (end 180.483108 93.704706) (width 0.09) (layer "In7.Cu") (net 809))
  (arc (start 180.200266 94.235036) (mid 180.090431 94.500201) (end 180.200266 94.765366) (width 0.09) (layer "In7.Cu") (net 809))
  (arc (start 179.465669 94.027862) (mid 179.717032 94.096244) (end 179.95278 93.987551) (width 0.09) (layer "In7.Cu") (net 809))
  (arc (start 242.542133 91.669999) (mid 242.188579 91.816446) (end 241.835025 91.669999) (width 0.1) (layer "In7.Cu") (net 809))
  (segment (start 245.92 90.776) (end 246.101999 90.957999) (width 0.1) (layer "B.Cu") (net 809))
  (segment (start 246.101999 90.957999) (end 246.452001 90.957999) (width 0.1) (layer "B.Cu") (net 809))
  (segment (start 246.452001 90.957999) (end 246.555 90.855) (width 0.1) (layer "B.Cu") (net 809))
  (segment (start 246.555 90.855) (end 246.555 90.475) (width 0.1) (layer "B.Cu") (net 809))
  (segment (start 177.136328 93.560008) (end 176.636328 94.060008) (width 0.1) (layer "F.Cu") (net 810))
  (via (at 176.636328 94.060008) (size 0.5) (drill 0.2) (layers "F.Cu" "B.Cu") (net 810))
  (via (at 247.19 97.79) (size 0.5) (drill 0.2) (layers "F.Cu" "B.Cu") (net 810))
  (segment (start 184.594094 102.834988) (end 184.594095 102.834988) (width 0.09) (layer "In5.Cu") (net 810))
  (segment (start 185.643703 105.323933) (end 185.686067 105.323933) (width 0.09) (layer "In5.Cu") (net 810))
  (segment (start 184.969843 104.361746) (end 184.898789 104.432797) (width 0.09) (layer "In5.Cu") (net 810))
  (segment (start 247.662134 96.4) (end 246.387866 96.4) (width 0.1) (layer "In5.Cu") (net 810))
  (segment (start 180.767681 99.841987) (end 180.767681 99.841986) (width 0.09) (layer "In5.Cu") (net 810))
  (segment (start 200.387866 105.65) (end 186.012134 105.65) (width 0.1) (layer "In5.Cu") (net 810))
  (segment (start 242.987866 96.75) (end 241.887866 97.85) (width 0.1) (layer "In5.Cu") (net 810))
  (segment (start 244.007792 96.75) (end 242.987866 96.75) (width 0.1) (layer "In5.Cu") (net 810))
  (segment (start 184.944669 103.866087) (end 184.94467 103.866089) (width 0.09) (layer "In5.Cu") (net 810))
  (segment (start 208.187866 97.85) (end 200.387866 105.65) (width 0.1) (layer "In5.Cu") (net 810))
  (segment (start 180.758933 99.850734) (end 180.767681 99.841987) (width 0.09) (layer "In5.Cu") (net 810))
  (segment (start 241.887866 97.85) (end 208.187866 97.85) (width 0.1) (layer "In5.Cu") (net 810))
  (segment (start 184.403133 103.937142) (end 184.474184 103.866088) (width 0.09) (layer "In5.Cu") (net 810))
  (segment (start 177.036328 94.460008) (end 177.94743 94.460008) (width 0.09) (layer "In5.Cu") (net 810))
  (segment (start 184.923962 104.644248) (end 185.587605 105.30789) (width 0.09) (layer "In5.Cu") (net 810))
  (segment (start 184.450179 101.983966) (end 184.450178 101.983964) (width 0.09) (layer "In5.Cu") (net 810))
  (segment (start 184.01 103.730285) (end 184.216855 103.93714) (width 0.09) (layer "In5.Cu") (net 810))
  (segment (start 180.194422 99.463) (end 180.582157 99.850734) (width 0.09) (layer "In5.Cu") (net 810))
  (segment (start 248.1 97.212134) (end 248.1 96.837866) (width 0.1) (layer "In5.Cu") (net 810))
  (segment (start 184.519699 101.914447) (end 184.450179 101.983966) (width 0.09) (layer "In5.Cu") (net 810))
  (segment (start 183.112078 101.426064) (end 183.112079 101.426063) (width 0.09) (layer "In5.Cu") (net 810))
  (segment (start 244.351774 96.406019) (end 244.007792 96.75) (width 0.1) (layer "In5.Cu") (net 810))
  (segment (start 180.944458 100.018764) (end 180.935711 100.027512) (width 0.09) (layer "In5.Cu") (net 810))
  (segment (start 178.233 99.286578) (end 178.409422 99.463) (width 0.09) (layer "In5.Cu") (net 810))
  (segment (start 184.898789 104.619073) (end 184.923962 104.644248) (width 0.09) (layer "In5.Cu") (net 810))
  (segment (start 180.935711 100.027512) (end 180.93571 100.027512) (width 0.09) (layer "In5.Cu") (net 810))
  (segment (start 247.19 97.79) (end 247.371999 97.608001) (width 0.1) (layer "In5.Cu") (net 810))
  (segment (start 177.94743 94.460008) (end 178.233 94.745578) (width 0.09) (layer "In5.Cu") (net 810))
  (segment (start 182.228197 101.249288) (end 182.581749 100.895733) (width 0.09) (layer "In5.Cu") (net 810))
  (segment (start 246.037866 96.75) (end 245.292208 96.75) (width 0.1) (layer "In5.Cu") (net 810))
  (segment (start 180.944458 99.841987) (end 180.944458 99.841988) (width 0.09) (layer "In5.Cu") (net 810))
  (segment (start 180.935711 100.204289) (end 181.980709 101.249288) (width 0.09) (layer "In5.Cu") (net 810))
  (segment (start 178.233 94.745578) (end 178.233 99.286578) (width 0.09) (layer "In5.Cu") (net 810))
  (segment (start 244.948227 96.406019) (end 244.351774 96.406019) (width 0.1) (layer "In5.Cu") (net 810))
  (segment (start 186.012134 105.65) (end 185.686067 105.323933) (width 0.1) (layer "In5.Cu") (net 810))
  (segment (start 184.94467 103.866089) (end 184.969843 103.891262) (width 0.09) (layer "In5.Cu") (net 810))
  (segment (start 178.409422 99.463) (end 180.194422 99.463) (width 0.09) (layer "In5.Cu") (net 810))
  (segment (start 246.387866 96.4) (end 246.037866 96.75) (width 0.1) (layer "In5.Cu") (net 810))
  (segment (start 183.743073 102.691073) (end 183.706528 102.727619) (width 0.09) (layer "In5.Cu") (net 810))
  (segment (start 181.980709 101.249288) (end 181.980707 101.249286) (width 0.09) (layer "In5.Cu") (net 810))
  (segment (start 247.704133 97.608001) (end 248.1 97.212134) (width 0.1) (layer "In5.Cu") (net 810))
  (segment (start 183.743072 102.691072) (end 183.743073 102.691073) (width 0.09) (layer "In5.Cu") (net 810))
  (segment (start 247.371999 97.608001) (end 247.704133 97.608001) (width 0.1) (layer "In5.Cu") (net 810))
  (segment (start 182.758526 102.027105) (end 182.758525 102.027103) (width 0.09) (layer "In5.Cu") (net 810))
  (segment (start 183.112079 101.426063) (end 182.758526 101.779617) (width 0.09) (layer "In5.Cu") (net 810))
  (segment (start 183.176199 102.19729) (end 183.98937 101.384116) (width 0.09) (layer "In5.Cu") (net 810))
  (segment (start 176.636328 94.060008) (end 177.036328 94.460008) (width 0.09) (layer "In5.Cu") (net 810))
  (segment (start 184.450178 102.196096) (end 184.594094 102.340013) (width 0.09) (layer "In5.Cu") (net 810))
  (segment (start 182.758525 102.027103) (end 182.928709 102.197288) (width 0.09) (layer "In5.Cu") (net 810))
  (segment (start 184.099119 102.834988) (end 183.955204 102.691072) (width 0.09) (layer "In5.Cu") (net 810))
  (segment (start 248.1 96.837866) (end 247.662134 96.4) (width 0.1) (layer "In5.Cu") (net 810))
  (segment (start 184.01 103.278578) (end 184.01 103.730285) (width 0.09) (layer "In5.Cu") (net 810))
  (segment (start 245.292208 96.75) (end 244.948227 96.406019) (width 0.1) (layer "In5.Cu") (net 810))
  (segment (start 184.969842 104.361747) (end 184.969843 104.361746) (width 0.09) (layer "In5.Cu") (net 810))
  (segment (start 183.706527 102.975106) (end 184.01 103.278578) (width 0.09) (layer "In5.Cu") (net 810))
  (segment (start 184.594094 102.340013) (end 184.594094 102.340012) (width 0.09) (layer "In5.Cu") (net 810))
  (arc (start 183.98937 101.384116) (mid 184.254535 101.274281) (end 184.5197 101.384116) (width 0.09) (layer "In5.Cu") (net 810))
  (arc (start 183.112079 100.895733) (mid 183.221915 101.1609) (end 183.112078 101.426064) (width 0.09) (layer "In5.Cu") (net 810))
  (arc (start 182.758526 101.779617) (mid 182.70727 101.903361) (end 182.758526 102.027105) (width 0.09) (layer "In5.Cu") (net 810))
  (arc (start 183.955204 102.691072) (mid 183.849138 102.647138) (end 183.743072 102.691072) (width 0.09) (layer "In5.Cu") (net 810))
  (arc (start 184.594095 102.834988) (mid 184.346607 102.937501) (end 184.099119 102.834988) (width 0.09) (layer "In5.Cu") (net 810))
  (arc (start 181.980707 101.249286) (mid 182.104453 101.300544) (end 182.228197 101.249288) (width 0.09) (layer "In5.Cu") (net 810))
  (arc (start 183.706528 102.727619) (mid 183.655271 102.851362) (end 183.706527 102.975106) (width 0.09) (layer "In5.Cu") (net 810))
  (arc (start 184.594094 102.340012) (mid 184.696607 102.5875) (end 184.594094 102.834988) (width 0.09) (layer "In5.Cu") (net 810))
  (arc (start 182.928709 102.197288) (mid 183.052455 102.248546) (end 183.176199 102.19729) (width 0.09) (layer "In5.Cu") (net 810))
  (arc (start 184.216855 103.93714) (mid 184.309994 103.97572) (end 184.403133 103.937142) (width 0.09) (layer "In5.Cu") (net 810))
  (arc (start 180.944458 99.841988) (mid 180.98107 99.930376) (end 180.944458 100.018764) (width 0.09) (layer "In5.Cu") (net 810))
  (arc (start 185.587605 105.30789) (mid 185.614673 105.319629) (end 185.643703 105.323933) (width 0.09) (layer "In5.Cu") (net 810))
  (arc (start 180.93571 100.027512) (mid 180.899099 100.115901) (end 180.935711 100.204289) (width 0.09) (layer "In5.Cu") (net 810))
  (arc (start 184.474184 103.866088) (mid 184.709427 103.768648) (end 184.944669 103.866087) (width 0.09) (layer "In5.Cu") (net 810))
  (arc (start 180.767681 99.841986) (mid 180.85607 99.805375) (end 180.944458 99.841987) (width 0.09) (layer "In5.Cu") (net 810))
  (arc (start 184.969843 103.891262) (mid 185.067282 104.126504) (end 184.969842 104.361747) (width 0.09) (layer "In5.Cu") (net 810))
  (arc (start 180.582157 99.850734) (mid 180.670545 99.887346) (end 180.758933 99.850734) (width 0.09) (layer "In5.Cu") (net 810))
  (arc (start 182.581749 100.895733) (mid 182.846914 100.785898) (end 183.112079 100.895733) (width 0.09) (layer "In5.Cu") (net 810))
  (arc (start 184.450178 101.983964) (mid 184.406244 102.09003) (end 184.450178 102.196096) (width 0.09) (layer "In5.Cu") (net 810))
  (arc (start 184.898789 104.432797) (mid 184.860211 104.525936) (end 184.898789 104.619073) (width 0.09) (layer "In5.Cu") (net 810))
  (arc (start 184.5197 101.384116) (mid 184.629536 101.649283) (end 184.519699 101.914447) (width 0.09) (layer "In5.Cu") (net 810))
  (segment (start 247.825 97.68) (end 247.825 98.095) (width 0.1) (layer "B.Cu") (net 810))
  (segment (start 247.371999 97.608001) (end 247.753001 97.608001) (width 0.1) (layer "B.Cu") (net 810))
  (segment (start 247.19 97.79) (end 247.371999 97.608001) (width 0.1) (layer "B.Cu") (net 810))
  (segment (start 247.753001 97.608001) (end 247.825 97.68) (width 0.1) (layer "B.Cu") (net 810))
  (segment (start 179.636328 93.060008) (end 180.136328 92.560008) (width 0.1) (layer "F.Cu") (net 811))
  (via (at 179.636328 93.060008) (size 0.5) (drill 0.2) (layers "F.Cu" "B.Cu") (net 811))
  (via (at 245.92 91.44) (size 0.5) (drill 0.2) (layers "F.Cu" "B.Cu") (net 811))
  (segment (start 190.326 97.272) (end 191.270385 97.272) (width 0.09) (layer "In7.Cu") (net 811))
  (segment (start 241.88806 92.889759) (end 241.781995 92.995825) (width 0.1) (layer "In7.Cu") (net 811))
  (segment (start 239.908162 93.87971) (end 239.437866 94.35) (width 0.1) (layer "In7.Cu") (net 811))
  (segment (start 240.244036 93.048855) (end 240.597589 93.402408) (width 0.1) (layer "In7.Cu") (net 811))
  (segment (start 180.624529 94.093617) (end 180.62453 94.093616) (width 0.09) (layer "In7.Cu") (net 811))
  (segment (start 189.601 97.647) (end 189.601 97.797) (width 0.09) (layer "In7.Cu") (net 811))
  (segment (start 180.341688 94.623947) (end 180.398742 94.681) (width 0.09) (layer "In7.Cu") (net 811))
  (segment (start 241.587538 92.412458) (end 241.587539 92.412462) (width 0.1) (layer "In7.Cu") (net 811))
  (segment (start 180.62453 94.093616) (end 180.341688 94.376459) (width 0.09) (layer "In7.Cu") (net 811))
  (segment (start 243.905 91.195) (end 243.905 91.042432) (width 0.1) (layer "In7.Cu") (net 811))
  (segment (start 241.587539 92.412462) (end 241.888061 92.712981) (width 0.1) (layer "In7.Cu") (net 811))
  (segment (start 245.662134 92.05) (end 245.462134 91.85) (width 0.1) (layer "In7.Cu") (net 811))
  (segment (start 246.51 91.765375) (end 246.225375 92.05) (width 0.1) (layer "In7.Cu") (net 811))
  (segment (start 179.299 93.581258) (end 179.563869 93.846128) (width 0.09) (layer "In7.Cu") (net 811))
  (segment (start 239.437866 94.35) (end 202.943866 94.35) (width 0.1) (layer "In7.Cu") (net 811))
  (segment (start 240.89811 93.879709) (end 240.792045 93.985775) (width 0.1) (layer "In7.Cu") (net 811))
  (segment (start 202.943866 94.35) (end 199.430866 97.863) (width 0.1) (layer "In7.Cu") (net 811))
  (segment (start 245.92 91.44) (end 246.101999 91.258001) (width 0.1) (layer "In7.Cu") (net 811))
  (segment (start 185.925422 97.272) (end 188.126 97.272) (width 0.09) (layer "In7.Cu") (net 811))
  (segment (start 242.047158 91.457866) (end 241.941091 91.351799) (width 0.1) (layer "In7.Cu") (net 811))
  (segment (start 191.270385 97.272) (end 191.463385 97.465) (width 0.09) (layer "In7.Cu") (net 811))
  (segment (start 240.615268 93.985774) (end 240.509203 93.879709) (width 0.1) (layer "In7.Cu") (net 811))
  (segment (start 195.095422 97.465) (end 195.54417 97.913748) (width 0.09) (layer "In7.Cu") (net 811))
  (segment (start 193.579971 97.86499) (end 193.579971 98.070338) (width 0.09) (layer "In7.Cu") (net 811))
  (segment (start 179.299 93.397336) (end 179.299 93.581258) (width 0.09) (layer "In7.Cu") (net 811))
  (segment (start 240.244037 92.341749) (end 240.244036 92.341749) (width 0.1) (layer "In7.Cu") (net 811))
  (segment (start 243.555 91.042432) (end 243.555 91.195) (width 0.1) (layer "In7.Cu") (net 811))
  (segment (start 179.636328 93.060008) (end 179.299 93.397336) (width 0.09) (layer "In7.Cu") (net 811))
  (segment (start 183.005422 94.681) (end 183.446422 95.122) (width 0.09) (layer "In7.Cu") (net 811))
  (segment (start 240.597589 93.402412) (end 240.898111 93.702931) (width 0.1) (layer "In7.Cu") (net 811))
  (segment (start 183.446422 95.122) (end 183.775422 95.122) (width 0.09) (layer "In7.Cu") (net 811))
  (segment (start 241.233984 91.3518) (end 241.233985 91.351799) (width 0.1) (layer "In7.Cu") (net 811))
  (segment (start 182.399 94.681) (end 183.005422 94.681) (width 0.09) (layer "In7.Cu") (net 811))
  (segment (start 246.51 91.432134) (end 246.51 91.765375) (width 0.1) (layer "In7.Cu") (net 811))
  (segment (start 244.937134 91.475) (end 244.937134 91.675) (width 0.1) (layer "In7.Cu") (net 811))
  (segment (start 188.851 97.797) (end 188.851 97.647) (width 0.09) (layer "In7.Cu") (net 811))
  (segment (start 246.225375 92.05) (end 245.662134 92.05) (width 0.1) (layer "In7.Cu") (net 811))
  (segment (start 179.811359 93.84613) (end 180.0942 93.563286) (width 0.09) (layer "In7.Cu") (net 811))
  (segment (start 195.54417 97.913748) (end 198.085831 97.913748) (width 0.09) (layer "In7.Cu") (net 811))
  (segment (start 240.898111 93.879707) (end 240.89811 93.879709) (width 0.1) (layer "In7.Cu") (net 811))
  (segment (start 246.335867 91.258001) (end 246.51 91.432134) (width 0.1) (layer "In7.Cu") (net 811))
  (segment (start 244.762134 91.85) (end 244.672134 91.85) (width 0.1) (layer "In7.Cu") (net 811))
  (segment (start 189.951 97.797) (end 189.951 97.647) (width 0.09) (layer "In7.Cu") (net 811))
  (segment (start 183.775422 95.122) (end 185.925422 97.272) (width 0.09) (layer "In7.Cu") (net 811))
  (segment (start 198.156542 97.884458) (end 198.178 97.863) (width 0.09) (layer "In7.Cu") (net 811))
  (segment (start 241.605218 92.995824) (end 240.951143 92.341749) (width 0.1) (layer "In7.Cu") (net 811))
  (segment (start 246.101999 91.258001) (end 246.335867 91.258001) (width 0.1) (layer "In7.Cu") (net 811))
  (segment (start 180.398742 94.681) (end 181.299 94.681) (width 0.09) (layer "In7.Cu") (net 811))
  (segment (start 182.224 93.806) (end 182.224 94.506) (width 0.09) (layer "In7.Cu") (net 811))
  (segment (start 240.597589 93.402408) (end 240.597589 93.402412) (width 0.1) (layer "In7.Cu") (net 811))
  (segment (start 241.233985 92.058905) (end 241.587538 92.412458) (width 0.1) (layer "In7.Cu") (net 811))
  (segment (start 242.417866 91.37) (end 242.33 91.457866) (width 0.1) (layer "In7.Cu") (net 811))
  (segment (start 199.430866 97.863) (end 198.178 97.863) (width 0.1) (layer "In7.Cu") (net 811))
  (segment (start 241.888061 92.889757) (end 241.88806 92.889759) (width 0.1) (layer "In7.Cu") (net 811))
  (segment (start 180.341687 94.623946) (end 180.341688 94.623947) (width 0.09) (layer "In7.Cu") (net 811))
  (segment (start 194.379981 97.465) (end 195.095422 97.465) (width 0.09) (layer "In7.Cu") (net 811))
  (segment (start 181.474 94.506) (end 181.474 93.806) (width 0.09) (layer "In7.Cu") (net 811))
  (segment (start 244.192134 91.37) (end 244.08 91.37) (width 0.1) (layer "In7.Cu") (net 811))
  (segment (start 245.287134 91.675) (end 245.287134 91.475) (width 0.1) (layer "In7.Cu") (net 811))
  (segment (start 193.979991 98.070338) (end 193.979991 97.86499) (width 0.09) (layer "In7.Cu") (net 811))
  (segment (start 244.672134 91.85) (end 244.192134 91.37) (width 0.1) (layer "In7.Cu") (net 811))
  (segment (start 191.463385 97.465) (end 193.179981 97.465) (width 0.09) (layer "In7.Cu") (net 811))
  (segment (start 242.58 91.37) (end 242.417866 91.37) (width 0.1) (layer "In7.Cu") (net 811))
  (segment (start 188.501 97.647) (end 188.501 97.797) (width 0.09) (layer "In7.Cu") (net 811))
  (arc (start 188.676 97.972) (mid 188.799744 97.920744) (end 188.851 97.797) (width 0.09) (layer "In7.Cu") (net 811))
  (arc (start 240.898111 93.702931) (mid 240.934723 93.791319) (end 240.898111 93.879707) (width 0.1) (layer "In7.Cu") (net 811))
  (arc (start 193.979991 97.86499) (mid 194.097145 97.582154) (end 194.379981 97.465) (width 0.09) (layer "In7.Cu") (net 811))
  (arc (start 180.341688 94.376459) (mid 180.290431 94.500202) (end 180.341687 94.623946) (width 0.09) (layer "In7.Cu") (net 811))
  (arc (start 242.33 91.457866) (mid 242.188579 91.516444) (end 242.047158 91.457866) (width 0.1) (layer "In7.Cu") (net 811))
  (arc (start 188.501 97.797) (mid 188.552256 97.920744) (end 188.676 97.972) (width 0.09) (layer "In7.Cu") (net 811))
  (arc (start 243.555 91.195) (mid 243.503744 91.318744) (end 243.38 91.37) (width 0.1) (layer "In7.Cu") (net 811))
  (arc (start 182.224 94.506) (mid 182.275256 94.629744) (end 182.399 94.681) (width 0.09) (layer "In7.Cu") (net 811))
  (arc (start 244.937134 91.675) (mid 244.885878 91.798744) (end 244.762134 91.85) (width 0.1) (layer "In7.Cu") (net 811))
  (arc (start 180.0942 93.563286) (mid 180.359365 93.453451) (end 180.62453 93.563286) (width 0.09) (layer "In7.Cu") (net 811))
  (arc (start 189.601 97.797) (mid 189.652256 97.920744) (end 189.776 97.972) (width 0.09) (layer "In7.Cu") (net 811))
  (arc (start 241.781995 92.995825) (mid 241.693606 93.032436) (end 241.605218 92.995824) (width 0.1) (layer "In7.Cu") (net 811))
  (arc (start 198.085831 97.913748) (mid 198.1241 97.906136) (end 198.156542 97.884458) (width 0.09) (layer "In7.Cu") (net 811))
  (arc (start 241.888061 92.712981) (mid 241.924673 92.801369) (end 241.888061 92.889757) (width 0.1) (layer "In7.Cu") (net 811))
  (arc (start 242.98 90.97) (mid 242.838579 91.028579) (end 242.78 91.17) (width 0.1) (layer "In7.Cu") (net 811))
  (arc (start 245.462134 91.85) (mid 245.33839 91.798744) (end 245.287134 91.675) (width 0.1) (layer "In7.Cu") (net 811))
  (arc (start 193.779981 98.270348) (mid 193.921409 98.211766) (end 193.979991 98.070338) (width 0.09) (layer "In7.Cu") (net 811))
  (arc (start 243.905 91.042432) (mid 243.853744 90.918688) (end 243.73 90.867432) (width 0.1) (layer "In7.Cu") (net 811))
  (arc (start 179.563869 93.846128) (mid 179.687615 93.897386) (end 179.811359 93.84613) (width 0.09) (layer "In7.Cu") (net 811))
  (arc (start 240.792045 93.985775) (mid 240.703656 94.022386) (end 240.615268 93.985774) (width 0.1) (layer "In7.Cu") (net 811))
  (arc (start 243.18 91.17) (mid 243.121421 91.028579) (end 242.98 90.97) (width 0.1) (layer "In7.Cu") (net 811))
  (arc (start 240.509203 93.879709) (mid 240.208682 93.75523) (end 239.908162 93.87971) (width 0.1) (layer "In7.Cu") (net 811))
  (arc (start 188.851 97.647) (mid 188.960835 97.381835) (end 189.226 97.272) (width 0.09) (layer "In7.Cu") (net 811))
  (arc (start 189.951 97.647) (mid 190.060835 97.381835) (end 190.326 97.272) (width 0.09) (layer "In7.Cu") (net 811))
  (arc (start 181.849 93.431) (mid 182.114165 93.540835) (end 182.224 93.806) (width 0.09) (layer "In7.Cu") (net 811))
  (arc (start 189.776 97.972) (mid 189.899744 97.920744) (end 189.951 97.797) (width 0.09) (layer "In7.Cu") (net 811))
  (arc (start 181.299 94.681) (mid 181.422744 94.629744) (end 181.474 94.506) (width 0.09) (layer "In7.Cu") (net 811))
  (arc (start 245.112134 91.3) (mid 244.98839 91.351256) (end 244.937134 91.475) (width 0.1) (layer "In7.Cu") (net 811))
  (arc (start 243.38 91.37) (mid 243.238579 91.311421) (end 243.18 91.17) (width 0.1) (layer "In7.Cu") (net 811))
  (arc (start 193.179981 97.465) (mid 193.462817 97.582154) (end 193.579971 97.86499) (width 0.09) (layer "In7.Cu") (net 811))
  (arc (start 241.233985 91.351799) (mid 241.087539 91.705352) (end 241.233985 92.058905) (width 0.1) (layer "In7.Cu") (net 811))
  (arc (start 242.78 91.17) (mid 242.721421 91.311421) (end 242.58 91.37) (width 0.1) (layer "In7.Cu") (net 811))
  (arc (start 180.62453 93.563286) (mid 180.734366 93.828453) (end 180.624529 94.093617) (width 0.09) (layer "In7.Cu") (net 811))
  (arc (start 245.287134 91.475) (mid 245.235878 91.351256) (end 245.112134 91.3) (width 0.1) (layer "In7.Cu") (net 811))
  (arc (start 244.08 91.37) (mid 243.956256 91.318744) (end 243.905 91.195) (width 0.1) (layer "In7.Cu") (net 811))
  (arc (start 188.126 97.272) (mid 188.391165 97.381835) (end 188.501 97.647) (width 0.09) (layer "In7.Cu") (net 811))
  (arc (start 241.941091 91.351799) (mid 241.587537 91.205353) (end 241.233984 91.3518) (width 0.1) (layer "In7.Cu") (net 811))
  (arc (start 240.244036 92.341749) (mid 240.09759 92.695302) (end 240.244036 93.048855) (width 0.1) (layer "In7.Cu") (net 811))
  (arc (start 193.579971 98.070338) (mid 193.638553 98.211766) (end 193.779981 98.270348) (width 0.09) (layer "In7.Cu") (net 811))
  (arc (start 243.73 90.867432) (mid 243.606256 90.918688) (end 243.555 91.042432) (width 0.1) (layer "In7.Cu") (net 811))
  (arc (start 240.951143 92.341749) (mid 240.59759 92.195303) (end 240.244037 92.341749) (width 0.1) (layer "In7.Cu") (net 811))
  (arc (start 181.474 93.806) (mid 181.583835 93.540835) (end 181.849 93.431) (width 0.09) (layer "In7.Cu") (net 811))
  (arc (start 189.226 97.272) (mid 189.491165 97.381835) (end 189.601 97.647) (width 0.09) (layer "In7.Cu") (net 811))
  (segment (start 246.555 91.33) (end 246.555 91.745) (width 0.1) (layer "B.Cu") (net 811))
  (segment (start 245.92 91.44) (end 246.101999 91.258001) (width 0.1) (layer "B.Cu") (net 811))
  (segment (start 246.101999 91.258001) (end 246.483001 91.258001) (width 0.1) (layer "B.Cu") (net 811))
  (segment (start 246.483001 91.258001) (end 246.555 91.33) (width 0.1) (layer "B.Cu") (net 811))
  (segment (start 179.136328 92.560008) (end 178.636328 93.060008) (width 0.1) (layer "F.Cu") (net 812))
  (via (at 178.636328 93.060008) (size 0.5) (drill 0.2) (layers "F.Cu" "B.Cu") (net 812))
  (via (at 245.92 109.826) (size 0.5) (drill 0.2) (layers "F.Cu" "B.Cu") (net 812))
  (segment (start 239.473402 99.185535) (end 242.35 102.062134) (width 0.1) (layer "In9.Cu") (net 812))
  (segment (start 243.787866 107.75) (end 244.781 107.75) (width 0.1) (layer "In9.Cu") (net 812))
  (segment (start 244.931 107.9) (end 244.931 108) (width 0.1) (layer "In9.Cu") (net 812))
  (segment (start 245.870945 108.330567) (end 245.870946 108.330566) (width 0.1) (layer "In9.Cu") (net 812))
  (segment (start 237.21029 96.216067) (end 237.316355 96.109999) (width 0.1) (layer "In9.Cu") (net 812))
  (segment (start 181.04 92.861422) (end 181.04 93.781422) (width 0.09) (layer "In9.Cu") (net 812))
  (segment (start 246.583 108.795134) (end 246.583 109.704866) (width 0.1) (layer "In9.Cu") (net 812))
  (segment (start 237.246394 96.746394) (end 236.893216 97.099572) (width 0.1) (layer "In9.Cu") (net 812))
  (segment (start 245.381 107.75) (end 245.537866 107.75) (width 0.1) (layer "In9.Cu") (net 812))
  (segment (start 237.883164 98.795876) (end 237.883916 98.796628) (width 0.1) (layer "In9.Cu") (net 812))
  (segment (start 237.600324 97.80668) (end 238.306679 97.100323) (width 0.1) (layer "In9.Cu") (net 812))
  (segment (start 182.058578 94.8) (end 187.841422 94.8) (width 0.09) (layer "In9.Cu") (net 812))
  (segment (start 196.227866 93.83) (end 197.297866 94.9) (width 0.1) (layer "In9.Cu") (net 812))
  (segment (start 179.420992 92.665008) (end 179.863992 92.665008) (width 0.09) (layer "In9.Cu") (net 812))
  (segment (start 239.579468 98.373112) (end 239.473402 98.479179) (width 0.1) (layer "In9.Cu") (net 812))
  (segment (start 238.588769 97.100323) (end 238.588769 97.100324) (width 0.1) (layer "In9.Cu") (net 812))
  (segment (start 237.598444 96.109998) (end 237.598445 96.11) (width 0.1) (layer "In9.Cu") (net 812))
  (segment (start 245.231 108) (end 245.231 107.9) (width 0.1) (layer "In9.Cu") (net 812))
  (segment (start 238.588769 97.100324) (end 238.589521 97.101076) (width 0.1) (layer "In9.Cu") (net 812))
  (segment (start 238.58952 97.383165) (end 238.58952 97.383164) (width 0.1) (layer "In9.Cu") (net 812))
  (segment (start 190.91066 93.775725) (end 192.103593 93.775725) (width 0.09) (layer "In9.Cu") (net 812))
  (segment (start 178.636328 92.745672) (end 178.716992 92.665008) (width 0.09) (layer "In9.Cu") (net 812))
  (segment (start 242.35 106.312134) (end 243.787866 107.75) (width 0.1) (layer "In9.Cu") (net 812))
  (segment (start 190.799943 93.665008) (end 190.91066 93.775725) (width 0.09) (layer "In9.Cu") (net 812))
  (segment (start 178.716992 92.665008) (end 178.920992 92.665008) (width 0.09) (layer "In9.Cu") (net 812))
  (segment (start 179.988992 92.790008) (end 179.988992 92.805234) (width 0.09) (layer "In9.Cu") (net 812))
  (segment (start 239.084495 98.302406) (end 239.296627 98.090271) (width 0.1) (layer "In9.Cu") (net 812))
  (segment (start 199.768866 95.481) (end 235.768866 95.481) (width 0.1) (layer "In9.Cu") (net 812))
  (segment (start 180.238992 92.805234) (end 180.238992 92.790008) (width 0.09) (layer "In9.Cu") (net 812))
  (segment (start 246.101999 110.007999) (end 245.92 109.826) (width 0.1) (layer "In9.Cu") (net 812))
  (segment (start 237.246019 96.746018) (end 237.246394 96.746394) (width 0.1) (layer "In9.Cu") (net 812))
  (segment (start 246.583 109.704866) (end 246.279867 110.007999) (width 0.1) (layer "In9.Cu") (net 812))
  (segment (start 180.640464 92.665008) (end 180.640984 92.665528) (width 0.09) (layer "In9.Cu") (net 812))
  (segment (start 236.893216 97.805928) (end 236.893968 97.80668) (width 0.1) (layer "In9.Cu") (net 812))
  (segment (start 192.209659 93.819659) (end 192.22 93.83) (width 0.09) (layer "In9.Cu") (net 812))
  (segment (start 188.241328 94.400094) (end 188.241328 93.896393) (width 0.09) (layer "In9.Cu") (net 812))
  (segment (start 187.841422 94.8) (end 188.241328 94.400094) (width 0.09) (layer "In9.Cu") (net 812))
  (segment (start 199.187866 94.9) (end 199.768866 95.481) (width 0.1) (layer "In9.Cu") (net 812))
  (segment (start 237.599196 96.39284) (end 237.246019 96.746018) (width 0.1) (layer "In9.Cu") (net 812))
  (segment (start 245.537866 107.75) (end 245.623457 107.835591) (width 0.1) (layer "In9.Cu") (net 812))
  (segment (start 242.35 102.062134) (end 242.35 106.312134) (width 0.1) (layer "In9.Cu") (net 812))
  (segment (start 197.297866 94.9) (end 199.187866 94.9) (width 0.1) (layer "In9.Cu") (net 812))
  (segment (start 178.636328 93.060008) (end 178.636328 92.745672) (width 0.09) (layer "In9.Cu") (net 812))
  (segment (start 246.279867 110.007999) (end 246.101999 110.007999) (width 0.1) (layer "In9.Cu") (net 812))
  (segment (start 180.363992 92.665008) (end 180.640464 92.665008) (width 0.09) (layer "In9.Cu") (net 812))
  (segment (start 238.837383 98.549516) (end 239.084495 98.302406) (width 0.1) (layer "In9.Cu") (net 812))
  (segment (start 239.578717 98.090272) (end 239.579469 98.091024) (width 0.1) (layer "In9.Cu") (net 812))
  (segment (start 237.598445 96.11) (end 237.599197 96.110752) (width 0.1) (layer "In9.Cu") (net 812))
  (segment (start 192.22 93.83) (end 196.227866 93.83) (width 0.1) (layer "In9.Cu") (net 812))
  (segment (start 235.768866 95.481) (end 236.503932 96.216065) (width 0.1) (layer "In9.Cu") (net 812))
  (segment (start 188.241328 93.896393) (end 188.472713 93.665008) (width 0.09) (layer "In9.Cu") (net 812))
  (segment (start 239.578717 98.090271) (end 239.578717 98.090272) (width 0.1) (layer "In9.Cu") (net 812))
  (segment (start 246.118433 108.330567) (end 246.583 108.795134) (width 0.1) (layer "In9.Cu") (net 812))
  (segment (start 239.579468 98.373113) (end 239.579468 98.373112) (width 0.1) (layer "In9.Cu") (net 812))
  (segment (start 181.04 93.781422) (end 182.058578 94.8) (width 0.09) (layer "In9.Cu") (net 812))
  (segment (start 180.640984 92.665528) (end 180.844106 92.665528) (width 0.09) (layer "In9.Cu") (net 812))
  (segment (start 237.599196 96.392841) (end 237.599196 96.39284) (width 0.1) (layer "In9.Cu") (net 812))
  (segment (start 245.623457 108.083079) (end 245.623456 108.08308) (width 0.1) (layer "In9.Cu") (net 812))
  (segment (start 238.58952 97.383164) (end 237.883164 98.08952) (width 0.1) (layer "In9.Cu") (net 812))
  (segment (start 188.472713 93.665008) (end 190.799943 93.665008) (width 0.09) (layer "In9.Cu") (net 812))
  (segment (start 180.844106 92.665528) (end 181.04 92.861422) (width 0.09) (layer "In9.Cu") (net 812))
  (segment (start 238.590272 98.796628) (end 238.837383 98.549516) (width 0.1) (layer "In9.Cu") (net 812))
  (arc (start 244.931 108) (mid 244.974934 108.106066) (end 245.081 108.15) (width 0.1) (layer "In9.Cu") (net 812))
  (arc (start 236.503932 96.216065) (mid 236.857111 96.362357) (end 237.21029 96.216067) (width 0.1) (layer "In9.Cu") (net 812))
  (arc (start 237.883164 98.08952) (mid 237.736873 98.442698) (end 237.883164 98.795876) (width 0.1) (layer "In9.Cu") (net 812))
  (arc (start 179.863992 92.665008) (mid 179.95238 92.70162) (end 179.988992 92.790008) (width 0.09) (layer "In9.Cu") (net 812))
  (arc (start 236.893216 97.099572) (mid 236.746925 97.45275) (end 236.893216 97.805928) (width 0.1) (layer "In9.Cu") (net 812))
  (arc (start 239.473402 98.479179) (mid 239.32711 98.832356) (end 239.473402 99.185535) (width 0.1) (layer "In9.Cu") (net 812))
  (arc (start 237.599197 96.110752) (mid 237.657618 96.251796) (end 237.599196 96.392841) (width 0.1) (layer "In9.Cu") (net 812))
  (arc (start 178.920992 92.665008) (mid 179.00938 92.70162) (end 179.045992 92.790008) (width 0.09) (layer "In9.Cu") (net 812))
  (arc (start 245.623457 108.330567) (mid 245.747201 108.381823) (end 245.870945 108.330567) (width 0.1) (layer "In9.Cu") (net 812))
  (arc (start 238.589521 97.101076) (mid 238.647942 97.24212) (end 238.58952 97.383165) (width 0.1) (layer "In9.Cu") (net 812))
  (arc (start 237.316355 96.109999) (mid 237.4574 96.051577) (end 237.598444 96.109998) (width 0.1) (layer "In9.Cu") (net 812))
  (arc (start 180.113992 92.930234) (mid 180.20238 92.893622) (end 180.238992 92.805234) (width 0.09) (layer "In9.Cu") (net 812))
  (arc (start 180.238992 92.790008) (mid 180.275604 92.70162) (end 180.363992 92.665008) (width 0.09) (layer "In9.Cu") (net 812))
  (arc (start 237.883916 98.796628) (mid 238.237094 98.942919) (end 238.590272 98.796628) (width 0.1) (layer "In9.Cu") (net 812))
  (arc (start 179.170992 92.915008) (mid 179.25938 92.878396) (end 179.295992 92.790008) (width 0.09) (layer "In9.Cu") (net 812))
  (arc (start 244.781 107.75) (mid 244.887066 107.793934) (end 244.931 107.9) (width 0.1) (layer "In9.Cu") (net 812))
  (arc (start 179.295992 92.790008) (mid 179.332604 92.70162) (end 179.420992 92.665008) (width 0.09) (layer "In9.Cu") (net 812))
  (arc (start 179.045992 92.790008) (mid 179.082604 92.878396) (end 179.170992 92.915008) (width 0.09) (layer "In9.Cu") (net 812))
  (arc (start 245.081 108.15) (mid 245.187066 108.106066) (end 245.231 108) (width 0.1) (layer "In9.Cu") (net 812))
  (arc (start 238.306679 97.100323) (mid 238.447724 97.0419) (end 238.588769 97.100323) (width 0.1) (layer "In9.Cu") (net 812))
  (arc (start 179.988992 92.805234) (mid 180.025604 92.893622) (end 180.113992 92.930234) (width 0.09) (layer "In9.Cu") (net 812))
  (arc (start 239.579469 98.091024) (mid 239.63789 98.232068) (end 239.579468 98.373113) (width 0.1) (layer "In9.Cu") (net 812))
  (arc (start 245.623457 107.835591) (mid 245.674713 107.959335) (end 245.623457 108.083079) (width 0.1) (layer "In9.Cu") (net 812))
  (arc (start 245.231 107.9) (mid 245.274934 107.793934) (end 245.381 107.75) (width 0.1) (layer "In9.Cu") (net 812))
  (arc (start 245.870946 108.330566) (mid 245.99469 108.27931) (end 246.118433 108.330567) (width 0.1) (layer "In9.Cu") (net 812))
  (arc (start 192.103593 93.775725) (mid 192.160996 93.787143) (end 192.209659 93.819659) (width 0.09) (layer "In9.Cu") (net 812))
  (arc (start 236.893968 97.80668) (mid 237.247146 97.952971) (end 237.600324 97.80668) (width 0.1) (layer "In9.Cu") (net 812))
  (arc (start 239.296627 98.090271) (mid 239.437672 98.031848) (end 239.578717 98.090271) (width 0.1) (layer "In9.Cu") (net 812))
  (arc (start 245.623456 108.08308) (mid 245.5722 108.206824) (end 245.623457 108.330567) (width 0.1) (layer "In9.Cu") (net 812))
  (segment (start 245.92 109.826) (end 246.101999 110.007999) (width 0.1) (layer "B.Cu") (net 812))
  (segment (start 246.555 109.905) (end 246.555 109.525) (width 0.1) (layer "B.Cu") (net 812))
  (segment (start 246.101999 110.007999) (end 246.452001 110.007999) (width 0.1) (layer "B.Cu") (net 812))
  (segment (start 246.452001 110.007999) (end 246.555 109.905) (width 0.1) (layer "B.Cu") (net 812))
  (segment (start 178.136328 92.560008) (end 177.636328 93.060008) (width 0.1) (layer "F.Cu") (net 813))
  (via (at 244.65 113.03) (size 0.5) (drill 0.2) (layers "F.Cu" "B.Cu") (net 813))
  (via (at 177.636328 93.060008) (size 0.5) (drill 0.2) (layers "F.Cu" "B.Cu") (net 813))
  (segment (start 177.24 93.19) (end 177.24 93.348578) (width 0.09) (layer "In9.Cu") (net 813))
  (segment (start 181.201013 94.761066) (end 181.201014 94.761065) (width 0.09) (layer "In9.Cu") (net 813))
  (segment (start 242.65 109.437866) (end 242.65 107.937866) (width 0.1) (layer "In9.Cu") (net 813))
  (segment (start 245.164133 112.848001) (end 245.6 112.412134) (width 0.1) (layer "In9.Cu") (net 813))
  (segment (start 242.65 107.937866) (end 241.15 106.437866) (width 0.1) (layer "In9.Cu") (net 813))
  (segment (start 241.15 102.687866) (end 235.112134 96.65) (width 0.1) (layer "In9.Cu") (net 813))
  (segment (start 181.201014 94.761065) (end 180.882816 95.079263) (width 0.09) (layer "In9.Cu") (net 813))
  (segment (start 245.6 112.412134) (end 245.6 111.866393) (width 0.1) (layer "In9.Cu") (net 813))
  (segment (start 200.855 97.303406) (end 200.855 97.125) (width 0.1) (layer "In9.Cu") (net 813))
  (segment (start 177.636328 93.060008) (end 177.369992 93.060008) (width 0.09) (layer "In9.Cu") (net 813))
  (segment (start 202.505 97.125) (end 202.505 97.303406) (width 0.1) (layer "In9.Cu") (net 813))
  (segment (start 201.205 96.296594) (end 201.205 97.303406) (width 0.1) (layer "In9.Cu") (net 813))
  (segment (start 180.092818 94.501397) (end 180.175711 94.584289) (width 0.09) (layer "In9.Cu") (net 813))
  (segment (start 195.892134 94.33) (end 192.26 94.33) (width 0.1) (layer "In9.Cu") (net 813))
  (segment (start 180.387843 94.584289) (end 180.70604 94.26609) (width 0.09) (layer "In9.Cu") (net 813))
  (segment (start 177.34643 93.455008) (end 179.04643 93.455008) (width 0.09) (layer "In9.Cu") (net 813))
  (segment (start 177.369992 93.060008) (end 177.24 93.19) (width 0.09) (layer "In9.Cu") (net 813))
  (segment (start 244.562134 111.35) (end 242.65 109.437866) (width 0.1) (layer "In9.Cu") (net 813))
  (segment (start 180.092816 94.501394) (end 180.092818 94.501397) (width 0.09) (layer "In9.Cu") (net 813))
  (segment (start 202.155 97.303406) (end 202.155 96.296594) (width 0.1) (layer "In9.Cu") (net 813))
  (segment (start 189.359578 94.465) (end 191.296578 94.465) (width 0.09) (layer "In9.Cu") (net 813))
  (segment (start 180.446371 93.93571) (end 180.092816 94.289262) (width 0.09) (layer "In9.Cu") (net 813))
  (segment (start 192.255 94.33) (end 192.26 94.33) (width 0.09) (layer "In9.Cu") (net 813))
  (segment (start 197.122134 95.56) (end 195.892134 94.33) (width 0.1) (layer "In9.Cu") (net 813))
  (segment (start 191.381578 94.38) (end 192.142868 94.38) (width 0.09) (layer "In9.Cu") (net 813))
  (segment (start 180.882817 95.291396) (end 180.941422 95.35) (width 0.09) (layer "In9.Cu") (net 813))
  (segment (start 244.65 113.03) (end 244.831999 112.848001) (width 0.1) (layer "In9.Cu") (net 813))
  (segment (start 180.44637 93.935711) (end 180.446371 93.93571) (width 0.09) (layer "In9.Cu") (net 813))
  (segment (start 244.831999 112.848001) (end 245.164133 112.848001) (width 0.1) (layer "In9.Cu") (net 813))
  (segment (start 177.24 93.348578) (end 177.34643 93.455008) (width 0.09) (layer "In9.Cu") (net 813))
  (segment (start 179.597843 93.79429) (end 179.951395 93.440735) (width 0.09) (layer "In9.Cu") (net 813))
  (segment (start 179.04643 93.455008) (end 179.385709 93.794288) (width 0.09) (layer "In9.Cu") (net 813))
  (segment (start 180.941422 95.35) (end 188.474578 95.35) (width 0.09) (layer "In9.Cu") (net 813))
  (segment (start 188.474578 95.35) (end 189.359578 94.465) (width 0.09) (layer "In9.Cu") (net 813))
  (segment (start 180.446369 93.440735) (end 180.446371 93.440736) (width 0.09) (layer "In9.Cu") (net 813))
  (segment (start 198.122134 95.56) (end 197.122134 95.56) (width 0.1) (layer "In9.Cu") (net 813))
  (segment (start 180.882816 95.291395) (end 180.882817 95.291396) (width 0.09) (layer "In9.Cu") (net 813))
  (segment (start 192.248934 94.336066) (end 192.255 94.33) (width 0.09) (layer "In9.Cu") (net 813))
  (segment (start 235.112134 96.65) (end 202.98 96.65) (width 0.1) (layer "In9.Cu") (net 813))
  (segment (start 245.083607 111.35) (end 244.562134 111.35) (width 0.1) (layer "In9.Cu") (net 813))
  (segment (start 191.296578 94.465) (end 191.381578 94.38) (width 0.09) (layer "In9.Cu") (net 813))
  (segment (start 199.212134 96.65) (end 198.122134 95.56) (width 0.1) (layer "In9.Cu") (net 813))
  (segment (start 245.6 111.866393) (end 245.083607 111.35) (width 0.1) (layer "In9.Cu") (net 813))
  (segment (start 241.15 106.437866) (end 241.15 102.687866) (width 0.1) (layer "In9.Cu") (net 813))
  (segment (start 181.201015 94.266089) (end 181.201014 94.266091) (width 0.09) (layer "In9.Cu") (net 813))
  (segment (start 200.38 96.65) (end 199.212134 96.65) (width 0.1) (layer "In9.Cu") (net 813))
  (arc (start 180.70604 94.26609) (mid 180.953527 94.163577) (end 181.201015 94.266089) (width 0.09) (layer "In9.Cu") (net 813))
  (arc (start 180.175711 94.584289) (mid 180.281777 94.628223) (end 180.387843 94.584289) (width 0.09) (layer "In9.Cu") (net 813))
  (arc (start 201.205 97.303406) (mid 201.153744 97.42715) (end 201.03 97.478406) (width 0.1) (layer "In9.Cu") (net 813))
  (arc (start 179.951395 93.440735) (mid 180.198883 93.338224) (end 180.446369 93.440735) (width 0.09) (layer "In9.Cu") (net 813))
  (arc (start 202.155 96.296594) (mid 202.015876 95.960718) (end 201.68 95.821594) (width 0.1) (layer "In9.Cu") (net 813))
  (arc (start 180.446371 93.440736) (mid 180.548883 93.688224) (end 180.44637 93.935711) (width 0.09) (layer "In9.Cu") (net 813))
  (arc (start 179.385709 93.794288) (mid 179.491777 93.838224) (end 179.597843 93.79429) (width 0.09) (layer "In9.Cu") (net 813))
  (arc (start 201.68 95.821594) (mid 201.344124 95.960718) (end 201.205 96.296594) (width 0.1) (layer "In9.Cu") (net 813))
  (arc (start 192.142868 94.38) (mid 192.200271 94.368582) (end 192.248934 94.336066) (width 0.09) (layer "In9.Cu") (net 813))
  (arc (start 180.092816 94.289262) (mid 180.048882 94.395328) (end 180.092816 94.501394) (width 0.09) (layer "In9.Cu") (net 813))
  (arc (start 180.882816 95.079263) (mid 180.838882 95.185327) (end 180.882816 95.291395) (width 0.09) (layer "In9.Cu") (net 813))
  (arc (start 202.98 96.65) (mid 202.644124 96.789124) (end 202.505 97.125) (width 0.1) (layer "In9.Cu") (net 813))
  (arc (start 202.33 97.478406) (mid 202.206256 97.42715) (end 202.155 97.303406) (width 0.1) (layer "In9.Cu") (net 813))
  (arc (start 201.03 97.478406) (mid 200.906256 97.42715) (end 200.855 97.303406) (width 0.1) (layer "In9.Cu") (net 813))
  (arc (start 202.505 97.303406) (mid 202.453744 97.42715) (end 202.33 97.478406) (width 0.1) (layer "In9.Cu") (net 813))
  (arc (start 181.201014 94.266091) (mid 181.303526 94.513579) (end 181.201013 94.761066) (width 0.09) (layer "In9.Cu") (net 813))
  (arc (start 200.855 97.125) (mid 200.715876 96.789124) (end 200.38 96.65) (width 0.1) (layer "In9.Cu") (net 813))
  (segment (start 244.65 113.03) (end 244.831999 112.848001) (width 0.1) (layer "B.Cu") (net 813))
  (segment (start 245.285 112.92) (end 245.285 113.335) (width 0.1) (layer "B.Cu") (net 813))
  (segment (start 244.831999 112.848001) (end 245.213001 112.848001) (width 0.1) (layer "B.Cu") (net 813))
  (segment (start 245.213001 112.848001) (end 245.285 112.92) (width 0.1) (layer "B.Cu") (net 813))
  (segment (start 177.136328 92.560008) (end 176.636328 93.060008) (width 0.1) (layer "F.Cu") (net 814))
  (via (at 176.636328 93.060008) (size 0.5) (drill 0.2) (layers "F.Cu" "B.Cu") (net 814))
  (via (at 244.65 112.366) (size 0.5) (drill 0.2) (layers "F.Cu" "B.Cu") (net 814))
  (segment (start 200.555 97.125) (end 200.555 97.303406) (width 0.1) (layer "In9.Cu") (net 814))
  (segment (start 243.987522 111.376433) (end 243.987524 111.376434) (width 0.1) (layer "In9.Cu") (net 814))
  (segment (start 177.04 93.19) (end 177.04 93.431422) (width 0.09) (layer "In9.Cu") (net 814))
  (segment (start 245.039867 112.547999) (end 244.831999 112.547999) (width 0.1) (layer "In9.Cu") (net 814))
  (segment (start 191.379422 94.665) (end 191.464422 94.58) (width 0.09) (layer "In9.Cu") (net 814))
  (segment (start 197.997866 95.86) (end 199.087866 96.95) (width 0.1) (layer "In9.Cu") (net 814))
  (segment (start 176.910008 93.060008) (end 177.04 93.19) (width 0.09) (layer "In9.Cu") (net 814))
  (segment (start 189.484924 94.664343) (end 189.812154 94.664343) (width 0.09) (layer "In9.Cu") (net 814))
  (segment (start 179.951396 94.642817) (end 180.034288 94.725708) (width 0.09) (layer "In9.Cu") (net 814))
  (segment (start 180.529262 94.72571) (end 180.529264 94.725709) (width 0.09) (layer "In9.Cu") (net 814))
  (segment (start 189.812154 94.664343) (end 189.812811 94.665) (width 0.09) (layer "In9.Cu") (net 814))
  (segment (start 180.741393 95.432814) (end 180.741394 95.432816) (width 0.09) (layer "In9.Cu") (net 814))
  (segment (start 179.739264 93.935711) (end 179.739264 93.93571) (width 0.09) (layer "In9.Cu") (net 814))
  (segment (start 244.959339 111.65) (end 245.3 111.990661) (width 0.1) (layer "In9.Cu") (net 814))
  (segment (start 191.464422 94.58) (end 192.147868 94.58) (width 0.09) (layer "In9.Cu") (net 814))
  (segment (start 178.963567 93.654989) (end 179.244288 93.935709) (width 0.09) (layer "In9.Cu") (net 814))
  (segment (start 195.767866 94.63) (end 196.997866 95.86) (width 0.1) (layer "In9.Cu") (net 814))
  (segment (start 244.376433 111.588567) (end 244.437866 111.65) (width 0.1) (layer "In9.Cu") (net 814))
  (segment (start 234.987866 96.95) (end 240.85 102.812134) (width 0.1) (layer "In9.Cu") (net 814))
  (segment (start 244.437866 111.65) (end 244.959339 111.65) (width 0.1) (layer "In9.Cu") (net 814))
  (segment (start 192.253934 94.623934) (end 192.26 94.63) (width 0.09) (layer "In9.Cu") (net 814))
  (segment (start 202.805 97.303406) (end 202.805 97.125) (width 0.1) (layer "In9.Cu") (net 814))
  (segment (start 176.636328 93.060008) (end 176.910008 93.060008) (width 0.09) (layer "In9.Cu") (net 814))
  (segment (start 188.557422 95.55) (end 189.442422 94.665) (width 0.09) (layer "In9.Cu") (net 814))
  (segment (start 179.951395 94.642815) (end 179.951396 94.642817) (width 0.09) (layer "In9.Cu") (net 814))
  (segment (start 245.3 111.990661) (end 245.3 112.287866) (width 0.1) (layer "In9.Cu") (net 814))
  (segment (start 243.563255 110.987521) (end 243.55191 110.998867) (width 0.1) (layer "In9.Cu") (net 814))
  (segment (start 181.059593 94.619644) (end 180.741395 94.93784) (width 0.09) (layer "In9.Cu") (net 814))
  (segment (start 244.831999 112.547999) (end 244.65 112.366) (width 0.1) (layer "In9.Cu") (net 814))
  (segment (start 196.997866 95.86) (end 197.997866 95.86) (width 0.1) (layer "In9.Cu") (net 814))
  (segment (start 180.741394 95.432816) (end 180.858578 95.55) (width 0.09) (layer "In9.Cu") (net 814))
  (segment (start 243.764043 111.211001) (end 243.77539 111.199653) (width 0.1) (layer "In9.Cu") (net 814))
  (segment (start 243.55191 110.998867) (end 243.551909 110.998869) (width 0.1) (layer "In9.Cu") (net 814))
  (segment (start 189.484267 94.665) (end 189.484924 94.664343) (width 0.09) (layer "In9.Cu") (net 814))
  (segment (start 245.3 112.287866) (end 245.039867 112.547999) (width 0.1) (layer "In9.Cu") (net 814))
  (segment (start 244.022879 111.588567) (end 244.022877 111.588566) (width 0.1) (layer "In9.Cu") (net 814))
  (segment (start 199.087866 96.95) (end 200.38 96.95) (width 0.1) (layer "In9.Cu") (net 814))
  (segment (start 180.858578 95.55) (end 188.557422 95.55) (width 0.09) (layer "In9.Cu") (net 814))
  (segment (start 240.85 106.562134) (end 242.35 108.062134) (width 0.1) (layer "In9.Cu") (net 814))
  (segment (start 189.812811 94.665) (end 191.379422 94.665) (width 0.09) (layer "In9.Cu") (net 814))
  (segment (start 177.263567 93.654989) (end 178.963567 93.654989) (width 0.09) (layer "In9.Cu") (net 814))
  (segment (start 201.505 97.303406) (end 201.505 96.296594) (width 0.1) (layer "In9.Cu") (net 814))
  (segment (start 192.26 94.63) (end 195.767866 94.63) (width 0.1) (layer "In9.Cu") (net 814))
  (segment (start 240.85 102.812134) (end 240.85 106.562134) (width 0.1) (layer "In9.Cu") (net 814))
  (segment (start 189.442422 94.665) (end 189.484267 94.665) (width 0.09) (layer "In9.Cu") (net 814))
  (segment (start 180.304949 93.79429) (end 180.30495 93.794289) (width 0.09) (layer "In9.Cu") (net 814))
  (segment (start 244.199655 111.588566) (end 244.199656 111.588566) (width 0.1) (layer "In9.Cu") (net 814))
  (segment (start 202.98 96.95) (end 234.987866 96.95) (width 0.1) (layer "In9.Cu") (net 814))
  (segment (start 180.529264 94.725709) (end 180.847461 94.40751) (width 0.09) (layer "In9.Cu") (net 814))
  (segment (start 179.739264 93.93571) (end 180.092818 93.582157) (width 0.09) (layer "In9.Cu") (net 814))
  (segment (start 177.04 93.431422) (end 177.263567 93.654989) (width 0.09) (layer "In9.Cu") (net 814))
  (segment (start 180.30495 93.794289) (end 179.951395 94.147841) (width 0.09) (layer "In9.Cu") (net 814))
  (segment (start 201.855 96.296594) (end 201.855 97.303406) (width 0.1) (layer "In9.Cu") (net 814))
  (segment (start 242.35 108.062134) (end 242.35 109.562134) (width 0.1) (layer "In9.Cu") (net 814))
  (segment (start 242.35 109.562134) (end 243.563257 110.775389) (width 0.1) (layer "In9.Cu") (net 814))
  (segment (start 243.987523 111.553211) (end 244.022879 111.588567) (width 0.1) (layer "In9.Cu") (net 814))
  (arc (start 180.092818 93.582157) (mid 180.198884 93.538223) (end 180.30495 93.582157) (width 0.09) (layer "In9.Cu") (net 814))
  (arc (start 244.199656 111.588566) (mid 244.288045 111.551955) (end 244.376433 111.588567) (width 0.1) (layer "In9.Cu") (net 814))
  (arc (start 243.987522 111.199655) (mid 244.024135 111.288045) (end 243.987522 111.376433) (width 0.1) (layer "In9.Cu") (net 814))
  (arc (start 202.33 97.778406) (mid 202.665876 97.639282) (end 202.805 97.303406) (width 0.1) (layer "In9.Cu") (net 814))
  (arc (start 200.555 97.303406) (mid 200.694124 97.639282) (end 201.03 97.778406) (width 0.1) (layer "In9.Cu") (net 814))
  (arc (start 201.855 97.303406) (mid 201.994124 97.639282) (end 202.33 97.778406) (width 0.1) (layer "In9.Cu") (net 814))
  (arc (start 243.77539 111.199653) (mid 243.881455 111.155721) (end 243.987522 111.199655) (width 0.1) (layer "In9.Cu") (net 814))
  (arc (start 202.805 97.125) (mid 202.856256 97.001256) (end 202.98 96.95) (width 0.1) (layer "In9.Cu") (net 814))
  (arc (start 243.987524 111.376434) (mid 243.950912 111.464822) (end 243.987523 111.553211) (width 0.1) (layer "In9.Cu") (net 814))
  (arc (start 180.847461 94.40751) (mid 180.953527 94.363578) (end 181.059593 94.407512) (width 0.09) (layer "In9.Cu") (net 814))
  (arc (start 201.03 97.778406) (mid 201.365876 97.639282) (end 201.505 97.303406) (width 0.1) (layer "In9.Cu") (net 814))
  (arc (start 200.38 96.95) (mid 200.503744 97.001256) (end 200.555 97.125) (width 0.1) (layer "In9.Cu") (net 814))
  (arc (start 179.951395 94.147841) (mid 179.848884 94.395329) (end 179.951395 94.642815) (width 0.09) (layer "In9.Cu") (net 814))
  (arc (start 192.147868 94.58) (mid 192.205271 94.591418) (end 192.253934 94.623934) (width 0.09) (layer "In9.Cu") (net 814))
  (arc (start 244.022877 111.588566) (mid 244.111267 111.625179) (end 244.199655 111.588566) (width 0.1) (layer "In9.Cu") (net 814))
  (arc (start 180.30495 93.582157) (mid 180.348883 93.688223) (end 180.304949 93.79429) (width 0.09) (layer "In9.Cu") (net 814))
  (arc (start 180.034288 94.725708) (mid 180.281776 94.828221) (end 180.529262 94.72571) (width 0.09) (layer "In9.Cu") (net 814))
  (arc (start 243.551909 110.998869) (mid 243.507975 111.104935) (end 243.551911 111.211001) (width 0.1) (layer "In9.Cu") (net 814))
  (arc (start 180.741395 94.93784) (mid 180.638882 95.185328) (end 180.741393 95.432814) (width 0.09) (layer "In9.Cu") (net 814))
  (arc (start 181.059593 94.407512) (mid 181.103527 94.513578) (end 181.059593 94.619644) (width 0.09) (layer "In9.Cu") (net 814))
  (arc (start 179.244288 93.935709) (mid 179.491776 94.038222) (end 179.739264 93.935711) (width 0.09) (layer "In9.Cu") (net 814))
  (arc (start 243.563257 110.775389) (mid 243.607191 110.881454) (end 243.563255 110.987521) (width 0.1) (layer "In9.Cu") (net 814))
  (arc (start 243.551911 111.211001) (mid 243.657977 111.254935) (end 243.764043 111.211001) (width 0.1) (layer "In9.Cu") (net 814))
  (arc (start 201.505 96.296594) (mid 201.556256 96.17285) (end 201.68 96.121594) (width 0.1) (layer "In9.Cu") (net 814))
  (arc (start 201.68 96.121594) (mid 201.803744 96.17285) (end 201.855 96.296594) (width 0.1) (layer "In9.Cu") (net 814))
  (segment (start 244.831999 112.547999) (end 245.182001 112.547999) (width 0.1) (layer "B.Cu") (net 814))
  (segment (start 244.65 112.366) (end 244.831999 112.547999) (width 0.1) (layer "B.Cu") (net 814))
  (segment (start 245.285 112.445) (end 245.285 112.065) (width 0.1) (layer "B.Cu") (net 814))
  (segment (start 245.182001 112.547999) (end 245.285 112.445) (width 0.1) (layer "B.Cu") (net 814))
  (segment (start 181.136328 91.560008) (end 180.636328 92.060008) (width 0.1) (layer "F.Cu") (net 815))
  (via (at 180.636328 92.060008) (size 0.5) (drill 0.2) (layers "F.Cu" "B.Cu") (net 815))
  (via (at 244.65 90.17) (size 0.5) (drill 0.2) (layers "F.Cu" "B.Cu") (net 815))
  (segment (start 196.275 96.537) (end 196.225 96.537) (width 0.1) (layer "In7.Cu") (net 815))
  (segment (start 193.887 97.012) (end 193.887 96.712) (width 0.1) (layer "In7.Cu") (net 815))
  (segment (start 185.902206 96.620115) (end 185.902206 96.620114) (width 0.1) (layer "In7.Cu") (net 815))
  (segment (start 185.301169 95.24126) (end 184.912262 95.630171) (width 0.1) (layer "In7.Cu") (net 815))
  (segment (start 185.796141 95.736232) (end 185.407234 96.125143) (width 0.1) (layer "In7.Cu") (net 815))
  (segment (start 197.025 96.537) (end 196.975 96.537) (width 0.1) (layer "In7.Cu") (net 815))
  (segment (start 198.6 95.862) (end 198.6 96.712) (width 0.1) (layer "In7.Cu") (net 815))
  (segment (start 185.407234 96.125143) (end 185.407234 96.125142) (width 0.1) (layer "In7.Cu") (net 815))
  (segment (start 241.75 90.5) (end 238.53 93.72) (width 0.1) (layer "In7.Cu") (net 815))
  (segment (start 202.353 93.72) (end 199.682446 96.390554) (width 0.1) (layer "In7.Cu") (net 815))
  (segment (start 184.355 94.684) (end 183.694634 94.684) (width 0.1) (layer "In7.Cu") (net 815))
  (segment (start 197.55 97.312) (end 197.55 95.862) (width 0.1) (layer "In7.Cu") (net 815))
  (segment (start 185.654719 96.372628) (end 186.04363 95.983721) (width 0.1) (layer "In7.Cu") (net 815))
  (segment (start 185.548658 95.488749) (end 185.548656 95.488748) (width 0.1) (layer "In7.Cu") (net 815))
  (segment (start 182.036328 92.894322) (end 181.608006 92.466) (width 0.1) (layer "In7.Cu") (net 815))
  (segment (start 183.035 94.024366) (end 183.035 93.68) (width 0.1) (layer "In7.Cu") (net 815))
  (segment (start 181.608006 92.466) (end 181.04232 92.466) (width 0.1) (layer "In7.Cu") (net 815))
  (segment (start 186.425 96.754) (end 186.220404 96.549404) (width 0.1) (layer "In7.Cu") (net 815))
  (segment (start 196.8 96.362) (end 196.8 95.962) (width 0.1) (layer "In7.Cu") (net 815))
  (segment (start 184.664775 95.382684) (end 185.053686 94.993777) (width 0.1) (layer "In7.Cu") (net 815))
  (segment (start 188.602 96.92) (end 188.436 96.754) (width 0.1) (layer "In7.Cu") (net 815))
  (segment (start 184.488 94.817) (end 184.355 94.684) (width 0.1) (layer "In7.Cu") (net 815))
  (segment (start 198.751 97.161) (end 198.75 97.162) (width 0.1) (layer "In7.Cu") (net 815))
  (segment (start 191.582314 96.537) (end 191.199314 96.92) (width 0.1) (layer "In7.Cu") (net 815))
  (segment (start 238.53 93.72) (end 202.353 93.72) (width 0.1) (layer "In7.Cu") (net 815))
  (segment (start 199.328893 96.537) (end 199.125 96.537) (width 0.1) (layer "In7.Cu") (net 815))
  (segment (start 197.2 95.862) (end 197.2 96.362) (width 0.1) (layer "In7.Cu") (net 815))
  (segment (start 198.786 97.161) (end 198.751 97.161) (width 0.1) (layer "In7.Cu") (net 815))
  (segment (start 185.972916 96.549404) (end 185.902206 96.620115) (width 0.1) (layer "In7.Cu") (net 815))
  (segment (start 198.75 96.862) (end 198.785 96.862) (width 0.1) (layer "In7.Cu") (net 815))
  (segment (start 182.815008 93.460008) (end 182.470642 93.460008) (width 0.1) (layer "In7.Cu") (net 815))
  (segment (start 183.035 93.68) (end 182.815008 93.460008) (width 0.1) (layer "In7.Cu") (net 815))
  (segment (start 184.912262 95.630171) (end 184.912262 95.63017) (width 0.1) (layer "In7.Cu") (net 815))
  (segment (start 196.45 95.962) (end 196.45 96.362) (width 0.1) (layer "In7.Cu") (net 815))
  (segment (start 184.664775 95.630171) (end 184.664775 95.630172) (width 0.1) (layer "In7.Cu") (net 815))
  (segment (start 183.694634 94.684) (end 183.035 94.024366) (width 0.1) (layer "In7.Cu") (net 815))
  (segment (start 193.537 96.712) (end 193.537 97.012) (width 0.1) (layer "In7.Cu") (net 815))
  (segment (start 194.237 96.712) (end 194.237 97.012) (width 0.1) (layer "In7.Cu") (net 815))
  (segment (start 195.35 96.362) (end 195.35 96.312) (width 0.1) (layer "In7.Cu") (net 815))
  (segment (start 184.806197 94.746289) (end 184.735488 94.817001) (width 0.1) (layer "In7.Cu") (net 815))
  (segment (start 198.95 96.362) (end 198.95 95.862) (width 0.1) (layer "In7.Cu") (net 815))
  (segment (start 195 96.312) (end 195 97.012) (width 0.1) (layer "In7.Cu") (net 815))
  (segment (start 196.05 96.362) (end 196.05 95.962) (width 0.1) (layer "In7.Cu") (net 815))
  (segment (start 194.65 97.012) (end 194.65 96.712) (width 0.1) (layer "In7.Cu") (net 815))
  (segment (start 185.548657 95.241261) (end 185.548659 95.241262) (width 0.1) (layer "In7.Cu") (net 815))
  (segment (start 185.053686 94.993777) (end 185.053684 94.993776) (width 0.1) (layer "In7.Cu") (net 815))
  (segment (start 198.785 96.862) (end 198.786 96.861) (width 0.1) (layer "In7.Cu") (net 815))
  (segment (start 186.043629 95.736233) (end 186.043631 95.736234) (width 0.1) (layer "In7.Cu") (net 815))
  (segment (start 197.9 95.862) (end 197.9 97.312) (width 0.1) (layer "In7.Cu") (net 815))
  (segment (start 194.475 96.537) (end 194.412 96.537) (width 0.1) (layer "In7.Cu") (net 815))
  (segment (start 181.04232 92.466) (end 180.636328 92.060008) (width 0.1) (layer "In7.Cu") (net 815))
  (segment (start 244.65 90.17) (end 244.32 90.5) (width 0.1) (layer "In7.Cu") (net 815))
  (segment (start 185.159747 96.125143) (end 185.159747 96.125144) (width 0.1) (layer "In7.Cu") (net 815))
  (segment (start 191.199314 96.92) (end 188.602 96.92) (width 0.1) (layer "In7.Cu") (net 815))
  (segment (start 182.470642 93.460008) (end 182.036328 93.025694) (width 0.1) (layer "In7.Cu") (net 815))
  (segment (start 185.159747 95.877656) (end 185.548658 95.488749) (width 0.1) (layer "In7.Cu") (net 815))
  (segment (start 184.735488 94.817001) (end 184.735487 94.816999) (width 0.1) (layer "In7.Cu") (net 815))
  (segment (start 195.7 95.962) (end 195.7 96.362) (width 0.1) (layer "In7.Cu") (net 815))
  (segment (start 186.04363 95.983721) (end 186.043628 95.98372) (width 0.1) (layer "In7.Cu") (net 815))
  (segment (start 198.25 97.312) (end 198.25 95.862) (width 0.1) (layer "In7.Cu") (net 815))
  (segment (start 182.036328 93.025694) (end 182.036328 92.894322) (width 0.1) (layer "In7.Cu") (net 815))
  (segment (start 188.436 96.754) (end 186.425 96.754) (width 0.1) (layer "In7.Cu") (net 815))
  (segment (start 193.012 96.537) (end 191.582314 96.537) (width 0.1) (layer "In7.Cu") (net 815))
  (segment (start 244.32 90.5) (end 241.75 90.5) (width 0.1) (layer "In7.Cu") (net 815))
  (segment (start 193.187 97.012) (end 193.187 96.712) (width 0.1) (layer "In7.Cu") (net 815))
  (segment (start 185.654719 96.620115) (end 185.654719 96.620116) (width 0.1) (layer "In7.Cu") (net 815))
  (arc (start 185.902206 96.620114) (mid 185.778463 96.671371) (end 185.654719 96.620115) (width 0.1) (layer "In7.Cu") (net 815))
  (arc (start 197.9 97.312) (mid 197.848744 97.435744) (end 197.725 97.487) (width 0.1) (layer "In7.Cu") (net 815))
  (arc (start 197.375 95.687) (mid 197.251256 95.738256) (end 197.2 95.862) (width 0.1) (layer "In7.Cu") (net 815))
  (arc (start 197.55 95.862) (mid 197.498744 95.738256) (end 197.375 95.687) (width 0.1) (layer "In7.Cu") (net 815))
  (arc (start 196.8 95.962) (mid 196.748744 95.838256) (end 196.625 95.787) (width 0.1) (layer "In7.Cu") (net 815))
  (arc (start 195.175 96.137) (mid 195.051256 96.188256) (end 195 96.312) (width 0.1) (layer "In7.Cu") (net 815))
  (arc (start 184.912262 95.63017) (mid 184.788519 95.681427) (end 184.664775 95.630171) (width 0.1) (layer "In7.Cu") (net 815))
  (arc (start 186.043628 95.98372) (mid 186.094885 95.859977) (end 186.043629 95.736233) (width 0.1) (layer "In7.Cu") (net 815))
  (arc (start 193.887 96.712) (mid 193.835744 96.588256) (end 193.712 96.537) (width 0.1) (layer "In7.Cu") (net 815))
  (arc (start 198.786 96.861) (mid 198.892066 96.904934) (end 198.936 97.011) (width 0.1) (layer "In7.Cu") (net 815))
  (arc (start 195 97.012) (mid 194.948744 97.135744) (end 194.825 97.187) (width 0.1) (layer "In7.Cu") (net 815))
  (arc (start 185.053684 94.993776) (mid 185.104941 94.870033) (end 185.053685 94.746289) (width 0.1) (layer "In7.Cu") (net 815))
  (arc (start 184.735487 94.816999) (mid 184.611744 94.868256) (end 184.488 94.817) (width 0.1) (layer "In7.Cu") (net 815))
  (arc (start 185.407234 96.125142) (mid 185.283491 96.176399) (end 185.159747 96.125143) (width 0.1) (layer "In7.Cu") (net 815))
  (arc (start 193.712 96.537) (mid 193.588256 96.588256) (end 193.537 96.712) (width 0.1) (layer "In7.Cu") (net 815))
  (arc (start 198.6 96.712) (mid 198.643934 96.818066) (end 198.75 96.862) (width 0.1) (layer "In7.Cu") (net 815))
  (arc (start 184.664775 95.630172) (mid 184.613519 95.506428) (end 184.664775 95.382684) (width 0.1) (layer "In7.Cu") (net 815))
  (arc (start 186.043631 95.736234) (mid 185.919887 95.684978) (end 185.796141 95.736232) (width 0.1) (layer "In7.Cu") (net 815))
  (arc (start 186.220404 96.549404) (mid 186.09666 96.498148) (end 185.972916 96.549404) (width 0.1) (layer "In7.Cu") (net 815))
  (arc (start 193.187 96.712) (mid 193.135744 96.588256) (end 193.012 96.537) (width 0.1) (layer "In7.Cu") (net 815))
  (arc (start 195.7 96.362) (mid 195.648744 96.485744) (end 195.525 96.537) (width 0.1) (layer "In7.Cu") (net 815))
  (arc (start 196.45 96.362) (mid 196.398744 96.485744) (end 196.275 96.537) (width 0.1) (layer "In7.Cu") (net 815))
  (arc (start 195.35 96.312) (mid 195.298744 96.188256) (end 195.175 96.137) (width 0.1) (layer "In7.Cu") (net 815))
  (arc (start 198.6 97.312) (mid 198.548744 97.435744) (end 198.425 97.487) (width 0.1) (layer "In7.Cu") (net 815))
  (arc (start 197.2 96.362) (mid 197.148744 96.485744) (end 197.025 96.537) (width 0.1) (layer "In7.Cu") (net 815))
  (arc (start 198.75 97.162) (mid 198.643934 97.205934) (end 198.6 97.312) (width 0.1) (layer "In7.Cu") (net 815))
  (arc (start 185.159747 96.125144) (mid 185.108491 96.0014) (end 185.159747 95.877656) (width 0.1) (layer "In7.Cu") (net 815))
  (arc (start 194.412 96.537) (mid 194.288256 96.588256) (end 194.237 96.712) (width 0.1) (layer "In7.Cu") (net 815))
  (arc (start 198.775 95.687) (mid 198.651256 95.738256) (end 198.6 95.862) (width 0.1) (layer "In7.Cu") (net 815))
  (arc (start 196.225 96.537) (mid 196.101256 96.485744) (end 196.05 96.362) (width 0.1) (layer "In7.Cu") (net 815))
  (arc (start 193.537 97.012) (mid 193.485744 97.135744) (end 193.362 97.187) (width 0.1) (layer "In7.Cu") (net 815))
  (arc (start 198.25 95.862) (mid 198.198744 95.738256) (end 198.075 95.687) (width 0.1) (layer "In7.Cu") (net 815))
  (arc (start 198.075 95.687) (mid 197.951256 95.738256) (end 197.9 95.862) (width 0.1) (layer "In7.Cu") (net 815))
  (arc (start 185.548656 95.488748) (mid 185.599913 95.365005) (end 185.548657 95.241261) (width 0.1) (layer "In7.Cu") (net 815))
  (arc (start 194.65 96.712) (mid 194.598744 96.588256) (end 194.475 96.537) (width 0.1) (layer "In7.Cu") (net 815))
  (arc (start 198.95 95.862) (mid 198.898744 95.738256) (end 198.775 95.687) (width 0.1) (layer "In7.Cu") (net 815))
  (arc (start 196.975 96.537) (mid 196.851256 96.485744) (end 196.8 96.362) (width 0.1) (layer "In7.Cu") (net 815))
  (arc (start 198.936 97.011) (mid 198.892066 97.117066) (end 198.786 97.161) (width 0.1) (layer "In7.Cu") (net 815))
  (arc (start 196.625 95.787) (mid 196.501256 95.838256) (end 196.45 95.962) (width 0.1) (layer "In7.Cu") (net 815))
  (arc (start 197.725 97.487) (mid 197.601256 97.435744) (end 197.55 97.312) (width 0.1) (layer "In7.Cu") (net 815))
  (arc (start 194.237 97.012) (mid 194.185744 97.135744) (end 194.062 97.187) (width 0.1) (layer "In7.Cu") (net 815))
  (arc (start 185.548659 95.241262) (mid 185.424915 95.190006) (end 185.301169 95.24126) (width 0.1) (layer "In7.Cu") (net 815))
  (arc (start 195.525 96.537) (mid 195.401256 96.485744) (end 195.35 96.362) (width 0.1) (layer "In7.Cu") (net 815))
  (arc (start 196.05 95.962) (mid 195.998744 95.838256) (end 195.875 95.787) (width 0.1) (layer "In7.Cu") (net 815))
  (arc (start 185.053685 94.746289) (mid 184.929941 94.695033) (end 184.806197 94.746289) (width 0.1) (layer "In7.Cu") (net 815))
  (arc (start 193.362 97.187) (mid 193.238256 97.135744) (end 193.187 97.012) (width 0.1) (layer "In7.Cu") (net 815))
  (arc (start 199.125 96.537) (mid 199.001256 96.485744) (end 198.95 96.362) (width 0.1) (layer "In7.Cu") (net 815))
  (arc (start 199.328893 96.537) (mid 199.520234 96.49894) (end 199.682446 96.390554) (width 0.1) (layer "In7.Cu") (net 815))
  (arc (start 198.425 97.487) (mid 198.301256 97.435744) (end 198.25 97.312) (width 0.1) (layer "In7.Cu") (net 815))
  (arc (start 185.654719 96.620116) (mid 185.603463 96.496372) (end 185.654719 96.372628) (width 0.1) (layer "In7.Cu") (net 815))
  (arc (start 194.825 97.187) (mid 194.701256 97.135744) (end 194.65 97.012) (width 0.1) (layer "In7.Cu") (net 815))
  (arc (start 194.062 97.187) (mid 193.938256 97.135744) (end 193.887 97.012) (width 0.1) (layer "In7.Cu") (net 815))
  (arc (start 195.875 95.787) (mid 195.751256 95.838256) (end 195.7 95.962) (width 0.1) (layer "In7.Cu") (net 815))
  (segment (start 244.831999 89.988001) (end 245.213001 89.988001) (width 0.1) (layer "B.Cu") (net 815))
  (segment (start 245.213001 89.988001) (end 245.285 90.06) (width 0.1) (layer "B.Cu") (net 815))
  (segment (start 245.285 90.475) (end 245.285 90.06) (width 0.1) (layer "B.Cu") (net 815))
  (segment (start 244.65 90.17) (end 244.831999 89.988001) (width 0.1) (layer "B.Cu") (net 815))
  (segment (start 180.136328 91.560008) (end 179.636328 92.060008) (width 0.1) (layer "F.Cu") (net 816))
  (via (at 245.92 110.49) (size 0.5) (drill 0.2) (layers "F.Cu" "B.Cu") (net 816))
  (via (at 179.636328 92.060008) (size 0.5) (drill 0.2) (layers "F.Cu" "B.Cu") (net 816))
  (segment (start 238.448477 97.948476) (end 238.801654 97.595298) (width 0.1) (layer "In9.Cu") (net 816))
  (segment (start 242.65 106.187866) (end 243.912134 107.45) (width 0.1) (layer "In9.Cu") (net 816))
  (segment (start 187.758578 94.6) (end 188.041347 94.317231) (width 0.09) (layer "In9.Cu") (net 816))
  (segment (start 190.882778 93.465027) (end 190.993476 93.575725) (width 0.09) (layer "In9.Cu") (net 816))
  (segment (start 188.041347 94.317231) (end 188.041347 93.813558) (width 0.09) (layer "In9.Cu") (net 816))
  (segment (start 188.389878 93.465027) (end 190.882778 93.465027) (width 0.09) (layer "In9.Cu") (net 816))
  (segment (start 239.79085 97.878138) (end 239.791602 97.87889) (width 0.1) (layer "In9.Cu") (net 816))
  (segment (start 181.24 92.778578) (end 181.24 93.698578) (width 0.09) (layer "In9.Cu") (net 816))
  (segment (start 237.810578 95.897867) (end 237.81133 95.898619) (width 0.1) (layer "In9.Cu") (net 816))
  (segment (start 238.095297 98.583743) (end 238.095297 98.583742) (width 0.1) (layer "In9.Cu") (net 816))
  (segment (start 192.22 93.53) (end 196.352134 93.53) (width 0.1) (layer "In9.Cu") (net 816))
  (segment (start 239.791602 98.585246) (end 239.685536 98.691313) (width 0.1) (layer "In9.Cu") (net 816))
  (segment (start 199.893134 95.181) (end 235.893134 95.181) (width 0.1) (layer "In9.Cu") (net 816))
  (segment (start 245.662134 107.45) (end 246.883 108.670866) (width 0.1) (layer "In9.Cu") (net 816))
  (segment (start 197.422134 94.6) (end 199.312134 94.6) (width 0.1) (layer "In9.Cu") (net 816))
  (segment (start 192.218209 93.531791) (end 192.22 93.53) (width 0.09) (layer "In9.Cu") (net 816))
  (segment (start 180.640483 92.465027) (end 180.640984 92.465528) (width 0.09) (layer "In9.Cu") (net 816))
  (segment (start 237.458527 96.958527) (end 237.105349 97.311705) (width 0.1) (layer "In9.Cu") (net 816))
  (segment (start 180.640984 92.465528) (end 180.92695 92.465528) (width 0.09) (layer "In9.Cu") (net 816))
  (segment (start 238.095297 98.583742) (end 238.096049 98.584494) (width 0.1) (layer "In9.Cu") (net 816))
  (segment (start 179.06 92.42) (end 179.105027 92.465027) (width 0.09) (layer "In9.Cu") (net 816))
  (segment (start 179.06 92.2) (end 179.06 92.42) (width 0.09) (layer "In9.Cu") (net 816))
  (segment (start 237.81133 96.604975) (end 237.705262 96.71104) (width 0.1) (layer "In9.Cu") (net 816))
  (segment (start 246.883 108.670866) (end 246.883 109.829134) (width 0.1) (layer "In9.Cu") (net 816))
  (segment (start 242.65 101.937866) (end 242.65 106.187866) (width 0.1) (layer "In9.Cu") (net 816))
  (segment (start 236.998157 96.003934) (end 236.998155 96.003933) (width 0.1) (layer "In9.Cu") (net 816))
  (segment (start 238.800902 96.88819) (end 238.801654 96.888942) (width 0.1) (layer "In9.Cu") (net 816))
  (segment (start 239.685535 98.973401) (end 242.65 101.937866) (width 0.1) (layer "In9.Cu") (net 816))
  (segment (start 238.448477 97.948476) (end 238.448475 97.948475) (width 0.1) (layer "In9.Cu") (net 816))
  (segment (start 180.92695 92.465528) (end 181.24 92.778578) (width 0.09) (layer "In9.Cu") (net 816))
  (segment (start 238.448475 97.948475) (end 238.095297 98.301653) (width 0.1) (layer "In9.Cu") (net 816))
  (segment (start 239.685535 98.973402) (end 239.685535 98.973401) (width 0.1) (layer "In9.Cu") (net 816))
  (segment (start 179.199992 92.060008) (end 179.06 92.2) (width 0.09) (layer "In9.Cu") (net 816))
  (segment (start 238.378138 98.584494) (end 238.872359 98.09027) (width 0.1) (layer "In9.Cu") (net 816))
  (segment (start 179.636328 92.060008) (end 179.199992 92.060008) (width 0.09) (layer "In9.Cu") (net 816))
  (segment (start 237.105349 97.593795) (end 237.105349 97.593794) (width 0.1) (layer "In9.Cu") (net 816))
  (segment (start 181.24 93.698578) (end 182.141422 94.6) (width 0.09) (layer "In9.Cu") (net 816))
  (segment (start 179.105027 92.465027) (end 180.640483 92.465027) (width 0.09) (layer "In9.Cu") (net 816))
  (segment (start 243.912134 107.45) (end 245.662134 107.45) (width 0.1) (layer "In9.Cu") (net 816))
  (segment (start 238.378138 98.584493) (end 238.378138 98.584494) (width 0.1) (layer "In9.Cu") (net 816))
  (segment (start 238.872359 98.09027) (end 239.084494 97.878138) (width 0.1) (layer "In9.Cu") (net 816))
  (segment (start 246.404133 110.308001) (end 246.101999 110.308001) (width 0.1) (layer "In9.Cu") (net 816))
  (segment (start 237.458151 96.958151) (end 237.458527 96.958527) (width 0.1) (layer "In9.Cu") (net 816))
  (segment (start 188.041347 93.813558) (end 188.389878 93.465027) (width 0.09) (layer "In9.Cu") (net 816))
  (segment (start 190.993476 93.575725) (end 192.112143 93.575725) (width 0.09) (layer "In9.Cu") (net 816))
  (segment (start 196.352134 93.53) (end 197.422134 94.6) (width 0.1) (layer "In9.Cu") (net 816))
  (segment (start 237.38819 97.594545) (end 237.38819 97.594546) (width 0.1) (layer "In9.Cu") (net 816))
  (segment (start 237.105349 97.593794) (end 237.106101 97.594546) (width 0.1) (layer "In9.Cu") (net 816))
  (segment (start 237.705262 96.71104) (end 237.458151 96.958151) (width 0.1) (layer "In9.Cu") (net 816))
  (segment (start 246.883 109.829134) (end 246.404133 110.308001) (width 0.1) (layer "In9.Cu") (net 816))
  (segment (start 235.893134 95.181) (end 236.716065 96.003932) (width 0.1) (layer "In9.Cu") (net 816))
  (segment (start 236.998155 96.003933) (end 237.104222 95.897867) (width 0.1) (layer "In9.Cu") (net 816))
  (segment (start 237.38819 97.594546) (end 238.094546 96.88819) (width 0.1) (layer "In9.Cu") (net 816))
  (segment (start 199.312134 94.6) (end 199.893134 95.181) (width 0.1) (layer "In9.Cu") (net 816))
  (segment (start 182.141422 94.6) (end 187.758578 94.6) (width 0.09) (layer "In9.Cu") (net 816))
  (segment (start 246.101999 110.308001) (end 245.92 110.49) (width 0.1) (layer "In9.Cu") (net 816))
  (arc (start 239.791602 97.87889) (mid 239.937894 98.232069) (end 239.791602 98.585246) (width 0.1) (layer "In9.Cu") (net 816))
  (arc (start 238.095297 98.301653) (mid 238.036874 98.442698) (end 238.095297 98.583743) (width 0.1) (layer "In9.Cu") (net 816))
  (arc (start 238.096049 98.584494) (mid 238.237094 98.642916) (end 238.378138 98.584493) (width 0.1) (layer "In9.Cu") (net 816))
  (arc (start 238.094546 96.88819) (mid 238.447723 96.741898) (end 238.800902 96.88819) (width 0.1) (layer "In9.Cu") (net 816))
  (arc (start 239.685536 98.691313) (mid 239.627112 98.832356) (end 239.685535 98.973402) (width 0.1) (layer "In9.Cu") (net 816))
  (arc (start 238.801654 96.888942) (mid 238.947946 97.242121) (end 238.801654 97.595298) (width 0.1) (layer "In9.Cu") (net 816))
  (arc (start 237.104222 95.897867) (mid 237.457399 95.751575) (end 237.810578 95.897867) (width 0.1) (layer "In9.Cu") (net 816))
  (arc (start 237.105349 97.311705) (mid 237.046926 97.45275) (end 237.105349 97.593795) (width 0.1) (layer "In9.Cu") (net 816))
  (arc (start 239.084494 97.878138) (mid 239.437671 97.731846) (end 239.79085 97.878138) (width 0.1) (layer "In9.Cu") (net 816))
  (arc (start 237.81133 95.898619) (mid 237.95762 96.251796) (end 237.81133 96.604975) (width 0.1) (layer "In9.Cu") (net 816))
  (arc (start 236.716065 96.003932) (mid 236.857112 96.062357) (end 236.998157 96.003934) (width 0.1) (layer "In9.Cu") (net 816))
  (arc (start 192.112143 93.575725) (mid 192.169546 93.564307) (end 192.218209 93.531791) (width 0.09) (layer "In9.Cu") (net 816))
  (arc (start 237.106101 97.594546) (mid 237.247146 97.652968) (end 237.38819 97.594545) (width 0.1) (layer "In9.Cu") (net 816))
  (segment (start 246.555 110.38) (end 246.555 110.795) (width 0.1) (layer "B.Cu") (net 816))
  (segment (start 246.483001 110.308001) (end 246.555 110.38) (width 0.1) (layer "B.Cu") (net 816))
  (segment (start 246.101999 110.308001) (end 246.483001 110.308001) (width 0.1) (layer "B.Cu") (net 816))
  (segment (start 245.92 110.49) (end 246.101999 110.308001) (width 0.1) (layer "B.Cu") (net 816))
  (segment (start 154.79 104.86) (end 154.54 104.61) (width 0.1) (layer "F.Cu") (net 824))
  (segment (start 155.5375 108.4475) (end 155.5375 107.464278) (width 0.1) (layer "F.Cu") (net 824))
  (segment (start 154.79 106.716778) (end 154.79 104.86) (width 0.1) (layer "F.Cu") (net 824))
  (segment (start 155.5375 107.464278) (end 154.79 106.716778) (width 0.1) (layer "F.Cu") (net 824))
  (segment (start 155.275 108.71) (end 155.5375 108.4475) (width 0.1) (layer "F.Cu") (net 824))
  (segment (start 156.05 108.71) (end 155.7875 108.4475) (width 0.1) (layer "F.Cu") (net 825))
  (segment (start 155.7875 108.4475) (end 155.7875 107.360722) (width 0.1) (layer "F.Cu") (net 825))
  (segment (start 155.04 104.86) (end 155.29 104.61) (width 0.1) (layer "F.Cu") (net 825))
  (segment (start 155.04 106.613222) (end 155.04 104.86) (width 0.1) (layer "F.Cu") (net 825))
  (segment (start 155.7875 107.360722) (end 155.04 106.613222) (width 0.1) (layer "F.Cu") (net 825))
  (segment (start 158.0475 107.014278) (end 157.31 106.276778) (width 0.1) (layer "F.Cu") (net 826))
  (segment (start 158.0475 108.4625) (end 157.8 108.71) (width 0.1) (layer "F.Cu") (net 826))
  (segment (start 158.0475 107.014278) (end 158.0475 108.4625) (width 0.1) (layer "F.Cu") (net 826))
  (segment (start 157.31 106.276778) (end 157.31 104.86) (width 0.1) (layer "F.Cu") (net 826))
  (segment (start 157.31 104.86) (end 157.06 104.61) (width 0.1) (layer "F.Cu") (net 826))
  (segment (start 158.2975 106.910722) (end 157.56 106.173222) (width 0.1) (layer "F.Cu") (net 827))
  (segment (start 158.2975 108.4625) (end 158.55 108.715) (width 0.1) (layer "F.Cu") (net 827))
  (segment (start 158.2975 106.910722) (end 158.2975 108.4625) (width 0.1) (layer "F.Cu") (net 827))
  (segment (start 157.56 106.173222) (end 157.56 104.86) (width 0.1) (layer "F.Cu") (net 827))
  (segment (start 157.56 104.86) (end 157.81 104.61) (width 0.1) (layer "F.Cu") (net 827))
  (segment (start 161.05 106.826778) (end 159.825 105.601778) (width 0.1) (layer "F.Cu") (net 828))
  (segment (start 160.8 108.71) (end 161.05 108.46) (width 0.1) (layer "F.Cu") (net 828))
  (segment (start 161.05 108.46) (end 161.05 106.826778) (width 0.1) (layer "F.Cu") (net 828))
  (segment (start 159.825 104.87) (end 159.575 104.62) (width 0.1) (layer "F.Cu") (net 828))
  (segment (start 159.825 105.601778) (end 159.825 104.87) (width 0.1) (layer "F.Cu") (net 828))
  (segment (start 161.3 106.723222) (end 160.075 105.498222) (width 0.1) (layer "F.Cu") (net 829))
  (segment (start 160.075 105.498222) (end 160.075 104.87) (width 0.1) (layer "F.Cu") (net 829))
  (segment (start 161.55 108.71) (end 161.3 108.46) (width 0.1) (layer "F.Cu") (net 829))
  (segment (start 161.3 108.46) (end 161.3 106.723222) (width 0.1) (layer "F.Cu") (net 829))
  (segment (start 160.075 104.87) (end 160.325 104.62) (width 0.1) (layer "F.Cu") (net 829))
  (segment (start 161.325 105.331778) (end 163.535 107.541778) (width 0.1) (layer "F.Cu") (net 830))
  (segment (start 161.325 104.86) (end 161.325 105.331778) (width 0.1) (layer "F.Cu") (net 830))
  (segment (start 163.535 107.541778) (end 163.535 108.445) (width 0.1) (layer "F.Cu") (net 830))
  (segment (start 163.535 108.445) (end 163.28 108.7) (width 0.1) (layer "F.Cu") (net 830))
  (segment (start 161.075 104.61) (end 161.325 104.86) (width 0.1) (layer "F.Cu") (net 830))
  (segment (start 161.575 104.86) (end 161.575 105.228222) (width 0.1) (layer "F.Cu") (net 831))
  (segment (start 161.575 105.228222) (end 163.785 107.438222) (width 0.1) (layer "F.Cu") (net 831))
  (segment (start 161.825 104.61) (end 161.575 104.86) (width 0.1) (layer "F.Cu") (net 831))
  (segment (start 163.785 108.445) (end 164.04 108.7) (width 0.1) (layer "F.Cu") (net 831))
  (segment (start 163.785 107.438222) (end 163.785 108.445) (width 0.1) (layer "F.Cu") (net 831))
  (segment (start 123.2 89.14) (end 123.2 88.9) (width 0.127) (layer "F.Cu") (net 832))
  (via (at 123.2 88.9) (size 0.5) (drill 0.2) (layers "F.Cu" "B.Cu") (net 832))
  (segment (start 121.82513 87.879) (end 121.629 87.879) (width 0.127) (layer "B.Cu") (net 832))
  (segment (start 124.1635 88.30737) (end 124.1635 87.306153) (width 0.127) (layer "B.Cu") (net 832))
  (segment (start 123.2 88.9) (end 123.5615 88.5385) (width 0.127) (layer "B.Cu") (net 832))
  (segment (start 123.5615 88.5385) (end 123.93237 88.5385) (width 0.127) (layer "B.Cu") (net 832))
  (segment (start 121.5175 87.7675) (end 121.0225 87.7675) (width 0.127) (layer "B.Cu") (net 832))
  (segment (start 122.76763 86.9365) (end 121.82513 87.879) (width 0.127) (layer "B.Cu") (net 832))
  (segment (start 123.93237 88.5385) (end 124.1635 88.30737) (width 0.127) (layer "B.Cu") (net 832))
  (segment (start 121.629 87.879) (end 121.5175 87.7675) (width 0.127) (layer "B.Cu") (net 832))
  (segment (start 124.1635 87.306153) (end 123.793847 86.9365) (width 0.127) (layer "B.Cu") (net 832))
  (segment (start 123.793847 86.9365) (end 122.76763 86.9365) (width 0.127) (layer "B.Cu") (net 832))
  (segment (start 119.675 84.24) (end 119.675 84) (width 0.127) (layer "F.Cu") (net 833))
  (via (at 119.675 84) (size 0.5) (drill 0.2) (layers "F.Cu" "B.Cu") (net 833))
  (segment (start 120.0375 83.6375) (end 120.560722 83.6375) (width 0.1) (layer "B.Cu") (net 833))
  (segment (start 119.81 86.565) (end 119.81 87.055) (width 0.1) (layer "B.Cu") (net 833))
  (segment (start 119.935 86.44) (end 119.81 86.565) (width 0.1) (layer "B.Cu") (net 833))
  (segment (start 120.75 84.523222) (end 119.935 85.338222) (width 0.1) (layer "B.Cu") (net 833))
  (segment (start 120.546453 84.325) (end 120.6 84.325) (width 0.1) (layer "B.Cu") (net 833))
  (segment (start 120.75 83.826778) (end 120.75 83.875) (width 0.1) (layer "B.Cu") (net 833))
  (segment (start 119.675 84) (end 120.0375 83.6375) (width 0.1) (layer "B.Cu") (net 833))
  (segment (start 120.75 84.475) (end 120.75 84.523222) (width 0.1) (layer "B.Cu") (net 833))
  (segment (start 120.6 84.025) (end 120.546453 84.025) (width 0.1) (layer "B.Cu") (net 833))
  (segment (start 119.935 85.338222) (end 119.935 86.44) (width 0.1) (layer "B.Cu") (net 833))
  (segment (start 120.560722 83.6375) (end 120.75 83.826778) (width 0.1) (layer "B.Cu") (net 833))
  (arc (start 120.396453 84.175) (mid 120.440387 84.281066) (end 120.546453 84.325) (width 0.1) (layer "B.Cu") (net 833))
  (arc (start 120.6 84.325) (mid 120.706066 84.368934) (end 120.75 84.475) (width 0.1) (layer "B.Cu") (net 833))
  (arc (start 120.546453 84.025) (mid 120.440387 84.068934) (end 120.396453 84.175) (width 0.1) (layer "B.Cu") (net 833))
  (arc (start 120.75 83.875) (mid 120.706066 83.981066) (end 120.6 84.025) (width 0.1) (layer "B.Cu") (net 833))
  (segment (start 112.45 92.203) (end 112.45 91.9) (width 0.127) (layer "F.Cu") (net 834))
  (via (at 112.45 91.9) (size 0.5) (drill 0.2) (layers "F.Cu" "B.Cu") (net 834))
  (segment (start 117.5825 87.7675) (end 118.0975 87.7675) (width 0.127) (layer "B.Cu") (net 834))
  (segment (start 111.0115 91.25737) (end 111.0115 90.34263) (width 0.127) (layer "B.Cu") (net 834))
  (segment (start 114.46763 89.4115) (end 116.00013 87.879) (width 0.127) (layer "B.Cu") (net 834))
  (segment (start 116.00013 87.879) (end 117.471 87.879) (width 0.127) (layer "B.Cu") (net 834))
  (segment (start 111.0115 90.34263) (end 111.94263 89.4115) (width 0.127) (layer "B.Cu") (net 834))
  (segment (start 112.45 91.9) (end 112.1635 91.6135) (width 0.127) (layer "B.Cu") (net 834))
  (segment (start 111.94263 89.4115) (end 114.46763 89.4115) (width 0.127) (layer "B.Cu") (net 834))
  (segment (start 111.36763 91.6135) (end 111.0115 91.25737) (width 0.127) (layer "B.Cu") (net 834))
  (segment (start 112.1635 91.6135) (end 111.36763 91.6135) (width 0.127) (layer "B.Cu") (net 834))
  (segment (start 117.471 87.879) (end 117.5825 87.7675) (width 0.127) (layer "B.Cu") (net 834))
  (segment (start 119.65 82.76) (end 119.65 83) (width 0.127) (layer "F.Cu") (net 835))
  (via (at 119.65 83) (size 0.5) (drill 0.2) (layers "F.Cu" "B.Cu") (net 835))
  (segment (start 120.185 85.441778) (end 120.185 86.435) (width 0.1) (layer "B.Cu") (net 835))
  (segment (start 120.31 86.56) (end 120.31 87.055) (width 0.1) (layer "B.Cu") (net 835))
  (segment (start 121 84.626778) (end 120.185 85.441778) (width 0.1) (layer "B.Cu") (net 835))
  (segment (start 121 83.723222) (end 121 84.626778) (width 0.1) (layer "B.Cu") (net 835))
  (segment (start 120.0375 83.3875) (end 120.664278 83.3875) (width 0.1) (layer "B.Cu") (net 835))
  (segment (start 120.185 86.435) (end 120.31 86.56) (width 0.1) (layer "B.Cu") (net 835))
  (segment (start 119.65 83) (end 120.0375 83.3875) (width 0.1) (layer "B.Cu") (net 835))
  (segment (start 120.664278 83.3875) (end 121 83.723222) (width 0.1) (layer "B.Cu") (net 835))
  (segment (start 123.2 87.657) (end 123.2 87.9) (width 0.127) (layer "F.Cu") (net 836))
  (via (at 123.2 87.9) (size 0.5) (drill 0.2) (layers "F.Cu" "B.Cu") (net 836))
  (segment (start 123.8865 87.420893) (end 123.679107 87.2135) (width 0.127) (layer "B.Cu") (net 836))
  (segment (start 122.88237 87.2135) (end 122.480409 87.615458) (width 0.127) (layer "B.Cu") (net 836))
  (segment (start 123.2 87.9) (end 123.5615 88.2615) (width 0.127) (layer "B.Cu") (net 836))
  (segment (start 121.5325 88.2675) (end 121.0225 88.2675) (width 0.127) (layer "B.Cu") (net 836))
  (segment (start 123.5615 88.2615) (end 123.81763 88.2615) (width 0.127) (layer "B.Cu") (net 836))
  (segment (start 121.93987 88.156) (end 121.644 88.156) (width 0.127) (layer "B.Cu") (net 836))
  (segment (start 121.985435 88.110435) (end 121.93987 88.156) (width 0.127) (layer "B.Cu") (net 836))
  (segment (start 121.644 88.156) (end 121.5325 88.2675) (width 0.127) (layer "B.Cu") (net 836))
  (segment (start 123.8865 88.19263) (end 123.8865 87.420893) (width 0.127) (layer "B.Cu") (net 836))
  (segment (start 122.480409 87.862946) (end 122.663661 88.046198) (width 0.127) (layer "B.Cu") (net 836))
  (segment (start 122.416173 88.293686) (end 122.232922 88.110435) (width 0.127) (layer "B.Cu") (net 836))
  (segment (start 123.679107 87.2135) (end 122.88237 87.2135) (width 0.127) (layer "B.Cu") (net 836))
  (segment (start 122.232922 88.110435) (end 122.232921 88.110435) (width 0.127) (layer "B.Cu") (net 836))
  (segment (start 123.81763 88.2615) (end 123.8865 88.19263) (width 0.127) (layer "B.Cu") (net 836))
  (arc (start 122.663661 88.293686) (mid 122.539917 88.344942) (end 122.416173 88.293686) (width 0.127) (layer "B.Cu") (net 836))
  (arc (start 122.663661 88.046198) (mid 122.714917 88.169942) (end 122.663661 88.293686) (width 0.127) (layer "B.Cu") (net 836))
  (arc (start 122.480409 87.615458) (mid 122.429153 87.739202) (end 122.480409 87.862946) (width 0.127) (layer "B.Cu") (net 836))
  (arc (start 122.232921 88.110435) (mid 122.109178 88.059179) (end 121.985435 88.110435) (width 0.127) (layer "B.Cu") (net 836))
  (segment (start 112.425 90.797) (end 112.425 91.075) (width 0.127) (layer "F.Cu") (net 837))
  (via (at 112.425 91.075) (size 0.5) (drill 0.2) (layers "F.Cu" "B.Cu") (net 837))
  (segment (start 111.535987 90.45737) (end 111.587141 90.508524) (width 0.127) (layer "B.Cu") (net 837))
  (segment (start 111.783474 89.962394) (end 111.783473 89.962394) (width 0.127) (layer "B.Cu") (net 837))
  (segment (start 117.4385 88.156) (end 117.55 88.2675) (width 0.127) (layer "B.Cu") (net 837))
  (segment (start 111.48237 91.3365) (end 111.2885 91.14263) (width 0.127) (layer "B.Cu") (net 837))
  (segment (start 117.55 88.2675) (end 118.0975 88.2675) (width 0.127) (layer "B.Cu") (net 837))
  (segment (start 112.425 91.075) (end 112.1635 91.3365) (width 0.127) (layer "B.Cu") (net 837))
  (segment (start 112.1635 91.3365) (end 111.48237 91.3365) (width 0.127) (layer "B.Cu") (net 837))
  (segment (start 112.9385 89.6885) (end 114.58237 89.6885) (width 0.127) (layer "B.Cu") (net 837))
  (segment (start 114.58237 89.6885) (end 116.11487 88.156) (width 0.127) (layer "B.Cu") (net 837))
  (segment (start 116.11487 88.156) (end 117.4385 88.156) (width 0.127) (layer "B.Cu") (net 837))
  (segment (start 112.4135 89.8635) (end 112.4135 89.868204) (width 0.127) (layer "B.Cu") (net 837))
  (segment (start 111.834628 90.261036) (end 111.783473 90.209881) (width 0.127) (layer "B.Cu") (net 837))
  (segment (start 112.05737 89.6885) (end 112.2385 89.6885) (width 0.127) (layer "B.Cu") (net 837))
  (segment (start 111.2885 91.14263) (end 111.2885 90.45737) (width 0.127) (layer "B.Cu") (net 837))
  (segment (start 111.783473 89.962394) (end 112.05737 89.6885) (width 0.127) (layer "B.Cu") (net 837))
  (segment (start 111.535986 90.45737) (end 111.535987 90.45737) (width 0.127) (layer "B.Cu") (net 837))
  (segment (start 111.834628 90.508523) (end 111.834628 90.508524) (width 0.127) (layer "B.Cu") (net 837))
  (segment (start 112.7635 89.868204) (end 112.7635 89.8635) (width 0.127) (layer "B.Cu") (net 837))
  (arc (start 111.587141 90.508524) (mid 111.710885 90.55978) (end 111.834628 90.508523) (width 0.127) (layer "B.Cu") (net 837))
  (arc (start 112.5885 90.043204) (mid 112.712244 89.991948) (end 112.7635 89.868204) (width 0.127) (layer "B.Cu") (net 837))
  (arc (start 111.834628 90.508524) (mid 111.885884 90.38478) (end 111.834628 90.261036) (width 0.127) (layer "B.Cu") (net 837))
  (arc (start 112.4135 89.868204) (mid 112.464756 89.991948) (end 112.5885 90.043204) (width 0.127) (layer "B.Cu") (net 837))
  (arc (start 111.783473 90.209881) (mid 111.732217 90.086137) (end 111.783474 89.962394) (width 0.127) (layer "B.Cu") (net 837))
  (arc (start 112.7635 89.8635) (mid 112.814756 89.739756) (end 112.9385 89.6885) (width 0.127) (layer "B.Cu") (net 837))
  (arc (start 111.2885 90.45737) (mid 111.412243 90.406114) (end 111.535986 90.45737) (width 0.127) (layer "B.Cu") (net 837))
  (arc (start 112.2385 89.6885) (mid 112.362244 89.739756) (end 112.4135 89.8635) (width 0.127) (layer "B.Cu") (net 837))
  (segment (start 131.6 100.24) (end 131.6 100) (width 0.127) (layer "F.Cu") (net 838))
  (via (at 131.6 100) (size 0.5) (drill 0.2) (layers "F.Cu" "B.Cu") (net 838))
  (segment (start 131.675 99.625) (end 132.351778 99.625) (width 0.1) (layer "B.Cu") (net 838))
  (segment (start 132.725 99.251778) (end 132.725 98.148222) (width 0.1) (layer "B.Cu") (net 838))
  (segment (start 132.725 98.148222) (end 131.951778 97.375) (width 0.1) (layer "B.Cu") (net 838))
  (segment (start 126.425 92.875) (end 126.55 92.75) (width 0.1) (layer "B.Cu") (net 838))
  (segment (start 129.32087 97.375) (end 126.425 94.47913) (width 0.1) (layer "B.Cu") (net 838))
  (segment (start 126.425 94.47913) (end 126.425 92.875) (width 0.1) (layer "B.Cu") (net 838))
  (segment (start 131.6 99.7) (end 131.675 99.625) (width 0.1) (layer "B.Cu") (net 838))
  (segment (start 132.351778 99.625) (end 132.725 99.251778) (width 0.1) (layer "B.Cu") (net 838))
  (segment (start 131.6 100) (end 131.6 99.7) (width 0.1) (layer "B.Cu") (net 838))
  (segment (start 126.55 92.75) (end 126.55 92.2625) (width 0.1) (layer "B.Cu") (net 838))
  (segment (start 131.951778 97.375) (end 129.32087 97.375) (width 0.1) (layer "B.Cu") (net 838))
  (segment (start 112.993 108.95) (end 112.75 108.95) (width 0.127) (layer "F.Cu") (net 839))
  (via (at 112.75 108.95) (size 0.5) (drill 0.2) (layers "F.Cu" "B.Cu") (net 839))
  (segment (start 114.876778 95.225) (end 113.338389 96.763389) (width 0.1) (layer "B.Cu") (net 839))
  (segment (start 112.843415 97.258365) (end 112.843415 97.258366) (width 0.1) (layer "B.Cu") (net 839))
  (segment (start 112.399503 108.597725) (end 112.399503 108.899503) (width 0.1) (layer "B.Cu") (net 839))
  (segment (start 124.85 91.55) (end 124.725 91.425) (width 0.1) (layer "B.Cu") (net 839))
  (segment (start 113.096109 97.263572) (end 113.096109 97.263571) (width 0.1) (layer "B.Cu") (net 839))
  (segment (start 122.851778 93.225) (end 117.601778 93.225) (width 0.1) (layer "B.Cu") (net 839))
  (segment (start 110.7 99.401778) (end 110.7 107.523222) (width 0.1) (layer "B.Cu") (net 839))
  (segment (start 115.601778 95.225) (end 114.876778 95.225) (width 0.1) (layer "B.Cu") (net 839))
  (segment (start 112.45 108.95) (end 112.75 108.95) (width 0.1) (layer "B.Cu") (net 839))
  (segment (start 110.7 107.523222) (end 111.326778 108.15) (width 0.1) (layer "B.Cu") (net 839))
  (segment (start 113.343596 97.263572) (end 113.343595 97.263572) (width 0.1) (layer "B.Cu") (net 839))
  (segment (start 113.096109 97.263571) (end 113.090903 97.258365) (width 0.1) (layer "B.Cu") (net 839))
  (segment (start 124.725 91.425) (end 124.651778 91.425) (width 0.1) (layer "B.Cu") (net 839))
  (segment (start 124.651778 91.425) (end 122.851778 93.225) (width 0.1) (layer "B.Cu") (net 839))
  (segment (start 113.338389 97.010877) (end 113.343596 97.016084) (width 0.1) (layer "B.Cu") (net 839))
  (segment (start 111.951778 108.15) (end 112.399503 108.597725) (width 0.1) (layer "B.Cu") (net 839))
  (segment (start 112.399503 108.899503) (end 112.45 108.95) (width 0.1) (layer "B.Cu") (net 839))
  (segment (start 117.601778 93.225) (end 115.601778 95.225) (width 0.1) (layer "B.Cu") (net 839))
  (segment (start 111.326778 108.15) (end 111.951778 108.15) (width 0.1) (layer "B.Cu") (net 839))
  (segment (start 112.843415 97.258366) (end 110.7 99.401778) (width 0.1) (layer "B.Cu") (net 839))
  (segment (start 125.3375 91.55) (end 124.85 91.55) (width 0.1) (layer "B.Cu") (net 839))
  (arc (start 113.338389 96.763389) (mid 113.287133 96.887133) (end 113.338389 97.010877) (width 0.1) (layer "B.Cu") (net 839))
  (arc (start 113.343596 97.016084) (mid 113.394852 97.139828) (end 113.343596 97.263572) (width 0.1) (layer "B.Cu") (net 839))
  (arc (start 113.090903 97.258365) (mid 112.967159 97.207109) (end 112.843415 97.258365) (width 0.1) (layer "B.Cu") (net 839))
  (arc (start 113.343595 97.263572) (mid 113.219853 97.314827) (end 113.096109 97.263572) (width 0.1) (layer "B.Cu") (net 839))
  (segment (start 130.7 84.133) (end 130.7 83.9) (width 0.127) (layer "F.Cu") (net 840))
  (via (at 130.7 83.9) (size 0.5) (drill 0.2) (layers "F.Cu" "B.Cu") (net 840))
  (segment (start 128.85 91.425) (end 128.725 91.55) (width 0.1) (layer "B.Cu") (net 840))
  (segment (start 130.126934 83.524844) (end 130.05 83.601778) (width 0.1) (layer "B.Cu") (net 840))
  (segment (start 130.7 83.6) (end 130.624844 83.524844) (width 0.1) (layer "B.Cu") (net 840))
  (segment (start 130.05 83.601778) (end 130.05 90.401778) (width 0.1) (layer "B.Cu") (net 840))
  (segment (start 129.026778 91.425) (end 128.85 91.425) (width 0.1) (layer "B.Cu") (net 840))
  (segment (start 130.624844 83.524844) (end 130.126934 83.524844) (width 0.1) (layer "B.Cu") (net 840))
  (segment (start 130.7 83.9) (end 130.7 83.6) (width 0.1) (layer "B.Cu") (net 840))
  (segment (start 130.05 90.401778) (end 129.026778 91.425) (width 0.1) (layer "B.Cu") (net 840))
  (segment (start 128.725 91.55) (end 128.2625 91.55) (width 0.1) (layer "B.Cu") (net 840))
  (segment (start 143.157 83.7) (end 143.4 83.7) (width 0.127) (layer "F.Cu") (net 841))
  (via (at 143.4 83.7) (size 0.5) (drill 0.2) (layers "F.Cu" "B.Cu") (net 841))
  (segment (start 131.726778 96.75) (end 132.925 95.551778) (width 0.1) (layer "B.Cu") (net 841))
  (segment (start 143.775 82.776778) (end 143.775 83.625) (width 0.1) (layer "B.Cu") (net 841))
  (segment (start 138.051778 90.925) (end 139.225 89.751778) (width 0.1) (layer "B.Cu") (net 841))
  (segment (start 143.7 83.7) (end 143.4 83.7) (width 0.1) (layer "B.Cu") (net 841))
  (segment (start 132.925 93.401778) (end 135.401778 90.925) (width 0.1) (layer "B.Cu") (net 841))
  (segment (start 139.225 89.751778) (end 139.225 87.348222) (width 0.1) (layer "B.Cu") (net 841))
  (segment (start 135.401778 90.925) (end 138.051778 90.925) (width 0.1) (layer "B.Cu") (net 841))
  (segment (start 138.825 84.126778) (end 140.376778 82.575) (width 0.1) (layer "B.Cu") (net 841))
  (segment (start 127.05 92.2625) (end 127.05 92.75) (width 0.1) (layer "B.Cu") (net 841))
  (segment (start 127.15 93.601778) (end 130.298222 96.75) (width 0.1) (layer "B.Cu") (net 841))
  (segment (start 127.15 92.85) (end 127.15 93.601778) (width 0.1) (layer "B.Cu") (net 841))
  (segment (start 132.925 95.551778) (end 132.925 93.401778) (width 0.1) (layer "B.Cu") (net 841))
  (segment (start 127.05 92.75) (end 127.15 92.85) (width 0.1) (layer "B.Cu") (net 841))
  (segment (start 143.573222 82.575) (end 143.775 82.776778) (width 0.1) (layer "B.Cu") (net 841))
  (segment (start 143.775 83.625) (end 143.7 83.7) (width 0.1) (layer "B.Cu") (net 841))
  (segment (start 139.225 87.348222) (end 138.825 86.948222) (width 0.1) (layer "B.Cu") (net 841))
  (segment (start 138.825 86.948222) (end 138.825 84.126778) (width 0.1) (layer "B.Cu") (net 841))
  (segment (start 130.298222 96.75) (end 131.726778 96.75) (width 0.1) (layer "B.Cu") (net 841))
  (segment (start 140.376778 82.575) (end 143.573222 82.575) (width 0.1) (layer "B.Cu") (net 841))
  (segment (start 131.6 98.76) (end 131.6 99) (width 0.127) (layer "F.Cu") (net 842))
  (via (at 131.6 99) (size 0.5) (drill 0.2) (layers "F.Cu" "B.Cu") (net 842))
  (segment (start 126.1615 94.60737) (end 126.175 94.59387) (width 0.1) (layer "B.Cu") (net 842))
  (segment (start 131.6 99.3) (end 131.675 99.375) (width 0.1) (layer "B.Cu") (net 842))
  (segment (start 132.475 98.425) (end 132.475 98.251778) (width 0.1) (layer "B.Cu") (net 842))
  (segment (start 132.475 98.475) (end 132.475 98.425) (width 0.1) (layer "B.Cu") (net 842))
  (segment (start 132.248222 99.375) (end 132.475 99.148222) (width 0.1) (layer "B.Cu") (net 842))
  (segment (start 132.475 98.251778) (end 131.848222 97.625) (width 0.1) (layer "B.Cu") (net 842))
  (segment (start 126.05 92.75) (end 126.05 92.2625) (width 0.1) (layer "B.Cu") (net 842))
  (segment (start 132.475 99.148222) (end 132.475 99.075) (width 0.1) (layer "B.Cu") (net 842))
  (segment (start 131.6 99) (end 131.6 99.3) (width 0.1) (layer "B.Cu") (net 842))
  (segment (start 129.17913 97.625) (end 126.1615 94.60737) (width 0.1) (layer "B.Cu") (net 842))
  (segment (start 131.675 99.375) (end 132.248222 99.375) (width 0.1) (layer "B.Cu") (net 842))
  (segment (start 126.175 94.59387) (end 126.175 92.875) (width 0.1) (layer "B.Cu") (net 842))
  (segment (start 132.305905 98.625) (end 132.325 98.625) (width 0.1) (layer "B.Cu") (net 842))
  (segment (start 132.325 98.925) (end 132.305905 98.925) (width 0.1) (layer "B.Cu") (net 842))
  (segment (start 126.175 92.875) (end 126.05 92.75) (width 0.1) (layer "B.Cu") (net 842))
  (segment (start 131.848222 97.625) (end 129.17913 97.625) (width 0.1) (layer "B.Cu") (net 842))
  (arc (start 132.325 98.625) (mid 132.431066 98.581066) (end 132.475 98.475) (width 0.1) (layer "B.Cu") (net 842))
  (arc (start 132.475 99.075) (mid 132.431066 98.968934) (end 132.325 98.925) (width 0.1) (layer "B.Cu") (net 842))
  (arc (start 132.305905 98.925) (mid 132.199839 98.881066) (end 132.155905 98.775) (width 0.1) (layer "B.Cu") (net 842))
  (arc (start 132.155905 98.775) (mid 132.199839 98.668934) (end 132.305905 98.625) (width 0.1) (layer "B.Cu") (net 842))
  (segment (start 111.507 108.95) (end 111.75 108.95) (width 0.1) (layer "F.Cu") (net 843))
  (via (at 111.75 108.95) (size 0.5) (drill 0.2) (layers "F.Cu" "B.Cu") (net 843))
  (segment (start 124.548222 91.175) (end 122.748222 92.975) (width 0.1) (layer "B.Cu") (net 843))
  (segment (start 110.45 99.298222) (end 110.45 107.626778) (width 0.1) (layer "B.Cu") (net 843))
  (segment (start 122.748222 92.975) (end 117.498222 92.975) (width 0.1) (layer "B.Cu") (net 843))
  (segment (start 112.05 108.95) (end 111.75 108.95) (width 0.1) (layer "B.Cu") (net 843))
  (segment (start 112.125 108.676778) (end 112.125 108.875) (width 0.1) (layer "B.Cu") (net 843))
  (segment (start 125.3375 91.05) (end 124.85 91.05) (width 0.1) (layer "B.Cu") (net 843))
  (segment (start 124.85 91.05) (end 124.725 91.175) (width 0.1) (layer "B.Cu") (net 843))
  (segment (start 124.725 91.175) (end 124.548222 91.175) (width 0.1) (layer "B.Cu") (net 843))
  (segment (start 112.125 108.875) (end 112.05 108.95) (width 0.1) (layer "B.Cu") (net 843))
  (segment (start 117.498222 92.975) (end 115.498222 94.975) (width 0.1) (layer "B.Cu") (net 843))
  (segment (start 111.223222 108.4) (end 111.848222 108.4) (width 0.1) (layer "B.Cu") (net 843))
  (segment (start 115.498222 94.975) (end 114.773222 94.975) (width 0.1) (layer "B.Cu") (net 843))
  (segment (start 110.45 107.626778) (end 111.223222 108.4) (width 0.1) (layer "B.Cu") (net 843))
  (segment (start 111.848222 108.4) (end 112.125 108.676778) (width 0.1) (layer "B.Cu") (net 843))
  (segment (start 114.773222 94.975) (end 110.45 99.298222) (width 0.1) (layer "B.Cu") (net 843))
  (segment (start 130.7 82.657) (end 130.7 82.9) (width 0.127) (layer "F.Cu") (net 844))
  (via (at 130.7 82.9) (size 0.5) (drill 0.2) (layers "F.Cu" "B.Cu") (net 844))
  (segment (start 130.023378 83.274844) (end 129.8 83.498222) (width 0.1) (layer "B.Cu") (net 844))
  (segment (start 130.7 83.225) (end 130.650156 83.274844) (width 0.1) (layer "B.Cu") (net 844))
  (segment (start 130.650156 83.274844) (end 130.023378 83.274844) (width 0.1) (layer "B.Cu") (net 844))
  (segment (start 128.85 91.175) (end 128.725 91.05) (width 0.1) (layer "B.Cu") (net 844))
  (segment (start 130.7 82.9) (end 130.7 83.225) (width 0.1) (layer "B.Cu") (net 844))
  (segment (start 129.8 90.298222) (end 128.923222 91.175) (width 0.1) (layer "B.Cu") (net 844))
  (segment (start 128.725 91.05) (end 128.2625 91.05) (width 0.1) (layer "B.Cu") (net 844))
  (segment (start 129.8 83.498222) (end 129.8 90.298222) (width 0.1) (layer "B.Cu") (net 844))
  (segment (start 128.923222 91.175) (end 128.85 91.175) (width 0.1) (layer "B.Cu") (net 844))
  (segment (start 144.643 83.7) (end 144.4 83.7) (width 0.127) (layer "F.Cu") (net 845))
  (via (at 144.4 83.7) (size 0.5) (drill 0.2) (layers "F.Cu" "B.Cu") (net 845))
  (segment (start 127.425 92.875) (end 127.425 93.523222) (width 0.1) (layer "B.Cu") (net 845))
  (segment (start 132.675 95.448222) (end 132.675 93.298222) (width 0.1) (layer "B.Cu") (net 845))
  (segment (start 138.575 87.051778) (end 138.575 84.023222) (width 0.1) (layer "B.Cu") (net 845))
  (segment (start 138.975 89.648222) (end 138.975 87.451778) (width 0.1) (layer "B.Cu") (net 845))
  (segment (start 127.425 93.523222) (end 130.401778 96.5) (width 0.1) (layer "B.Cu") (net 845))
  (segment (start 132.675 93.298222) (end 135.298222 90.675) (width 0.1) (layer "B.Cu") (net 845))
  (segment (start 135.298222 90.675) (end 137.948222 90.675) (width 0.1) (layer "B.Cu") (net 845))
  (segment (start 127.55 92.2625) (end 127.55 92.75) (width 0.1) (layer "B.Cu") (net 845))
  (segment (start 138.975 87.451778) (end 138.575 87.051778) (width 0.1) (layer "B.Cu") (net 845))
  (segment (start 144.1 83.7) (end 144.4 83.7) (width 0.1) (layer "B.Cu") (net 845))
  (segment (start 144.025 82.673222) (end 144.025 83.625) (width 0.1) (layer "B.Cu") (net 845))
  (segment (start 130.401778 96.5) (end 131.623222 96.5) (width 0.1) (layer "B.Cu") (net 845))
  (segment (start 144.025 83.625) (end 144.1 83.7) (width 0.1) (layer "B.Cu") (net 845))
  (segment (start 137.948222 90.675) (end 138.975 89.648222) (width 0.1) (layer "B.Cu") (net 845))
  (segment (start 131.623222 96.5) (end 132.675 95.448222) (width 0.1) (layer "B.Cu") (net 845))
  (segment (start 140.273222 82.325) (end 143.676778 82.325) (width 0.1) (layer "B.Cu") (net 845))
  (segment (start 127.55 92.75) (end 127.425 92.875) (width 0.1) (layer "B.Cu") (net 845))
  (segment (start 143.676778 82.325) (end 144.025 82.673222) (width 0.1) (layer "B.Cu") (net 845))
  (segment (start 138.575 84.023222) (end 140.273222 82.325) (width 0.1) (layer "B.Cu") (net 845))
  (segment (start 232.065 121.95) (end 232.1 121.915) (width 0.2) (layer "F.Cu") (net 846))
  (segment (start 230.75 121.95) (end 232.065 121.95) (width 0.2) (layer "F.Cu") (net 846))
  (segment (start 232.1 121.915) (end 232.785 121.915) (width 0.2) (layer "F.Cu") (net 846))
  (segment (start 224.9 123.55) (end 224.9 124.585) (width 0.2) (layer "F.Cu") (net 846))
  (segment (start 224.9 124.585) (end 224.915 124.6) (width 0.2) (layer "F.Cu") (net 846))
  (segment (start 232.785 121.915) (end 232.8 121.9) (width 0.2) (layer "F.Cu") (net 846))
  (segment (start 224.3 124.6) (end 224.915 124.6) (width 0.2) (layer "F.Cu") (net 846))
  (via (at 224.3 124.6) (size 0.5) (drill 0.2) (layers "F.Cu" "B.Cu") (net 846))
  (via (at 232.8 121.9) (size 0.5) (drill 0.2) (layers "F.Cu" "B.Cu") (net 846))
  (segment (start 224.780011 124.119989) (end 224.3 124.6) (width 0.4) (layer "B.Cu") (net 846))
  (segment (start 231.056102 124.15) (end 226.777987 124.15) (width 0.4) (layer "B.Cu") (net 846))
  (segment (start 232.515 126.785) (end 231.8 126.785) (width 0.4) (layer "B.Cu") (net 846))
  (segment (start 230.45 126.75) (end 231.765 126.75) (width 0.2) (layer "B.Cu") (net 846))
  (segment (start 231.2 122.5) (end 231.2 124.006102) (width 0.4) (layer "B.Cu") (net 846))
  (segment (start 231.2 124.006102) (end 231.056102 124.15) (width 0.4) (layer "B.Cu") (net 846))
  (segment (start 233.1 125.4) (end 233.1 126.2) (width 0.4) (layer "B.Cu") (net 846))
  (segment (start 232.335686 124.635686) (end 233.1 125.4) (width 0.4) (layer "B.Cu") (net 846))
  (segment (start 231.2 124.006102) (end 231.2 124.1) (width 0.4) (layer "B.Cu") (net 846))
  (segment (start 231.765 126.75) (end 231.8 126.785) (width 0.2) (layer "B.Cu") (net 846))
  (segment (start 233.1 126.2) (end 232.515 126.785) (width 0.4) (layer "B.Cu") (net 846))
  (segment (start 226.777987 124.15) (end 226.747976 124.119989) (width 0.4) (layer "B.Cu") (net 846))
  (segment (start 226.747976 124.119989) (end 224.780011 124.119989) (width 0.4) (layer "B.Cu") (net 846))
  (segment (start 231.8 121.9) (end 231.2 122.5) (width 0.4) (layer "B.Cu") (net 846))
  (segment (start 231.735686 124.635686) (end 232.335686 124.635686) (width 0.4) (layer "B.Cu") (net 846))
  (segment (start 231.2 124.1) (end 231.735686 124.635686) (width 0.4) (layer "B.Cu") (net 846))
  (segment (start 232.8 121.9) (end 231.8 121.9) (width 0.4) (layer "B.Cu") (net 846))
  (segment (start 146.598501 129.693501) (end 146.45 129.545) (width 0.127) (layer "F.Cu") (net 853))
  (segment (start 151.101499 130.748501) (end 150.2 131.65) (width 0.127) (layer "F.Cu") (net 853))
  (segment (start 151.101499 129.693501) (end 151.101499 130.748501) (width 0.127) (layer "F.Cu") (net 853))
  (segment (start 147.45 131.65) (end 146.598501 130.798501) (width 0.127) (layer "F.Cu") (net 853))
  (segment (start 146.45 129.545) (end 146.45 128.460767) (width 0.127) (layer "F.Cu") (net 853))
  (segment (start 144.639233 126.65) (end 143.375 126.65) (width 0.127) (layer "F.Cu") (net 853))
  (segment (start 151.25 129.545) (end 151.101499 129.693501) (width 0.127) (layer "F.Cu") (net 853))
  (segment (start 150.2 131.65) (end 147.45 131.65) (width 0.127) (layer "F.Cu") (net 853))
  (segment (start 146.45 128.460767) (end 144.639233 126.65) (width 0.127) (layer "F.Cu") (net 853))
  (segment (start 146.598501 130.798501) (end 146.598501 129.693501) (width 0.127) (layer "F.Cu") (net 853))
  (segment (start 138.4 80.9) (end 137.05 79.55) (width 0.4) (layer "B.Cu") (net 854))
  (segment (start 139.05 80.9) (end 138.4 80.9) (width 0.4) (layer "B.Cu") (net 854))
  (segment (start 140.95 80.9) (end 142.1 80.9) (width 0.4) (layer "B.Cu") (net 855))
  (segment (start 142.6 80.4) (end 143.4 80.4) (width 0.4) (layer "B.Cu") (net 855))
  (segment (start 142.1 80.9) (end 142.6 80.4) (width 0.4) (layer "B.Cu") (net 855))
  (segment (start 151.7 123.55) (end 149.45 125.8) (width 0.4) (layer "B.Cu") (net 856))
  (segment (start 127.7 122.5) (end 127.7 119.5) (width 0.4) (layer "B.Cu") (net 856))
  (segment (start 131 125.8) (end 127.7 122.5) (width 0.4) (layer "B.Cu") (net 856))
  (segment (start 127.7 119.5) (end 127.1 118.9) (width 0.4) (layer "B.Cu") (net 856))
  (segment (start 127.1 118.9) (end 122.85 118.9) (width 0.4) (layer "B.Cu") (net 856))
  (segment (start 149.45 125.8) (end 131 125.8) (width 0.4) (layer "B.Cu") (net 856))
  (segment (start 152.45 123.55) (end 151.7 123.55) (width 0.4) (layer "B.Cu") (net 856))
  (segment (start 120.95 118.9) (end 118.4 118.9) (width 0.4) (layer "B.Cu") (net 857))
  (segment (start 118.4 118.9) (end 114.3 114.8) (width 0.4) (layer "B.Cu") (net 857))
  (segment (start 227.825 121.95) (end 228.05 121.95) (width 0.2) (layer "F.Cu") (net 859))
  (segment (start 226.7 122.8) (end 226.975 122.8) (width 0.2) (layer "F.Cu") (net 859))
  (segment (start 228.95 121.85) (end 229.1 122) (width 0.2) (layer "F.Cu") (net 859))
  (segment (start 229.1 122) (end 229.8 122) (width 0.2) (layer "F.Cu") (net 859))
  (segment (start 226.975 122.8) (end 227.825 121.95) (width 0.2) (layer "F.Cu") (net 859))
  (segment (start 229.8 122) (end 229.8 123) (width 0.2) (layer "F.Cu") (net 859))
  (segment (start 228.15 121.85) (end 228.95 121.85) (width 0.2) (layer "F.Cu") (net 859))
  (via (at 229.8 123) (size 0.5) (drill 0.2) (layers "F.Cu" "B.Cu") (net 859))
  (via (at 229.8 122) (size 0.5) (drill 0.2) (layers "F.Cu" "B.Cu") (net 859))
  (segment (start 229.135 123) (end 229.8 123) (width 0.2) (layer "B.Cu") (net 859))
  (segment (start 229.135 122) (end 229.8 122) (width 0.2) (layer "B.Cu") (net 859))
  (segment (start 228.35 123.75) (end 228.899999 124.299999) (width 0.127) (layer "F.Cu") (net 860))
  (segment (start 228.0105 123.6105) (end 227.35 123.6105) (width 0.2) (layer "F.Cu") (net 860))
  (segment (start 228.899999 124.299999) (end 228.899999 125.3) (width 0.127) (layer "F.Cu") (net 860))
  (segment (start 228.15 123.75) (end 228.35 123.75) (width 0.2) (layer "F.Cu") (net 860))
  (segment (start 228.15 123.75) (end 228.0105 123.6105) (width 0.2) (layer "F.Cu") (net 860))
  (via (at 227.35 123.6105) (size 0.5) (drill 0.2) (layers "F.Cu" "B.Cu") (net 860))
  (segment (start 227.35 123.6105) (end 227.4545 123.6105) (width 0.2) (layer "B.Cu") (net 860))
  (segment (start 226.25 123.335) (end 226.685 123.335) (width 0.2) (layer "B.Cu") (net 860))
  (segment (start 227.4545 123.6105) (end 228.065 123) (width 0.2) (layer "B.Cu") (net 860))
  (segment (start 226.685 123.335) (end 226.9605 123.6105) (width 0.2) (layer "B.Cu") (net 860))
  (segment (start 226.9605 123.6105) (end 227.35 123.6105) (width 0.2) (layer "B.Cu") (net 860))
  (segment (start 144.53 134.3) (end 153.17 134.3) (width 0.4) (layer "F.Cu") (net 862))
  (segment (start 153.2 128) (end 153.2 128.015) (width 0.4) (layer "F.Cu") (net 862))
  (segment (start 153.2 128) (end 154.2 128) (width 0.4) (layer "F.Cu") (net 862))
  (segment (start 173.35 123.966398) (end 173.35 128.099) (width 0.4) (layer "F.Cu") (net 862))
  (segment (start 153.17 130.12) (end 153.17 128.03) (width 0.4) (layer "F.Cu") (net 862))
  (segment (start 157.65 127.75) (end 157.65 127.65) (width 0.4) (layer "F.Cu") (net 862))
  (segment (start 157.4 128) (end 157.65 128.25) (width 0.4) (layer "F.Cu") (net 862))
  (segment (start 157.65 127.65) (end 157.65 128.25) (width 0.4) (layer "F.Cu") (net 862))
  (segment (start 157.65 123.966398) (end 157.65 127.65) (width 0.4) (layer "F.Cu") (net 862))
  (segment (start 173.35 128.099) (end 172.149 129.3) (width 0.4) (layer "F.Cu") (net 862))
  (segment (start 158.7 129.3) (end 157.65 128.25) (width 0.4) (layer "F.Cu") (net 862))
  (segment (start 144.53 130.12) (end 144.53 134.3) (width 0.4) (layer "F.Cu") (net 862))
  (segment (start 153.17 134.3) (end 153.17 130.12) (width 0.4) (layer "F.Cu") (net 862))
  (segment (start 172.149 129.3) (end 158.7 129.3) (width 0.4) (layer "F.Cu") (net 862))
  (segment (start 157.4 128) (end 157.65 127.75) (width 0.4) (layer "F.Cu") (net 862))
  (segment (start 154.2 128) (end 157.4 128) (width 0.4) (layer "F.Cu") (net 862))
  (segment (start 153.17 128.03) (end 153.2 128) (width 0.4) (layer "F.Cu") (net 862))
  (segment (start 202.4285 133.75) (end 202.4285 127.75) (width 0.4) (layer "F.Cu") (net 863))
  (segment (start 202.4285 124.3565) (end 202.485 124.3) (width 0.4) (layer "F.Cu") (net 863))
  (segment (start 202.4285 127.75) (end 202.4285 124.3565) (width 0.4) (layer "F.Cu") (net 863))
  (segment (start 202.485 124.3) (end 202.485 123.3) (width 0.4) (layer "F.Cu") (net 863))
  (segment (start 216.9285 133.75) (end 202.4285 133.75) (width 0.4) (layer "F.Cu") (net 863))
  (segment (start 216.9285 133.75) (end 216.9285 127.75) (width 0.4) (layer "F.Cu") (net 863))
  (segment (start 238.3 122.315) (end 238.159277 122.315) (width 0.2) (layer "F.Cu") (net 864))
  (segment (start 238.159277 122.315) (end 237.544277 121.7) (width 0.2) (layer "F.Cu") (net 864))
  (via (at 237.544277 121.7) (size 0.5) (drill 0.2) (layers "F.Cu" "B.Cu") (net 864))
  (segment (start 237.544277 121.7) (end 236.944277 121.1) (width 0.2) (layer "In2.Cu") (net 864))
  (segment (start 208.27 123.7) (end 197.41 112.84) (width 0.2) (layer "In2.Cu") (net 864))
  (segment (start 226.8 121.1) (end 224.2 123.7) (width 0.2) (layer "In2.Cu") (net 864))
  (segment (start 224.2 123.7) (end 208.27 123.7) (width 0.2) (layer "In2.Cu") (net 864))
  (segment (start 236.944277 121.1) (end 226.8 121.1) (width 0.2) (layer "In2.Cu") (net 864))
  (segment (start 257.105 100.5) (end 257.432211 100.172789) (width 0.122) (layer "F.Cu") (net 883))
  (segment (start 191.636328 94.060008) (end 191.136328 93.560008) (width 0.2) (layer "F.Cu") (net 883))
  (segment (start 257.60589 100.17279) (end 257.767099 100.334) (width 0.122) (layer "F.Cu") (net 883))
  (segment (start 257.502921 100.1435) (end 257.535179 100.1435) (width 0.122) (layer "F.Cu") (net 883))
  (via blind (at 191.636328 94.060008) (size 0.5) (drill 0.2) (layers "F.Cu" "In5.Cu") (net 883))
  (via (at 257.767099 100.334) (size 0.5) (drill 0.2) (layers "F.Cu" "B.Cu") (net 883))
  (arc (start 257.432211 100.172789) (mid 257.464653 100.151112) (end 257.502921 100.1435) (width 0.122) (layer "F.Cu") (net 883))
  (arc (start 257.60589 100.17279) (mid 257.573448 100.151112) (end 257.535179 100.1435) (width 0.122) (layer "F.Cu") (net 883))
  (segment (start 202.993646 90.1575) (end 238.099849 90.1575) (width 0.105) (layer "In5.Cu") (net 883))
  (segment (start 198.604646 94.422236) (end 202.781514 90.245368) (width 0.105) (layer "In5.Cu") (net 883))
  (segment (start 255.662151 100.1695) (end 257.519756 100.1695) (width 0.105) (layer "In5.Cu") (net 883))
  (segment (start 251.000151 98.1775) (end 253.326354 98.1775) (width 0.105) (layer "In5.Cu") (net 883))
  (segment (start 193.90556 94.573224) (end 193.909806 94.57747) (width 0.08) (layer "In5.Cu") (net 883))
  (segment (start 249.908486 85.485368) (end 250.094632 85.671514) (width 0.105) (layer "In5.Cu") (net 883))
  (segment (start 193.430123 94.5) (end 193.728783 94.5) (width 0.08) (layer "In5.Cu") (net 883))
  (segment (start 193.909806 94.57747) (end 198.229879 94.57747) (width 0.105) (layer "In5.Cu") (net 883))
  (segment (start 250.1825 85.883646) (end 250.1825 97.359849) (width 0.105) (layer "In5.Cu") (net 883))
  (segment (start 257.661178 100.228079) (end 257.767099 100.334) (width 0.105) (layer "In5.Cu") (net 883))
  (segment (start 238.474616 90.002266) (end 240.521514 87.955368) (width 0.105) (layer "In5.Cu") (net 883))
  (segment (start 192.416984 94.68) (end 193.043016 94.68) (width 0.08) (layer "In5.Cu") (net 883))
  (segment (start 241.524616 87.712266) (end 243.751514 85.485368) (width 0.105) (layer "In5.Cu") (net 883))
  (segment (start 250.337734 97.734616) (end 250.625385 98.022267) (width 0.105) (layer "In5.Cu") (net 883))
  (segment (start 192.03 94.171421) (end 192.03 94.293016) (width 0.08) (layer "In5.Cu") (net 883))
  (segment (start 240.733646 87.8675) (end 241.149849 87.8675) (width 0.105) (layer "In5.Cu") (net 883))
  (segment (start 253.538486 98.265368) (end 255.287385 100.014267) (width 0.105) (layer "In5.Cu") (net 883))
  (segment (start 193.255148 94.592132) (end 193.288702 94.558578) (width 0.08) (layer "In5.Cu") (net 883))
  (segment (start 192.117868 94.505148) (end 192.204852 94.592132) (width 0.08) (layer "In5.Cu") (net 883))
  (segment (start 243.963646 85.3975) (end 249.696354 85.3975) (width 0.105) (layer "In5.Cu") (net 883))
  (segment (start 191.989298 94.089298) (end 192.000711 94.100711) (width 0.08) (layer "In5.Cu") (net 883))
  (segment (start 191.636328 94.060008) (end 191.918587 94.060008) (width 0.08) (layer "In5.Cu") (net 883))
  (arc (start 250.094632 85.671514) (mid 250.159664 85.768841) (end 250.1825 85.883646) (width 0.105) (layer "In5.Cu") (net 883))
  (arc (start 251.000151 98.1775) (mid 250.797329 98.137156) (end 250.625385 98.022267) (width 0.105) (layer "In5.Cu") (net 883))
  (arc (start 202.993646 90.1575) (mid 202.878841 90.180336) (end 202.781514 90.245368) (width 0.105) (layer "In5.Cu") (net 883))
  (arc (start 253.326354 98.1775) (mid 253.441159 98.200336) (end 253.538486 98.265368) (width 0.105) (layer "In5.Cu") (net 883))
  (arc (start 192.416984 94.68) (mid 192.302179 94.657164) (end 192.204852 94.592132) (width 0.08) (layer "In5.Cu") (net 883))
  (arc (start 192.000711 94.100711) (mid 192.022388 94.133153) (end 192.03 94.171421) (width 0.08) (layer "In5.Cu") (net 883))
  (arc (start 257.519756 100.1695) (mid 257.596293 100.184724) (end 257.661178 100.228079) (width 0.105) (layer "In5.Cu") (net 883))
  (arc (start 198.229879 94.57747) (mid 198.432702 94.537126) (end 198.604646 94.422236) (width 0.105) (layer "In5.Cu") (net 883))
  (arc (start 192.03 94.293016) (mid 192.052836 94.407821) (end 192.117868 94.505148) (width 0.08) (layer "In5.Cu") (net 883))
  (arc (start 193.430123 94.5) (mid 193.353587 94.515224) (end 193.288702 94.558578) (width 0.08) (layer "In5.Cu") (net 883))
  (arc (start 255.662151 100.1695) (mid 255.459329 100.129156) (end 255.287385 100.014267) (width 0.105) (layer "In5.Cu") (net 883))
  (arc (start 193.728783 94.5) (mid 193.824454 94.51903) (end 193.90556 94.573224) (width 0.08) (layer "In5.Cu") (net 883))
  (arc (start 240.521514 87.955368) (mid 240.618841 87.890336) (end 240.733646 87.8675) (width 0.105) (layer "In5.Cu") (net 883))
  (arc (start 191.989298 94.089298) (mid 191.956856 94.06762) (end 191.918587 94.060008) (width 0.08) (layer "In5.Cu") (net 883))
  (arc (start 250.1825 97.359849) (mid 250.222844 97.562672) (end 250.337734 97.734616) (width 0.105) (layer "In5.Cu") (net 883))
  (arc (start 193.043016 94.68) (mid 193.157821 94.657164) (end 193.255148 94.592132) (width 0.08) (layer "In5.Cu") (net 883))
  (arc (start 238.474616 90.002266) (mid 238.302671 90.117156) (end 238.099849 90.1575) (width 0.105) (layer "In5.Cu") (net 883))
  (arc (start 243.963646 85.3975) (mid 243.848841 85.420336) (end 243.751514 85.485368) (width 0.105) (layer "In5.Cu") (net 883))
  (arc (start 249.908486 85.485368) (mid 249.811159 85.420336) (end 249.696354 85.3975) (width 0.105) (layer "In5.Cu") (net 883))
  (arc (start 241.524616 87.712266) (mid 241.352671 87.827156) (end 241.149849 87.8675) (width 0.105) (layer "In5.Cu") (net 883))
  (segment (start 257.105 99.5) (end 257.432211 99.827211) (width 0.122) (layer "F.Cu") (net 884))
  (segment (start 192.6 94.02368) (end 192.6 94.0505) (width 0.127) (layer "F.Cu") (net 884))
  (segment (start 192.136328 93.560008) (end 192.6 94.02368) (width 0.2) (layer "F.Cu") (net 884))
  (segment (start 257.502921 99.8565) (end 257.539178 99.8565) (width 0.122) (layer "F.Cu") (net 884))
  (segment (start 257.609891 99.82721) (end 257.7671 99.67) (width 0.122) (layer "F.Cu") (net 884))
  (via blind (at 192.6 94.0505) (size 0.5) (drill 0.2) (layers "F.Cu" "In5.Cu") (net 884))
  (via (at 257.7671 99.67) (size 0.5) (drill 0.2) (layers "F.Cu" "B.Cu") (net 884))
  (arc (start 257.502921 99.8565) (mid 257.464653 99.848888) (end 257.432211 99.827211) (width 0.122) (layer "F.Cu") (net 884))
  (arc (start 257.539178 99.8565) (mid 257.577448 99.848888) (end 257.609891 99.82721) (width 0.122) (layer "F.Cu") (net 884))
  (segment (start 192.450123 94.5) (end 193.009877 94.5) (width 0.08) (layer "In5.Cu") (net 884))
  (segment (start 240.594882 87.5325) (end 241.106354 87.5325) (width 0.105) (layer "In5.Cu") (net 884))
  (segment (start 241.318486 87.444632) (end 243.545385 85.217733) (width 0.105) (layer "In5.Cu") (net 884))
  (segment (start 192.23929 94.122131) (end 192.281632 94.079789) (width 0.08) (layer "In5.Cu") (net 884))
  (segment (start 192.21 94.259877) (end 192.21 94.192842) (width 0.08) (layer "In5.Cu") (net 884))
  (segment (start 193.151299 94.441421) (end 193.184852 94.407868) (width 0.08) (layer "In5.Cu") (net 884))
  (segment (start 192.6 94.0505) (end 192.352342 94.0505) (width 0.08) (layer "In5.Cu") (net 884))
  (segment (start 243.920151 85.0625) (end 249.739849 85.0625) (width 0.105) (layer "In5.Cu") (net 884))
  (segment (start 238.268486 89.734632) (end 240.38275 87.620368) (width 0.105) (layer "In5.Cu") (net 884))
  (segment (start 255.705646 99.8345) (end 257.519757 99.8345) (width 0.105) (layer "In5.Cu") (net 884))
  (segment (start 257.661178 99.775922) (end 257.7671 99.67) (width 0.105) (layer "In5.Cu") (net 884))
  (segment (start 250.114616 85.217734) (end 250.362267 85.465385) (width 0.105) (layer "In5.Cu") (net 884))
  (segment (start 253.744616 97.997734) (end 255.493514 99.746632) (width 0.105) (layer "In5.Cu") (net 884))
  (segment (start 193.909806 94.24247) (end 198.186384 94.24247) (width 0.105) (layer "In5.Cu") (net 884))
  (segment (start 250.605368 97.528486) (end 250.831514 97.754632) (width 0.105) (layer "In5.Cu") (net 884))
  (segment (start 193.396984 94.32) (end 193.728723 94.32) (width 0.08) (layer "In5.Cu") (net 884))
  (segment (start 250.5175 85.840151) (end 250.5175 97.316354) (width 0.105) (layer "In5.Cu") (net 884))
  (segment (start 198.398516 94.154602) (end 202.575385 89.977733) (width 0.105) (layer "In5.Cu") (net 884))
  (segment (start 192.268579 94.401299) (end 192.308702 94.441422) (width 0.08) (layer "In5.Cu") (net 884))
  (segment (start 202.950151 89.8225) (end 238.056354 89.8225) (width 0.105) (layer "In5.Cu") (net 884))
  (segment (start 251.043646 97.8425) (end 253.369849 97.8425) (width 0.105) (layer "In5.Cu") (net 884))
  (segment (start 193.9055 94.246776) (end 193.909806 94.24247) (width 0.08) (layer "In5.Cu") (net 884))
  (arc (start 250.5175 85.840151) (mid 250.477156 85.637329) (end 250.362267 85.465385) (width 0.105) (layer "In5.Cu") (net 884))
  (arc (start 257.661178 99.775922) (mid 257.596293 99.819276) (end 257.519757 99.8345) (width 0.105) (layer "In5.Cu") (net 884))
  (arc (start 241.106354 87.5325) (mid 241.221159 87.509664) (end 241.318486 87.444632) (width 0.105) (layer "In5.Cu") (net 884))
  (arc (start 192.450123 94.5) (mid 192.373587 94.484776) (end 192.308702 94.441422) (width 0.08) (layer "In5.Cu") (net 884))
  (arc (start 192.281632 94.079789) (mid 192.314074 94.058112) (end 192.352342 94.0505) (width 0.08) (layer "In5.Cu") (net 884))
  (arc (start 250.605368 97.528486) (mid 250.540336 97.431159) (end 250.5175 97.316354) (width 0.105) (layer "In5.Cu") (net 884))
  (arc (start 250.831514 97.754632) (mid 250.928841 97.819664) (end 251.043646 97.8425) (width 0.105) (layer "In5.Cu") (net 884))
  (arc (start 255.493514 99.746632) (mid 255.590841 99.811664) (end 255.705646 99.8345) (width 0.105) (layer "In5.Cu") (net 884))
  (arc (start 249.739849 85.0625) (mid 249.942672 85.102844) (end 250.114616 85.217734) (width 0.105) (layer "In5.Cu") (net 884))
  (arc (start 198.186384 94.24247) (mid 198.301189 94.219634) (end 198.398516 94.154602) (width 0.105) (layer "In5.Cu") (net 884))
  (arc (start 193.009877 94.5) (mid 193.086414 94.484776) (end 193.151299 94.441421) (width 0.08) (layer "In5.Cu") (net 884))
  (arc (start 202.950151 89.8225) (mid 202.747329 89.862844) (end 202.575385 89.977733) (width 0.105) (layer "In5.Cu") (net 884))
  (arc (start 243.545385 85.217733) (mid 243.717329 85.102844) (end 243.920151 85.0625) (width 0.105) (layer "In5.Cu") (net 884))
  (arc (start 253.744616 97.997734) (mid 253.572671 97.882844) (end 253.369849 97.8425) (width 0.105) (layer "In5.Cu") (net 884))
  (arc (start 240.594882 87.5325) (mid 240.480077 87.555336) (end 240.38275 87.620368) (width 0.105) (layer "In5.Cu") (net 884))
  (arc (start 193.728723 94.32) (mid 193.824394 94.30097) (end 193.9055 94.246776) (width 0.08) (layer "In5.Cu") (net 884))
  (arc (start 192.21 94.259877) (mid 192.225224 94.336414) (end 192.268579 94.401299) (width 0.08) (layer "In5.Cu") (net 884))
  (arc (start 193.396984 94.32) (mid 193.282179 94.342836) (end 193.184852 94.407868) (width 0.08) (layer "In5.Cu") (net 884))
  (arc (start 238.056354 89.8225) (mid 238.171159 89.799664) (end 238.268486 89.734632) (width 0.105) (layer "In5.Cu") (net 884))
  (arc (start 192.23929 94.122131) (mid 192.217612 94.154573) (end 192.21 94.192842) (width 0.08) (layer "In5.Cu") (net 884))
  (segment (start 191.636328 100.060008) (end 191.136328 99.560008) (width 0.127) (layer "F.Cu") (net 885))
  (segment (start 242.0565 116.85944) (end 242.0565 115.75944) (width 0.122) (layer "F.Cu") (net 885))
  (segment (start 240.962873 115.440067) (end 240.850801 115.552139) (width 0.122) (layer "F.Cu") (net 885))
  (segment (start 240.850801 115.552139) (end 240.850801 115.819427) (width 0.122) (layer "F.Cu") (net 885))
  (segment (start 242.6565 117.5585) (end 242.6565 117.45944) (width 0.122) (layer "F.Cu") (net 885))
  (segment (start 242.3 117.915) (end 242.6565 117.5585) (width 0.122) (layer "F.Cu") (net 885))
  (segment (start 242.6565 117.45944) (end 242.0565 116.85944) (width 0.122) (layer "F.Cu") (net 885))
  (segment (start 242.0565 115.75944) (end 241.737127 115.440067) (width 0.122) (layer "F.Cu") (net 885))
  (segment (start 241.737127 115.440067) (end 240.962873 115.440067) (width 0.122) (layer "F.Cu") (net 885))
  (via (at 191.636328 100.060008) (size 0.5) (drill 0.2) (layers "F.Cu" "B.Cu") (net 885))
  (via (at 240.850801 115.819427) (size 0.5) (drill 0.2) (layers "F.Cu" "B.Cu") (free) (net 885))
  (segment (start 240.247341 116.034) (end 239.752658 116.034) (width 0.13) (layer "In9.Cu") (net 885))
  (segment (start 211.138628 103.655004) (end 210.58307 103.099446) (width 0.13) (layer "In9.Cu") (net 885))
  (segment (start 230.22241 103.853) (end 211.616632 103.853) (width 0.13) (layer "In9.Cu") (net 885))
  (segment (start 240.553014 115.863361) (end 240.477858 115.938517) (width 0.13) (layer "In9.Cu") (net 885))
  (segment (start 192.145811 100.537435) (end 192.158893 100.550517) (width 0.082) (layer "In9.Cu") (net 885))
  (segment (start 193.949517 100.713) (end 193.79 100.713) (width 0.13) (layer "In9.Cu") (net 885))
  (segment (start 191.953942 100.103942) (end 192.006394 100.156394) (width 0.082) (layer "In9.Cu") (net 885))
  (segment (start 240.850801 115.819427) (end 240.65908 115.819427) (width 0.13) (layer "In9.Cu") (net 885))
  (segment (start 207.383368 103.853) (end 197.783739 103.853) (width 0.13) (layer "In9.Cu") (net 885))
  (segment (start 192.050328 100.26246) (end 192.050328 100.306918) (width 0.082) (layer "In9.Cu") (net 885))
  (segment (start 192.869963 100.681147) (end 193.017169 100.828353) (width 0.082) (layer "In9.Cu") (net 885))
  (segment (start 193.571706 100.646) (end 193.640157 100.646) (width 0.082) (layer "In9.Cu") (net 885))
  (segment (start 234.300553 107.516929) (end 230.929517 104.145893) (width 0.13) (layer "In9.Cu") (net 885))
  (segment (start 193.102022 100.8635) (end 193.26611 100.8635) (width 0.082) (layer "In9.Cu") (net 885))
  (segment (start 193.331646 100.836354) (end 193.486853 100.681147) (width 0.082) (layer "In9.Cu") (net 885))
  (segment (start 208.416929 103.099447) (end 207.861372 103.655004) (width 0.13) (layer "In9.Cu") (net 885))
  (segment (start 210.229517 102.953) (end 208.770483 102.953) (width 0.13) (layer "In9.Cu") (net 885))
  (segment (start 193.781579 100.704579) (end 193.79 100.713) (width 0.082) (layer "In9.Cu") (net 885))
  (segment (start 234.447 110.583368) (end 234.447 107.870483) (width 0.13) (layer "In9.Cu") (net 885))
  (segment (start 239.522141 115.938517) (end 234.644996 111.061372) (width 0.13) (layer "In9.Cu") (net 885))
  (segment (start 191.636328 100.060008) (end 191.847876 100.060008) (width 0.082) (layer "In9.Cu") (net 885))
  (segment (start 196.952181 103.508557) (end 194.30307 100.859446) (width 0.13) (layer "In9.Cu") (net 885))
  (segment (start 192.38941 100.646) (end 192.78511 100.646) (width 0.082) (layer "In9.Cu") (net 885))
  (arc (start 192.78511 100.646) (mid 192.831032 100.655134) (end 192.869963 100.681147) (width 0.082) (layer "In9.Cu") (net 885))
  (arc (start 193.017169 100.828353) (mid 193.0561 100.854366) (end 193.102022 100.8635) (width 0.082) (layer "In9.Cu") (net 885))
  (arc (start 210.58307 103.099446) (mid 210.420858 102.99106) (end 210.229517 102.953) (width 0.13) (layer "In9.Cu") (net 885))
  (arc (start 230.929517 104.145893) (mid 230.605094 103.92912) (end 230.22241 103.853) (width 0.13) (layer "In9.Cu") (net 885))
  (arc (start 193.331646 100.836354) (mid 193.301578 100.856445) (end 193.26611 100.8635) (width 0.082) (layer "In9.Cu") (net 885))
  (arc (start 192.158893 100.550517) (mid 192.264655 100.621185) (end 192.38941 100.646) (width 0.082) (layer "In9.Cu") (net 885))
  (arc (start 191.847876 100.060008) (mid 191.905279 100.071426) (end 191.953942 100.103942) (width 0.082) (layer "In9.Cu") (net 885))
  (arc (start 192.050328 100.306918) (mid 192.075143 100.431673) (end 192.145811 100.537435) (width 0.082) (layer "In9.Cu") (net 885))
  (arc (start 192.006394 100.156394) (mid 192.03891 100.205057) (end 192.050328 100.26246) (width 0.082) (layer "In9.Cu") (net 885))
  (arc (start 240.553014 115.863361) (mid 240.601677 115.830845) (end 240.65908 115.819427) (width 0.13) (layer "In9.Cu") (net 885))
  (arc (start 239.752658 116.034) (mid 239.627903 116.009185) (end 239.522141 115.938517) (width 0.13) (layer "In9.Cu") (net 885))
  (arc (start 194.30307 100.859446) (mid 194.140858 100.75106) (end 193.949517 100.713) (width 0.13) (layer "In9.Cu") (net 885))
  (arc (start 234.644996 111.061372) (mid 234.498457 110.842062) (end 234.447 110.583368) (width 0.13) (layer "In9.Cu") (net 885))
  (arc (start 207.861372 103.655004) (mid 207.642062 103.801543) (end 207.383368 103.853) (width 0.13) (layer "In9.Cu") (net 885))
  (arc (start 211.616632 103.853) (mid 211.357938 103.801542) (end 211.138628 103.655004) (width 0.13) (layer "In9.Cu") (net 885))
  (arc (start 193.640157 100.646) (mid 193.716694 100.661224) (end 193.781579 100.704579) (width 0.082) (layer "In9.Cu") (net 885))
  (arc (start 197.783739 103.853) (mid 197.333703 103.763482) (end 196.952181 103.508557) (width 0.13) (layer "In9.Cu") (net 885))
  (arc (start 234.447 107.870483) (mid 234.40894 107.679141) (end 234.300553 107.516929) (width 0.13) (layer "In9.Cu") (net 885))
  (arc (start 240.477858 115.938517) (mid 240.372096 116.009185) (end 240.247341 116.034) (width 0.13) (layer "In9.Cu") (net 885))
  (arc (start 208.770483 102.953) (mid 208.579141 102.99106) (end 208.416929 103.099447) (width 0.13) (layer "In9.Cu") (net 885))
  (arc (start 193.486853 100.681147) (mid 193.525784 100.655134) (end 193.571706 100.646) (width 0.082) (layer "In9.Cu") (net 885))
  (segment (start 242.9435 117.5585) (end 242.9435 117.34056) (width 0.122) (layer "F.Cu") (net 886))
  (segment (start 242.3435 116.74056) (end 242.3435 115.64056) (width 0.122) (layer "F.Cu") (net 886))
  (segment (start 242.3435 115.64056) (end 241.856007 115.153067) (width 0.122) (layer "F.Cu") (net 886))
  (segment (start 192.636328 100.060008) (end 192.136328 99.560008) (width 0.127) (layer "F.Cu") (net 886))
  (segment (start 240.647861 115.349199) (end 240.380573 115.349199) (width 0.122) (layer "F.Cu") (net 886))
  (segment (start 240.843993 115.153067) (end 240.647861 115.349199) (width 0.122) (layer "F.Cu") (net 886))
  (segment (start 242.9435 117.34056) (end 242.3435 116.74056) (width 0.122) (layer "F.Cu") (net 886))
  (segment (start 241.856007 115.153067) (end 240.843993 115.153067) (width 0.122) (layer "F.Cu") (net 886))
  (segment (start 243.3 117.915) (end 242.9435 117.5585) (width 0.122) (layer "F.Cu") (net 886))
  (via (at 192.636328 100.060008) (size 0.5) (drill 0.2) (layers "F.Cu" "B.Cu") (net 886))
  (via (at 240.380573 115.349199) (size 0.5) (drill 0.2) (layers "F.Cu" "B.Cu") (free) (net 886))
  (segment (start 192.316058 100.103942) (end 192.266262 100.153738) (width 0.082) (layer "In9.Cu") (net 886))
  (segment (start 211.316929 103.400553) (end 210.761372 102.844996) (width 0.13) (layer "In9.Cu") (net 886))
  (segment (start 240.193493 115.728) (end 239.806508 115.728) (width 0.13) (layer "In9.Cu") (net 886))
  (segment (start 240.380573 115.349199) (end 240.380573 115.54092) (width 0.13) (layer "In9.Cu") (net 886))
  (segment (start 208.238628 102.844996) (end 207.68307 103.400554) (width 0.13) (layer "In9.Cu") (net 886))
  (segment (start 194.003368 100.407) (end 193.79 100.407) (width 0.13) (layer "In9.Cu") (net 886))
  (segment (start 197.130483 103.254107) (end 194.481372 100.604996) (width 0.13) (layer "In9.Cu") (net 886))
  (segment (start 192.636328 100.060008) (end 192.422124 100.060008) (width 0.082) (layer "In9.Cu") (net 886))
  (segment (start 230.276261 103.547) (end 211.670483 103.547) (width 0.13) (layer "In9.Cu") (net 886))
  (segment (start 210.283368 102.647) (end 208.716632 102.647) (width 0.13) (layer "In9.Cu") (net 886))
  (segment (start 234.753 110.529517) (end 234.753 107.816632) (width 0.13) (layer "In9.Cu") (net 886))
  (segment (start 239.700442 115.684066) (end 234.899446 110.88307) (width 0.13) (layer "In9.Cu") (net 886))
  (segment (start 193.781579 100.415421) (end 193.79 100.407) (width 0.082) (layer "In9.Cu") (net 886))
  (segment (start 207.329517 103.547) (end 197.83759 103.547) (width 0.13) (layer "In9.Cu") (net 886))
  (segment (start 234.555004 107.338628) (end 231.107818 103.891442) (width 0.13) (layer "In9.Cu") (net 886))
  (segment (start 192.387756 100.474) (end 193.640157 100.474) (width 0.082) (layer "In9.Cu") (net 886))
  (segment (start 192.266262 100.414638) (end 192.28169 100.430066) (width 0.082) (layer "In9.Cu") (net 886))
  (segment (start 192.222328 100.259804) (end 192.222328 100.308572) (width 0.082) (layer "In9.Cu") (net 886))
  (segment (start 240.336639 115.646986) (end 240.299559 115.684066) (width 0.13) (layer "In9.Cu") (net 886))
  (arc (start 192.266262 100.414638) (mid 192.233746 100.365975) (end 192.222328 100.308572) (width 0.082) (layer "In9.Cu") (net 886))
  (arc (start 193.640157 100.474) (mid 193.716694 100.458776) (end 193.781579 100.415421) (width 0.082) (layer "In9.Cu") (net 886))
  (arc (start 192.316058 100.103942) (mid 192.364721 100.071426) (end 192.422124 100.060008) (width 0.082) (layer "In9.Cu") (net 886))
  (arc (start 208.716632 102.647) (mid 208.457938 102.698458) (end 208.238628 102.844996) (width 0.13) (layer "In9.Cu") (net 886))
  (arc (start 194.481372 100.604996) (mid 194.262062 100.458458) (end 194.003368 100.407) (width 0.13) (layer "In9.Cu") (net 886))
  (arc (start 197.83759 103.547) (mid 197.454906 103.47088) (end 197.130483 103.254107) (width 0.13) (layer "In9.Cu") (net 886))
  (arc (start 192.387756 100.474) (mid 192.330353 100.462582) (end 192.28169 100.430066) (width 0.082) (layer "In9.Cu") (net 886))
  (arc (start 207.68307 103.400554) (mid 207.520858 103.50894) (end 207.329517 103.547) (width 0.13) (layer "In9.Cu") (net 886))
  (arc (start 240.193493 115.728) (mid 240.250896 115.716582) (end 240.299559 115.684066) (width 0.13) (layer "In9.Cu") (net 886))
  (arc (start 192.266262 100.153738) (mid 192.233746 100.202401) (end 192.222328 100.259804) (width 0.082) (layer "In9.Cu") (net 886))
  (arc (start 211.670483 103.547) (mid 211.479141 103.50894) (end 211.316929 103.400553) (width 0.13) (layer "In9.Cu") (net 886))
  (arc (start 231.107818 103.891442) (mid 230.726296 103.636518) (end 230.276261 103.547) (width 0.13) (layer "In9.Cu") (net 886))
  (arc (start 234.899446 110.88307) (mid 234.79106 110.720858) (end 234.753 110.529517) (width 0.13) (layer "In9.Cu") (net 886))
  (arc (start 240.380573 115.54092) (mid 240.369155 115.598323) (end 240.336639 115.646986) (width 0.13) (layer "In9.Cu") (net 886))
  (arc (start 239.806508 115.728) (mid 239.749105 115.716582) (end 239.700442 115.684066) (width 0.13) (layer "In9.Cu") (net 886))
  (arc (start 210.761372 102.844996) (mid 210.542062 102.698457) (end 210.283368 102.647) (width 0.13) (layer "In9.Cu") (net 886))
  (arc (start 234.753 107.816632) (mid 234.701542 107.557938) (end 234.555004 107.338628) (width 0.13) (layer "In9.Cu") (net 886))
  (segment (start 191.636328 98.060008) (end 191.136328 97.560008) (width 0.127) (layer "F.Cu") (net 887))
  (segment (start 242.707698 122.63529) (end 242.547988 122.795) (width 0.122) (layer "F.Cu") (net 887))
  (segment (start 243.225 122.975) (end 242.885289 122.635289) (width 0.122) (layer "F.Cu") (net 887))
  (segment (start 242.814579 122.606) (end 242.778409 122.606) (width 0.122) (layer "F.Cu") (net 887))
  (via (at 191.636328 98.060008) (size 0.5) (drill 0.2) (layers "F.Cu" "B.Cu") (net 887))
  (via (at 242.547988 122.795) (size 0.5) (drill 0.2) (layers "F.Cu" "B.Cu") (net 887))
  (arc (start 242.885289 122.635289) (mid 242.852847 122.613612) (end 242.814579 122.606) (width 0.122) (layer "F.Cu") (net 887))
  (arc (start 242.707698 122.63529) (mid 242.74014 122.613612) (end 242.778409 122.606) (width 0.122) (layer "F.Cu") (net 887))
  (segment (start 192.145811 99.467435) (end 192.168893 99.490517) (width 0.082) (layer "In9.Cu") (net 887))
  (segment (start 241.644996 122.128973) (end 242.050685 122.534662) (width 0.13) (layer "In9.Cu") (net 887))
  (segment (start 242.397778 122.64479) (end 242.547988 122.795) (width 0.13) (layer "In9.Cu") (net 887))
  (segment (start 236.644996 110.661372) (end 241.659132 115.675508) (width 0.13) (layer "In9.Cu") (net 887))
  (segment (start 236.447 107.870483) (end 236.447 110.183368) (width 0.13) (layer "In9.Cu") (net 887))
  (segment (start 196.129517 99.545893) (end 198.092182 101.508558) (width 0.13) (layer "In9.Cu") (net 887))
  (segment (start 191.636328 98.060008) (end 191.897876 98.060008) (width 0.082) (layer "In9.Cu") (net 887))
  (segment (start 212.016632 102.053) (end 230.42241 102.053) (width 0.13) (layer "In9.Cu") (net 887))
  (segment (start 241.659132 116.924492) (end 241.586417 116.997207) (width 0.13) (layer "In9.Cu") (net 887))
  (segment (start 207.261372 101.655004) (end 207.31693 101.599446) (width 0.13) (layer "In9.Cu") (net 887))
  (segment (start 193.86229 99.21529) (end 193.9 99.253) (width 0.082) (layer "In9.Cu") (net 887))
  (segment (start 241.747 115.88764) (end 241.747 116.71236) (width 0.13) (layer "In9.Cu") (net 887))
  (segment (start 242.245846 122.6155) (end 242.327067 122.6155) (width 0.13) (layer "In9.Cu") (net 887))
  (segment (start 192.39941 99.586) (end 192.90059 99.586) (width 0.082) (layer "In9.Cu") (net 887))
  (segment (start 192.050328 98.21246) (end 192.050328 99.236918) (width 0.082) (layer "In9.Cu") (net 887))
  (segment (start 193.131107 99.490517) (end 193.39169 99.229934) (width 0.082) (layer "In9.Cu") (net 887))
  (segment (start 231.129517 102.345893) (end 236.300554 107.51693) (width 0.13) (layer "In9.Cu") (net 887))
  (segment (start 207.670483 101.453) (end 210.929517 101.453) (width 0.13) (layer "In9.Cu") (net 887))
  (segment (start 193.497756 99.186) (end 193.791579 99.186) (width 0.082) (layer "In9.Cu") (net 887))
  (segment (start 211.283071 101.599447) (end 211.538628 101.855004) (width 0.13) (layer "In9.Cu") (net 887))
  (segment (start 193.9 99.253) (end 195.42241 99.253) (width 0.13) (layer "In9.Cu") (net 887))
  (segment (start 192.003942 98.103942) (end 192.006394 98.106394) (width 0.082) (layer "In9.Cu") (net 887))
  (segment (start 241.447 117.33379) (end 241.447 121.650969) (width 0.13) (layer "In9.Cu") (net 887))
  (segment (start 198.923739 101.853) (end 206.783368 101.853) (width 0.13) (layer "In9.Cu") (net 887))
  (arc (start 192.90059 99.586) (mid 193.025345 99.561185) (end 193.131107 99.490517) (width 0.082) (layer "In9.Cu") (net 887))
  (arc (start 241.586417 116.997207) (mid 241.483233 117.151633) (end 241.447 117.33379) (width 0.13) (layer "In9.Cu") (net 887))
  (arc (start 210.929517 101.453) (mid 211.120859 101.49106) (end 211.283071 101.599447) (width 0.13) (layer "In9.Cu") (net 887))
  (arc (start 241.659132 115.675508) (mid 241.724164 115.772835) (end 241.747 115.88764) (width 0.13) (layer "In9.Cu") (net 887))
  (arc (start 241.447 121.650969) (mid 241.498458 121.909663) (end 241.644996 122.128973) (width 0.13) (layer "In9.Cu") (net 887))
  (arc (start 192.168893 99.490517) (mid 192.274655 99.561185) (end 192.39941 99.586) (width 0.082) (layer "In9.Cu") (net 887))
  (arc (start 195.42241 99.253) (mid 195.805094 99.32912) (end 196.129517 99.545893) (width 0.13) (layer "In9.Cu") (net 887))
  (arc (start 231.129517 102.345893) (mid 230.805094 102.12912) (end 230.42241 102.053) (width 0.13) (layer "In9.Cu") (net 887))
  (arc (start 192.145811 99.467435) (mid 192.075143 99.361673) (end 192.050328 99.236918) (width 0.082) (layer "In9.Cu") (net 887))
  (arc (start 193.791579 99.186) (mid 193.829848 99.193612) (end 193.86229 99.21529) (width 0.082) (layer "In9.Cu") (net 887))
  (arc (start 191.897876 98.060008) (mid 191.955279 98.071426) (end 192.003942 98.103942) (width 0.082) (layer "In9.Cu") (net 887))
  (arc (start 236.300554 107.51693) (mid 236.40894 107.679142) (end 236.447 107.870483) (width 0.13) (layer "In9.Cu") (net 887))
  (arc (start 211.538628 101.855004) (mid 211.757938 102.001542) (end 212.016632 102.053) (width 0.13) (layer "In9.Cu") (net 887))
  (arc (start 193.39169 99.229934) (mid 193.440353 99.197418) (end 193.497756 99.186) (width 0.082) (layer "In9.Cu") (net 887))
  (arc (start 236.447 110.183368) (mid 236.498457 110.442062) (end 236.644996 110.661372) (width 0.13) (layer "In9.Cu") (net 887))
  (arc (start 207.31693 101.599446) (mid 207.479142 101.49106) (end 207.670483 101.453) (width 0.13) (layer "In9.Cu") (net 887))
  (arc (start 206.783368 101.853) (mid 207.042062 101.801542) (end 207.261372 101.655004) (width 0.13) (layer "In9.Cu") (net 887))
  (arc (start 192.050328 98.21246) (mid 192.03891 98.155057) (end 192.006394 98.106394) (width 0.082) (layer "In9.Cu") (net 887))
  (arc (start 241.747 116.71236) (mid 241.724164 116.827165) (end 241.659132 116.924492) (width 0.13) (layer "In9.Cu") (net 887))
  (arc (start 242.327067 122.6155) (mid 242.365336 122.623112) (end 242.397778 122.64479) (width 0.13) (layer "In9.Cu") (net 887))
  (arc (start 242.050685 122.534662) (mid 242.140226 122.594491) (end 242.245846 122.6155) (width 0.13) (layer "In9.Cu") (net 887))
  (arc (start 198.092182 101.508558) (mid 198.473704 101.763482) (end 198.923739 101.853) (width 0.13) (layer "In9.Cu") (net 887))
  (segment (start 242.814579 122.319) (end 242.778409 122.319) (width 0.122) (layer "F.Cu") (net 888))
  (segment (start 192.636328 98.060008) (end 192.136328 97.560008) (width 0.127) (layer "F.Cu") (net 888))
  (segment (start 243.225 121.95) (end 242.885289 122.289711) (width 0.122) (layer "F.Cu") (net 888))
  (segment (start 242.707698 122.28971) (end 242.547988 122.13) (width 0.122) (layer "F.Cu") (net 888))
  (via (at 242.547988 122.13) (size 0.5) (drill 0.2) (layers "F.Cu" "B.Cu") (net 888))
  (via (at 192.636328 98.060008) (size 0.5) (drill 0.2) (layers "F.Cu" "B.Cu") (net 888))
  (arc (start 242.778409 122.319) (mid 242.74014 122.311388) (end 242.707698 122.28971) (width 0.122) (layer "F.Cu") (net 888))
  (arc (start 242.814579 122.319) (mid 242.852847 122.311388) (end 242.885289 122.289711) (width 0.122) (layer "F.Cu") (net 888))
  (segment (start 241.753 121.353) (end 241.753 121.597118) (width 0.13) (layer "In9.Cu") (net 888))
  (segment (start 192.222328 98.239804) (end 192.222328 99.238572) (width 0.082) (layer "In9.Cu") (net 888))
  (segment (start 193.9 98.947) (end 195.476261 98.947) (width 0.13) (layer "In9.Cu") (net 888))
  (segment (start 242.397778 122.28021) (end 242.547988 122.13) (width 0.13) (layer "In9.Cu") (net 888))
  (segment (start 236.899446 110.48307) (end 241.913583 115.497207) (width 0.13) (layer "In9.Cu") (net 888))
  (segment (start 242.003 120.553) (end 242.101431 120.553) (width 0.13) (layer "In9.Cu") (net 888))
  (segment (start 231.307819 102.091443) (end 236.555004 107.338628) (width 0.13) (layer "In9.Cu") (net 888))
  (segment (start 193.86229 98.98471) (end 193.9 98.947) (width 0.082) (layer "In9.Cu") (net 888))
  (segment (start 192.275921 98.124079) (end 192.266262 98.133738) (width 0.082) (layer "In9.Cu") (net 888))
  (segment (start 242.101431 121.053) (end 242.003 121.053) (width 0.13) (layer "In9.Cu") (net 888))
  (segment (start 241.899446 121.950671) (end 242.228986 122.280211) (width 0.13) (layer "In9.Cu") (net 888))
  (segment (start 207.08307 101.400554) (end 207.138628 101.344996) (width 0.13) (layer "In9.Cu") (net 888))
  (segment (start 193.49941 99.014) (end 193.791579 99.014) (width 0.082) (layer "In9.Cu") (net 888))
  (segment (start 241.913583 117.102793) (end 241.840868 117.175508) (width 0.13) (layer "In9.Cu") (net 888))
  (segment (start 212.070483 101.747) (end 230.476261 101.747) (width 0.13) (layer "In9.Cu") (net 888))
  (segment (start 196.307818 99.291442) (end 198.270483 101.254107) (width 0.13) (layer "In9.Cu") (net 888))
  (segment (start 198.97759 101.547) (end 206.729517 101.547) (width 0.13) (layer "In9.Cu") (net 888))
  (segment (start 241.753 121.303) (end 241.753 121.353) (width 0.13) (layer "In9.Cu") (net 888))
  (segment (start 236.753 107.816632) (end 236.753 110.129517) (width 0.13) (layer "In9.Cu") (net 888))
  (segment (start 211.461372 101.344996) (end 211.716929 101.600553) (width 0.13) (layer "In9.Cu") (net 888))
  (segment (start 207.616632 101.147) (end 210.983368 101.147) (width 0.13) (layer "In9.Cu") (net 888))
  (segment (start 242.053 115.83379) (end 242.053 116.76621) (width 0.13) (layer "In9.Cu") (net 888))
  (segment (start 242.299696 122.3095) (end 242.327067 122.3095) (width 0.13) (layer "In9.Cu") (net 888))
  (segment (start 241.753 117.38764) (end 241.753 120.303) (width 0.13) (layer "In9.Cu") (net 888))
  (segment (start 193.00831 99.370066) (end 193.268893 99.109483) (width 0.082) (layer "In9.Cu") (net 888))
  (segment (start 192.275921 98.124079) (end 192.277323 98.122677) (width 0.082) (layer "In9.Cu") (net 888))
  (segment (start 192.636328 98.060008) (end 192.428659 98.060008) (width 0.082) (layer "In9.Cu") (net 888))
  (segment (start 192.397756 99.414) (end 192.902244 99.414) (width 0.082) (layer "In9.Cu") (net 888))
  (segment (start 192.266262 99.344638) (end 192.29169 99.370066) (width 0.082) (layer "In9.Cu") (net 888))
  (arc (start 242.101431 120.553) (mid 242.278208 120.626223) (end 242.351431 120.803) (width 0.13) (layer "In9.Cu") (net 888))
  (arc (start 193.49941 99.014) (mid 193.374655 99.038815) (end 193.268893 99.109483) (width 0.082) (layer "In9.Cu") (net 888))
  (arc (start 206.729517 101.547) (mid 206.920858 101.50894) (end 207.08307 101.400554) (width 0.13) (layer "In9.Cu") (net 888))
  (arc (start 193.00831 99.370066) (mid 192.959647 99.402582) (end 192.902244 99.414) (width 0.082) (layer "In9.Cu") (net 888))
  (arc (start 230.476261 101.747) (mid 230.926297 101.836518) (end 231.307819 102.091443) (width 0.13) (layer "In9.Cu") (net 888))
  (arc (start 241.753 121.597118) (mid 241.79106 121.788459) (end 241.899446 121.950671) (width 0.13) (layer "In9.Cu") (net 888))
  (arc (start 242.053 116.76621) (mid 242.016767 116.948367) (end 241.913583 117.102793) (width 0.13) (layer "In9.Cu") (net 888))
  (arc (start 241.913583 115.497207) (mid 242.016767 115.651633) (end 242.053 115.83379) (width 0.13) (layer "In9.Cu") (net 888))
  (arc (start 210.983368 101.147) (mid 211.242062 101.198458) (end 211.461372 101.344996) (width 0.13) (layer "In9.Cu") (net 888))
  (arc (start 198.270483 101.254107) (mid 198.594907 101.47088) (end 198.97759 101.547) (width 0.13) (layer "In9.Cu") (net 888))
  (arc (start 242.003 121.053) (mid 241.826223 121.126223) (end 241.753 121.303) (width 0.13) (layer "In9.Cu") (net 888))
  (arc (start 236.555004 107.338628) (mid 236.701542 107.557938) (end 236.753 107.816632) (width 0.13) (layer "In9.Cu") (net 888))
  (arc (start 242.327067 122.3095) (mid 242.365336 122.301888) (end 242.397778 122.28021) (width 0.13) (layer "In9.Cu") (net 888))
  (arc (start 242.228986 122.280211) (mid 242.261428 122.301888) (end 242.299696 122.3095) (width 0.13) (layer "In9.Cu") (net 888))
  (arc (start 195.476261 98.947) (mid 195.926296 99.036518) (end 196.307818 99.291442) (width 0.13) (layer "In9.Cu") (net 888))
  (arc (start 192.222328 98.239804) (mid 192.233746 98.182401) (end 192.266262 98.133738) (width 0.082) (layer "In9.Cu") (net 888))
  (arc (start 241.840868 117.175508) (mid 241.775836 117.272835) (end 241.753 117.38764) (width 0.13) (layer "In9.Cu") (net 888))
  (arc (start 192.222328 99.238572) (mid 192.233746 99.295975) (end 192.266262 99.344638) (width 0.082) (layer "In9.Cu") (net 888))
  (arc (start 193.86229 98.98471) (mid 193.829848 99.006388) (end 193.791579 99.014) (width 0.082) (layer "In9.Cu") (net 888))
  (arc (start 192.397756 99.414) (mid 192.340353 99.402582) (end 192.29169 99.370066) (width 0.082) (layer "In9.Cu") (net 888))
  (arc (start 241.753 120.303) (mid 241.826223 120.479777) (end 242.003 120.553) (width 0.13) (layer "In9.Cu") (net 888))
  (arc (start 211.716929 101.600553) (mid 211.879141 101.70894) (end 212.070483 101.747) (width 0.13) (layer "In9.Cu") (net 888))
  (arc (start 207.138628 101.344996) (mid 207.357938 101.198458) (end 207.616632 101.147) (width 0.13) (layer "In9.Cu") (net 888))
  (arc (start 236.753 110.129517) (mid 236.79106 110.320858) (end 236.899446 110.48307) (width 0.13) (layer "In9.Cu") (net 888))
  (arc (start 192.277323 98.122677) (mid 192.346757 98.076296) (end 192.428659 98.060008) (width 0.082) (layer "In9.Cu") (net 888))
  (arc (start 242.351431 120.803) (mid 242.278208 120.979777) (end 242.101431 121.053) (width 0.13) (layer "In9.Cu") (net 888))
  (segment (start 255.832434 100.187434) (end 256.145 100.5) (width 0.122) (layer "F.Cu") (net 891))
  (segment (start 255.603632 100.1435) (end 255.726368 100.1435) (width 0.122) (layer "F.Cu") (net 891))
  (segment (start 255.185 100.5) (end 255.497566 100.187434) (width 0.122) (layer "F.Cu") (net 891))
  (arc (start 255.726368 100.1435) (mid 255.783771 100.154918) (end 255.832434 100.187434) (width 0.122) (layer "F.Cu") (net 891))
  (arc (start 255.603632 100.1435) (mid 255.546229 100.154918) (end 255.497566 100.187434) (width 0.122) (layer "F.Cu") (net 891))
  (segment (start 255.822434 99.812566) (end 256.135 99.5) (width 0.122) (layer "F.Cu") (net 892))
  (segment (start 255.185 99.5) (end 255.497566 99.812566) (width 0.122) (layer "F.Cu") (net 892))
  (segment (start 255.603632 99.8565) (end 255.716368 99.8565) (width 0.122) (layer "F.Cu") (net 892))
  (arc (start 255.603632 99.8565) (mid 255.546229 99.845082) (end 255.497566 99.812566) (width 0.122) (layer "F.Cu") (net 892))
  (arc (start 255.716368 99.8565) (mid 255.773771 99.845082) (end 255.822434 99.812566) (width 0.122) (layer "F.Cu") (net 892))
  (segment (start 243.36056 120.4635) (end 242.6565 119.75944) (width 0.122) (layer "F.Cu") (net 893))
  (segment (start 242.6565 119.2415) (end 242.3 118.885) (width 0.122) (layer "F.Cu") (net 893))
  (segment (start 242.6565 119.75944) (end 242.6565 119.2415) (width 0.122) (layer "F.Cu") (net 893))
  (segment (start 244.287901 120.82) (end 243.931401 120.4635) (width 0.122) (layer "F.Cu") (net 893))
  (segment (start 243.931401 120.4635) (end 243.36056 120.4635) (width 0.122) (layer "F.Cu") (net 893))
  (segment (start 242.9435 119.64056) (end 243.05147 119.74853) (width 0.122) (layer "F.Cu") (net 894))
  (segment (start 243.47944 120.1765) (end 243.931401 120.1765) (width 0.122) (layer "F.Cu") (net 894))
  (segment (start 243.228247 119.748529) (end 243.228246 119.74853) (width 0.122) (layer "F.Cu") (net 894))
  (segment (start 243.931401 120.1765) (end 244.287901 119.82) (width 0.122) (layer "F.Cu") (net 894))
  (segment (start 243.3 118.885) (end 242.9435 119.2415) (width 0.122) (layer "F.Cu") (net 894))
  (segment (start 242.9435 119.2415) (end 242.9435 119.64056) (width 0.122) (layer "F.Cu") (net 894))
  (segment (start 243.472201 119.858127) (end 243.472202 119.858126) (width 0.122) (layer "F.Cu") (net 894))
  (segment (start 243.472202 119.858126) (end 243.405023 119.925306) (width 0.122) (layer "F.Cu") (net 894))
  (segment (start 243.405022 120.102082) (end 243.47944 120.1765) (width 0.122) (layer "F.Cu") (net 894))
  (segment (start 243.228246 119.74853) (end 243.295426 119.681351) (width 0.122) (layer "F.Cu") (net 894))
  (segment (start 243.405023 120.102082) (end 243.405022 120.102082) (width 0.122) (layer "F.Cu") (net 894))
  (segment (start 243.472202 119.681351) (end 243.472202 119.68135) (width 0.122) (layer "F.Cu") (net 894))
  (arc (start 243.405023 119.925306) (mid 243.368411 120.013694) (end 243.405023 120.102082) (width 0.122) (layer "F.Cu") (net 894))
  (arc (start 243.472202 119.68135) (mid 243.508813 119.769739) (end 243.472201 119.858127) (width 0.122) (layer "F.Cu") (net 894))
  (arc (start 243.295426 119.681351) (mid 243.383814 119.644739) (end 243.472202 119.681351) (width 0.122) (layer "F.Cu") (net 894))
  (arc (start 243.05147 119.74853) (mid 243.139859 119.785141) (end 243.228247 119.748529) (width 0.122) (layer "F.Cu") (net 894))
  (segment (start 244.195 122.975) (end 244.534711 122.635289) (width 0.122) (layer "F.Cu") (net 895))
  (segment (start 245.230692 123.03279) (end 245.557902 123.36) (width 0.122) (layer "F.Cu") (net 895))
  (segment (start 245.122334 123.0035) (end 245.159981 123.0035) (width 0.122) (layer "F.Cu") (net 895))
  (segment (start 244.712703 122.63529) (end 245.051624 122.974211) (width 0.122) (layer "F.Cu") (net 895))
  (segment (start 244.605421 122.606) (end 244.641992 122.606) (width 0.122) (layer "F.Cu") (net 895))
  (arc (start 244.534711 122.635289) (mid 244.567153 122.613612) (end 244.605421 122.606) (width 0.122) (layer "F.Cu") (net 895))
  (arc (start 245.122334 123.0035) (mid 245.084066 122.995888) (end 245.051624 122.974211) (width 0.122) (layer "F.Cu") (net 895))
  (arc (start 244.712703 122.63529) (mid 244.680261 122.613612) (end 244.641992 122.606) (width 0.122) (layer "F.Cu") (net 895))
  (arc (start 245.230692 123.03279) (mid 245.19825 123.011112) (end 245.159981 123.0035) (width 0.122) (layer "F.Cu") (net 895))
  (segment (start 244.605667 122.319) (end 244.760872 122.319) (width 0.122) (layer "F.Cu") (net 896))
  (segment (start 244.831582 122.348289) (end 245.102358 122.619064) (width 0.122) (layer "F.Cu") (net 896))
  (segment (start 245.173068 122.648353) (end 245.228128 122.648353) (width 0.122) (layer "F.Cu") (net 896))
  (segment (start 245.298839 122.619063) (end 245.557902 122.36) (width 0.122) (layer "F.Cu") (net 896))
  (segment (start 244.195 121.95) (end 244.534537 122.289537) (width 0.122) (layer "F.Cu") (net 896))
  (arc (start 244.605667 122.319) (mid 244.567172 122.311343) (end 244.534537 122.289537) (width 0.122) (layer "F.Cu") (net 896))
  (arc (start 245.298839 122.619063) (mid 245.266397 122.640741) (end 245.228128 122.648353) (width 0.122) (layer "F.Cu") (net 896))
  (arc (start 245.173068 122.648353) (mid 245.1348 122.640741) (end 245.102358 122.619064) (width 0.122) (layer "F.Cu") (net 896))
  (arc (start 244.831582 122.348289) (mid 244.79914 122.326612) (end 244.760872 122.319) (width 0.122) (layer "F.Cu") (net 896))
  (segment (start 254.215 100.5) (end 253.887789 100.172789) (width 0.122) (layer "F.Cu") (net 897))
  (segment (start 253.71011 100.17279) (end 253.5529 100.33) (width 0.122) (layer "F.Cu") (net 897))
  (segment (start 253.817079 100.1435) (end 253.780821 100.1435) (width 0.122) (layer "F.Cu") (net 897))
  (via (at 253.5529 100.33) (size 0.5) (drill 0.2) (layers "F.Cu" "B.Cu") (net 897))
  (arc (start 253.817079 100.1435) (mid 253.855347 100.151112) (end 253.887789 100.172789) (width 0.122) (layer "F.Cu") (net 897))
  (arc (start 253.780821 100.1435) (mid 253.742552 100.151112) (end 253.71011 100.17279) (width 0.122) (layer "F.Cu") (net 897))
  (segment (start 255.256368 100.1435) (end 253.801532 100.1435) (width 0.122) (layer "B.Cu") (net 897))
  (segment (start 253.695466 100.187434) (end 253.5529 100.33) (width 0.122) (layer "B.Cu") (net 897))
  (segment (start 255.445 100.635) (end 255.445 100.332132) (width 0.122) (layer "B.Cu") (net 897))
  (segment (start 255.401066 100.226066) (end 255.362434 100.187434) (width 0.122) (layer "B.Cu") (net 897))
  (arc (start 255.362434 100.187434) (mid 255.313771 100.154918) (end 255.256368 100.1435) (width 0.122) (layer "B.Cu") (net 897))
  (arc (start 253.695466 100.187434) (mid 253.744129 100.154918) (end 253.801532 100.1435) (width 0.122) (layer "B.Cu") (net 897))
  (arc (start 255.401066 100.226066) (mid 255.433582 100.274729) (end 255.445 100.332132) (width 0.122) (layer "B.Cu") (net 897))
  (segment (start 253.817079 99.8565) (end 253.784821 99.8565) (width 0.122) (layer "F.Cu") (net 898))
  (segment (start 254.215 99.5) (end 253.887789 99.827211) (width 0.122) (layer "F.Cu") (net 898))
  (segment (start 253.71411 99.82721) (end 253.5529 99.666) (width 0.122) (layer "F.Cu") (net 898))
  (via (at 253.5529 99.666) (size 0.5) (drill 0.2) (layers "F.Cu" "B.Cu") (net 898))
  (arc (start 253.887789 99.827211) (mid 253.855347 99.848888) (end 253.817079 99.8565) (width 0.122) (layer "F.Cu") (net 898))
  (arc (start 253.71411 99.82721) (mid 253.746552 99.848888) (end 253.784821 99.8565) (width 0.122) (layer "F.Cu") (net 898))
  (segment (start 253.699466 99.812566) (end 253.5529 99.666) (width 0.122) (layer "B.Cu") (net 898))
  (segment (start 255.445 99.365) (end 255.445 99.667868) (width 0.122) (layer "B.Cu") (net 898))
  (segment (start 255.401066 99.773934) (end 255.362434 99.812566) (width 0.122) (layer "B.Cu") (net 898))
  (segment (start 255.256368 99.8565) (end 253.805532 99.8565) (width 0.122) (layer "B.Cu") (net 898))
  (arc (start 253.805532 99.8565) (mid 253.748129 99.845082) (end 253.699466 99.812566) (width 0.122) (layer "B.Cu") (net 898))
  (arc (start 255.445 99.667868) (mid 255.433582 99.725271) (end 255.401066 99.773934) (width 0.122) (layer "B.Cu") (net 898))
  (arc (start 255.256368 99.8565) (mid 255.313771 99.845082) (end 255.362434 99.812566) (width 0.122) (layer "B.Cu") (net 898))
  (segment (start 246.925823 123.0035) (end 246.958081 123.0035) (width 0.122) (layer "F.Cu") (net 899))
  (segment (start 247.028792 123.03279) (end 247.190001 123.194) (width 0.122) (layer "F.Cu") (net 899))
  (segment (start 246.527902 123.36) (end 246.855113 123.032789) (width 0.122) (layer "F.Cu") (net 899))
  (via (at 247.190001 123.194) (size 0.5) (drill 0.2) (layers "F.Cu" "B.Cu") (net 899))
  (arc (start 247.028792 123.03279) (mid 246.99635 123.011112) (end 246.958081 123.0035) (width 0.122) (layer "F.Cu") (net 899))
  (arc (start 246.855113 123.032789) (mid 246.887555 123.011112) (end 246.925823 123.0035) (width 0.122) (layer "F.Cu") (net 899))
  (segment (start 247.190001 123.194) (end 247.060078 123.064078) (width 0.122) (layer "B.Cu") (net 899))
  (segment (start 246.918657 123.0055) (end 246.742343 123.005501) (width 0.122) (layer "B.Cu") (net 899))
  (segment (start 246.600921 123.064079) (end 246.584289 123.080711) (width 0.122) (layer "B.Cu") (net 899))
  (segment (start 246.555 123.151421) (end 246.555 123.495) (width 0.122) (layer "B.Cu") (net 899))
  (arc (start 246.584289 123.080711) (mid 246.562612 123.113153) (end 246.555 123.151421) (width 0.122) (layer "B.Cu") (net 899))
  (arc (start 246.918657 123.0055) (mid 246.995193 123.020725) (end 247.060078 123.064078) (width 0.122) (layer "B.Cu") (net 899))
  (arc (start 246.742343 123.005501) (mid 246.665806 123.020725) (end 246.600921 123.064079) (width 0.122) (layer "B.Cu") (net 899))
  (segment (start 247.032793 122.68721) (end 247.190002 122.53) (width 0.122) (layer "F.Cu") (net 900))
  (segment (start 246.527902 122.36) (end 246.855113 122.687211) (width 0.122) (layer "F.Cu") (net 900))
  (segment (start 246.925823 122.7165) (end 246.96208 122.7165) (width 0.122) (layer "F.Cu") (net 900))
  (via (at 247.19 122.530001) (size 0.5) (drill 0.2) (layers "F.Cu" "B.Cu") (net 900))
  (arc (start 246.96208 122.7165) (mid 247.00035 122.708888) (end 247.032793 122.68721) (width 0.122) (layer "F.Cu") (net 900))
  (arc (start 246.925823 122.7165) (mid 246.887555 122.708888) (end 246.855113 122.687211) (width 0.122) (layer "F.Cu") (net 900))
  (segment (start 246.918657 122.718501) (end 246.726342 122.718501) (width 0.122) (layer "B.Cu") (net 900))
  (segment (start 246.584921 122.65992) (end 246.58429 122.659289) (width 0.122) (layer "B.Cu") (net 900))
  (segment (start 247.19 122.530001) (end 247.060078 122.659923) (width 0.122) (layer "B.Cu") (net 900))
  (segment (start 246.555001 122.588579) (end 246.555 122.225) (width 0.122) (layer "B.Cu") (net 900))
  (arc (start 246.918657 122.718501) (mid 246.995193 122.703277) (end 247.060078 122.659923) (width 0.122) (layer "B.Cu") (net 900))
  (arc (start 246.555001 122.588579) (mid 246.562613 122.626847) (end 246.58429 122.659289) (width 0.122) (layer "B.Cu") (net 900))
  (arc (start 246.726342 122.718501) (mid 246.649807 122.703276) (end 246.584921 122.65992) (width 0.122) (layer "B.Cu") (net 900))
  (segment (start 245.257901 120.82) (end 245.585112 120.492789) (width 0.122) (layer "F.Cu") (net 903))
  (segment (start 245.655822 120.4635) (end 245.68808 120.4635) (width 0.122) (layer "F.Cu") (net 903))
  (segment (start 245.758791 120.49279) (end 245.92 120.654) (width 0.122) (layer "F.Cu") (net 903))
  (via (at 245.92 120.654) (size 0.5) (drill 0.2) (layers "F.Cu" "B.Cu") (net 903))
  (arc (start 245.758791 120.49279) (mid 245.726349 120.471112) (end 245.68808 120.4635) (width 0.122) (layer "F.Cu") (net 903))
  (arc (start 245.585112 120.492789) (mid 245.617554 120.471112) (end 245.655822 120.4635) (width 0.122) (layer "F.Cu") (net 903))
  (segment (start 245.648657 120.4655) (end 245.472343 120.4655) (width 0.122) (layer "B.Cu") (net 903))
  (segment (start 245.92 120.654) (end 245.790078 120.524078) (width 0.122) (layer "B.Cu") (net 903))
  (segment (start 245.285 120.611422) (end 245.285 120.955001) (width 0.122) (layer "B.Cu") (net 903))
  (segment (start 245.330922 120.524079) (end 245.314289 120.540712) (width 0.122) (layer "B.Cu") (net 903))
  (arc (start 245.314289 120.540712) (mid 245.292612 120.573154) (end 245.285 120.611422) (width 0.122) (layer "B.Cu") (net 903))
  (arc (start 245.472343 120.4655) (mid 245.395806 120.480724) (end 245.330922 120.524079) (width 0.122) (layer "B.Cu") (net 903))
  (arc (start 245.648657 120.4655) (mid 245.725193 120.480724) (end 245.790078 120.524078) (width 0.122) (layer "B.Cu") (net 903))
  (segment (start 245.655822 120.1765) (end 245.692079 120.1765) (width 0.122) (layer "F.Cu") (net 904))
  (segment (start 245.762792 120.14721) (end 245.920001 119.99) (width 0.122) (layer "F.Cu") (net 904))
  (segment (start 245.257901 119.82) (end 245.585112 120.147211) (width 0.122) (layer "F.Cu") (net 904))
  (via (at 245.92 119.99) (size 0.5) (drill 0.2) (layers "F.Cu" "B.Cu") (net 904))
  (arc (start 245.655822 120.1765) (mid 245.617554 120.168888) (end 245.585112 120.147211) (width 0.122) (layer "F.Cu") (net 904))
  (arc (start 245.692079 120.1765) (mid 245.730349 120.168888) (end 245.762792 120.14721) (width 0.122) (layer "F.Cu") (net 904))
  (segment (start 245.92 119.99) (end 245.790078 120.119922) (width 0.122) (layer "B.Cu") (net 904))
  (segment (start 245.648657 120.1785) (end 245.456343 120.1785) (width 0.122) (layer "B.Cu") (net 904))
  (segment (start 245.285 120.048579) (end 245.285 119.685) (width 0.122) (layer "B.Cu") (net 904))
  (segment (start 245.314921 120.119921) (end 245.314289 120.119289) (width 0.122) (layer "B.Cu") (net 904))
  (arc (start 245.648657 120.1785) (mid 245.725193 120.163276) (end 245.790078 120.119922) (width 0.122) (layer "B.Cu") (net 904))
  (arc (start 245.456343 120.1785) (mid 245.379806 120.163276) (end 245.314921 120.119921) (width 0.122) (layer "B.Cu") (net 904))
  (arc (start 245.285 120.048579) (mid 245.292612 120.086847) (end 245.314289 120.119289) (width 0.122) (layer "B.Cu") (net 904))
  (segment (start 257.332775 90.3) (end 256.685 90.3) (width 0.127) (layer "F.Cu") (net 907))
  (segment (start 175.136328 95.560008) (end 175.160008 95.560008) (width 0.127) (layer "F.Cu") (net 907))
  (segment (start 175.160008 95.560008) (end 175.65 96.05) (width 0.127) (layer "F.Cu") (net 907))
  (segment (start 257.786973 90.754198) (end 257.332775 90.3) (width 0.127) (layer "F.Cu") (net 907))
  (via (at 175.65 96.05) (size 0.5) (drill 0.2) (layers "F.Cu" "B.Cu") (net 907))
  (via (at 254.6 88.65) (size 0.5) (drill 0.2) (layers "F.Cu" "B.Cu") (net 907))
  (via (at 257.786973 90.754198) (size 0.5) (drill 0.2) (layers "F.Cu" "B.Cu") (net 907))
  (segment (start 257.786973 90.754198) (end 256.704198 90.754198) (width 0.127) (layer "In7.Cu") (net 907))
  (segment (start 256.704198 90.754198) (end 254.6 88.65) (width 0.127) (layer "In7.Cu") (net 907))
  (segment (start 214.65 112.75) (end 217.45 112.75) (width 0.1) (layer "B.Cu") (net 907))
  (segment (start 171.246328 99.296328) (end 171.55 99.6) (width 0.1) (layer "B.Cu") (net 907))
  (segment (start 220.7 127.2) (end 220.7 130.825) (width 0.1) (layer "B.Cu") (net 907))
  (segment (start 172.374792 96.55) (end 172.26 96.664792) (width 0.1) (layer "B.Cu") (net 907))
  (segment (start 171.246328 98.803672) (end 171.246328 99.296328) (width 0.1) (layer "B.Cu") (net 907))
  (segment (start 254.41658 128.074001) (end 256.290581 126.2) (width 0.1) (layer "B.Cu") (net 907))
  (segment (start 223.783336 115.733336) (end 225.95 117.9) (width 0.1) (layer "B.Cu") (net 907))
  (segment (start 171.8 99.6) (end 172.246328 100.046328) (width 0.1) (layer "B.Cu") (net 907))
  (segment (start 171.85 98.6) (end 171.45 98.6) (width 0.1) (layer "B.Cu") (net 907))
  (segment (start 247.45 128.2) (end 249.2 126.45) (width 0.1) (layer "B.Cu") (net 907))
  (segment (start 172.26 96.664792) (end 172.26 97.211544) (width 0.1) (layer "B.Cu") (net 907))
  (segment (start 218.2 113.5) (end 219.65 113.5) (width 0.1) (layer "B.Cu") (net 907))
  (segment (start 175.15 96.55) (end 172.374792 96.55) (width 0.1) (layer "B.Cu") (net 907))
  (segment (start 171.55 99.6) (end 171.8 99.6) (width 0.1) (layer "B.Cu") (net 907))
  (segment (start 172.246328 102.321328) (end 172.8 102.875) (width 0.1) (layer "B.Cu") (net 907))
  (segment (start 242.4 132.9) (end 244.25 131.05) (width 0.1) (layer "B.Cu") (net 907))
  (segment (start 257.96 90.927225) (end 257.786973 90.754198) (width 0.1) (layer "B.Cu") (net 907))
  (segment (start 172.3 97.251544) (end 172.3 98.15) (width 0.1) (layer "B.Cu") (net 907))
  (segment (start 257.76 125.44) (end 257.76 101.75) (width 0.1) (layer "B.Cu") (net 907))
  (segment (start 185.65 106.95) (end 187 108.3) (width 0.1) (layer "B.Cu") (net 907))
  (segment (start 256.290581 126.2) (end 257 126.2) (width 0.1) (layer "B.Cu") (net 907))
  (segment (start 240.3 133.3) (end 240.7 132.9) (width 0.1) (layer "B.Cu") (net 907))
  (segment (start 172.8 102.875) (end 172.8 103.05) (width 0.1) (layer "B.Cu") (net 907))
  (segment (start 253.524001 128.074001) (end 254.41658 128.074001) (width 0.1) (layer "B.Cu") (net 907))
  (segment (start 172.26 97.211544) (end 172.3 97.251544) (width 0.1) (layer "B.Cu") (net 907))
  (segment (start 217.45 112.75) (end 218.2 113.5) (width 0.1) (layer "B.Cu") (net 907))
  (segment (start 225.95 117.9) (end 225.95 120.35) (width 0.1) (layer "B.Cu") (net 907))
  (segment (start 223.175 133.3) (end 240.3 133.3) (width 0.1) (layer "B.Cu") (net 907))
  (segment (start 221.063272 125.236728) (end 221.065 125.238456) (width 0.1) (layer "B.Cu") (net 907))
  (segment (start 220.285 126.785) (end 220.7 127.2) (width 0.1) (layer "B.Cu") (net 907))
  (segment (start 222.4 114.4) (end 223.341 115.341) (width 0.1) (layer "B.Cu") (net 907))
  (segment (start 244.25 131.05) (end 244.25 129.85) (width 0.1) (layer "B.Cu") (net 907))
  (segment (start 187 108.3) (end 210.2 108.3) (width 0.1) (layer "B.Cu") (net 907))
  (segment (start 176.7 106.95) (end 185.65 106.95) (width 0.1) (layer "B.Cu") (net 907))
  (segment (start 251.9 126.45) (end 253.524001 128.074001) (width 0.1) (layer "B.Cu") (net 907))
  (segment (start 225.95 120.35) (end 221.063272 125.236728) (width 0.1) (layer "B.Cu") (net 907))
  (segment (start 223.55488 115.341) (end 223.783336 115.569456) (width 0.1) (layer "B.Cu") (net 907))
  (segment (start 221.065 125.635) (end 220.8 125.9) (width 0.1) (layer "B.Cu") (net 907))
  (segment (start 210.2 108.3) (end 214.65 112.75) (width 0.1) (layer "B.Cu") (net 907))
  (segment (start 171.45 98.6) (end 171.246328 98.803672) (width 0.1) (layer "B.Cu") (net 907))
  (segment (start 175.65 96.05) (end 175.15 96.55) (width 0.1) (layer "B.Cu") (net 907))
  (segment (start 244.25 129.85) (end 245.9 128.2) (width 0.1) (layer "B.Cu") (net 907))
  (segment (start 223.341 115.341) (end 223.55488 115.341) (width 0.1) (layer "B.Cu") (net 907))
  (segment (start 254.175 87.935) (end 254.6 88.36) (width 0.127) (layer "B.Cu") (net 907))
  (segment (start 220.499228 125.9) (end 220.285 126.114228) (width 0.1) (layer "B.Cu") (net 907))
  (segment (start 223.783336 115.569456) (end 223.783336 115.733336) (width 0.1) (layer "B.Cu") (net 907))
  (segment (start 254.6 88.36) (end 254.6 88.65) (width 0.127) (layer "B.Cu") (net 907))
  (segment (start 220.7 130.825) (end 223.175 133.3) (width 0.1) (layer "B.Cu") (net 907))
  (segment (start 172.246328 100.046328) (end 172.246328 102.321328) (width 0.1) (layer "B.Cu") (net 907))
  (segment (start 220.8 125.9) (end 220.499228 125.9) (width 0.1) (layer "B.Cu") (net 907))
  (segment (start 240.7 132.9) (end 242.4 132.9) (width 0.1) (layer "B.Cu") (net 907))
  (segment (start 257.76 101.75) (end 258.37 101.14) (width 0.1) (layer "B.Cu") (net 907))
  (segment (start 220.55 114.4) (end 222.4 114.4) (width 0.1) (layer "B.Cu") (net 907))
  (segment (start 221.065 125.238456) (end 221.065 125.635) (width 0.1) (layer "B.Cu") (net 907))
  (segment (start 258.37 99.43) (end 257.96 99.02) (width 0.1) (layer "B.Cu") (net 907))
  (segment (start 249.2 126.45) (end 251.9 126.45) (width 0.1) (layer "B.Cu") (net 907))
  (segment (start 257.96 99.02) (end 257.96 90.927225) (width 0.1) (layer "B.Cu") (net 907))
  (segment (start 257 126.2) (end 257.76 125.44) (width 0.1) (layer "B.Cu") (net 907))
  (segment (start 172.8 103.05) (end 176.7 106.95) (width 0.1) (layer "B.Cu") (net 907))
  (segment (start 219.65 113.5) (end 220.55 114.4) (width 0.1) (layer "B.Cu") (net 907))
  (segment (start 245.9 128.2) (end 247.45 128.2) (width 0.1) (layer "B.Cu") (net 907))
  (segment (start 258.37 101.14) (end 258.37 99.43) (width 0.1) (layer "B.Cu") (net 907))
  (segment (start 172.3 98.15) (end 171.85 98.6) (width 0.1) (layer "B.Cu") (net 907))
  (segment (start 220.285 126.114228) (end 220.285 126.785) (width 0.1) (layer "B.Cu") (net 907))
  (segment (start 173.110008 96.560008) (end 172.65 96.1) (width 0.127) (layer "F.Cu") (net 908))
  (segment (start 173.136328 96.560008) (end 173.110008 96.560008) (width 0.127) (layer "F.Cu") (net 908))
  (segment (start 256.685 89.3) (end 257.8 89.3) (width 0.127) (layer "F.Cu") (net 908))
  (via (at 172.65 96.1) (size 0.5) (drill 0.2) (layers "F.Cu" "B.Cu") (net 908))
  (via (at 254.6 86) (size 0.5) (drill 0.2) (layers "F.Cu" "B.Cu") (net 908))
  (via (at 257.8 89.3) (size 0.5) (drill 0.2) (layers "F.Cu" "B.Cu") (net 908))
  (segment (start 254.6 86) (end 254.6 87.3) (width 0.127) (layer "In7.Cu") (net 908))
  (segment (start 255.652074 88.68271) (end 256.269364 89.3) (width 0.127) (layer "In7.Cu") (net 908))
  (segment (start 255.652074 88.352074) (end 255.652074 88.68271) (width 0.127) (layer "In7.Cu") (net 908))
  (segment (start 256.269364 89.3) (end 257.8 89.3) (width 0.127) (layer "In7.Cu") (net 908))
  (segment (start 254.6 87.3) (end 255.652074 88.352074) (width 0.127) (layer "In7.Cu") (net 908))
  (segment (start 258.3 90.55) (end 257.8 90.05) (width 0.1) (layer "B.Cu") (net 908))
  (segment (start 220.2 130.9) (end 223 133.7) (width 0.1) (layer "B.Cu") (net 908))
  (segment (start 258.15 125.65) (end 258.15 102) (width 0.1) (layer "B.Cu") (net 908))
  (segment (start 257.25 126.55) (end 258.15 125.65) (width 0.1) (layer "B.Cu") (net 908))
  (segment (start 172.2 103.483812) (end 176.296188 107.58) (width 0.1) (layer "B.Cu") (net 908))
  (segment (start 171.474784 97.670008) (end 171.15 97.994792) (width 0.1) (layer "B.Cu") (net 908))
  (segment (start 171.1 99.736068) (end 171.1 100.25) (width 0.1) (layer "B.Cu") (net 908))
  (segment (start 171.85 102.5) (end 172.2 102.85) (width 0.1) (layer "B.Cu") (net 908))
  (segment (start 256.45 126.55) (end 257.25 126.55) (width 0.1) (layer "B.Cu") (net 908))
  (segment (start 219.9 125.623456) (end 219.9 127.05) (width 0.1) (layer "B.Cu") (net 908))
  (segment (start 220.4 114.8) (end 222.1 114.8) (width 0.1) (layer "B.Cu") (net 908))
  (segment (start 171.2 101.8) (end 171.2 102.35) (width 0.1) (layer "B.Cu") (net 908))
  (segment (start 223.231792 116.121) (end 223.421 116.121) (width 0.1) (layer "B.Cu") (net 908))
  (segment (start 258.3 98.8) (end 258.3 90.55) (width 0.1) (layer "B.Cu") (net 908))
  (segment (start 242.498958 133.2) (end 244.6 131.098958) (width 0.1) (layer "B.Cu") (net 908))
  (segment (start 223 133.7) (end 240.35 133.7) (width 0.1) (layer "B.Cu") (net 908))
  (segment (start 244.6 131.098958) (end 244.6 130.05) (width 0.1) (layer "B.Cu") (net 908))
  (segment (start 171.2 102.35) (end 171.35 102.5) (width 0.1) (layer "B.Cu") (net 908))
  (segment (start 172.2 102.85) (end 172.2 103.483812) (width 0.1) (layer "B.Cu") (net 908))
  (segment (start 223.003336 115.703336) (end 223.003336 115.892544) (width 0.1) (layer "B.Cu") (net 908))
  (segment (start 209.85 108.65) (end 214.4 113.2) (width 0.1) (layer "B.Cu") (net 908))
  (segment (start 223.851544 122) (end 223.523456 122) (width 0.1) (layer "B.Cu") (net 908))
  (segment (start 247.65 128.45) (end 249.4 126.7) (width 0.1) (layer "B.Cu") (net 908))
  (segment (start 253.45 128.5) (end 254.5 128.5) (width 0.1) (layer "B.Cu") (net 908))
  (segment (start 258.66 99.16) (end 258.3 98.8) (width 0.1) (layer "B.Cu") (net 908))
  (segment (start 217.875 113.8) (end 219.4 113.8) (width 0.1) (layer "B.Cu") (net 908))
  (segment (start 214.4 113.2) (end 217.275 113.2) (width 0.1) (layer "B.Cu") (net 908))
  (segment (start 254.175 86.665) (end 254.285 86.665) (width 0.127) (layer "B.Cu") (net 908))
  (segment (start 171.45 100.6) (end 171.727864 100.6) (width 0.1) (layer "B.Cu") (net 908))
  (segment (start 170.4 99.55) (end 170.913932 99.55) (width 0.1) (layer "B.Cu") (net 908))
  (segment (start 172.3 96.1) (end 171.95 96.45) (width 0.1) (layer "B.Cu") (net 908))
  (segment (start 171.77394 101.55) (end 171.45 101.55) (width 0.1) (layer "B.Cu") (net 908))
  (segment (start 217.275 113.2) (end 217.875 113.8) (width 0.1) (layer "B.Cu") (net 908))
  (segment (start 219.9 127.05) (end 220.2 127.35) (width 0.1) (layer "B.Cu") (net 908))
  (segment (start 223.003336 115.892544) (end 223.231792 116.121) (width 0.1) (layer "B.Cu") (net 908))
  (segment (start 172.026328 97.441552) (end 171.797872 97.670008) (width 0.1) (layer "B.Cu") (net 908))
  (segment (start 240.35 133.7) (end 240.85 133.2) (width 0.1) (layer "B.Cu") (net 908))
  (segment (start 170.95 98.55) (end 170.5 98.55) (width 0.1) (layer "B.Cu") (net 908))
  (segment (start 254.285 86.665) (end 254.6 86.35) (width 0.127) (layer "B.Cu") (net 908))
  (segment (start 258.15 102) (end 258.66 101.49) (width 0.1) (layer "B.Cu") (net 908))
  (segment (start 172.026328 96.898464) (end 172.026328 97.441552) (width 0.1) (layer "B.Cu") (net 908))
  (segment (start 254.6 86.35) (end 254.6 86) (width 0.127) (layer "B.Cu") (net 908))
  (segment (start 171.15 98.35) (end 170.95 98.55) (width 0.1) (layer "B.Cu") (net 908))
  (segment (start 220.2 127.35) (end 220.2 130.9) (width 0.1) (layer "B.Cu") (net 908))
  (segment (start 246.2 128.45) (end 247.65 128.45) (width 0.1) (layer "B.Cu") (net 908))
  (segment (start 171.15 97.994792) (end 171.15 98.35) (width 0.1) (layer "B.Cu") (net 908))
  (segment (start 171.797872 97.670008) (end 171.474784 97.670008) (width 0.1) (layer "B.Cu") (net 908))
  (segment (start 172.026328 101.297612) (end 171.77394 101.55) (width 0.1) (layer "B.Cu") (net 908))
  (segment (start 224.325772 121.374228) (end 224.325772 121.525772) (width 0.1) (layer "B.Cu") (net 908))
  (segment (start 223.523456 122) (end 219.9 125.623456) (width 0.1) (layer "B.Cu") (net 908))
  (segment (start 171.95 96.45) (end 171.95 96.822136) (width 0.1) (layer "B.Cu") (net 908))
  (segment (start 249.4 126.7) (end 251.65 126.7) (width 0.1) (layer "B.Cu") (net 908))
  (segment (start 171.95 96.822136) (end 172.026328 96.898464) (width 0.1) (layer "B.Cu") (net 908))
  (segment (start 171.35 102.5) (end 171.85 102.5) (width 0.1) (layer "B.Cu") (net 908))
  (segment (start 171.727864 100.6) (end 172.026328 100.898464) (width 0.1) (layer "B.Cu") (net 908))
  (segment (start 224.325772 121.525772) (end 223.851544 122) (width 0.1) (layer "B.Cu") (net 908))
  (segment (start 225.55 120.15) (end 224.325772 121.374228) (width 0.1) (layer "B.Cu") (net 908))
  (segment (start 170.913932 99.55) (end 171.1 99.736068) (width 0.1) (layer "B.Cu") (net 908))
  (segment (start 258.66 101.49) (end 258.66 99.16) (width 0.1) (layer "B.Cu") (net 908))
  (segment (start 185.38 107.58) (end 186.45 108.65) (width 0.1) (layer "B.Cu") (net 908))
  (segment (start 170.2 99.35) (end 170.4 99.55) (width 0.1) (layer "B.Cu") (net 908))
  (segment (start 186.45 108.65) (end 209.85 108.65) (width 0.1) (layer "B.Cu") (net 908))
  (segment (start 172.026328 100.898464) (end 172.026328 101.297612) (width 0.1) (layer "B.Cu") (net 908))
  (segment (start 176.296188 107.58) (end 185.38 107.58) (width 0.1) (layer "B.Cu") (net 908))
  (segment (start 240.85 133.2) (end 242.498958 133.2) (width 0.1) (layer "B.Cu") (net 908))
  (segment (start 257.8 90.05) (end 257.8 89.3) (width 0.1) (layer "B.Cu") (net 908))
  (segment (start 244.6 130.05) (end 246.2 128.45) (width 0.1) (layer "B.Cu") (net 908))
  (segment (start 254.5 128.5) (end 256.45 126.55) (width 0.1) (layer "B.Cu") (net 908))
  (segment (start 172.65 96.1) (end 172.3 96.1) (width 0.1) (layer "B.Cu") (net 908))
  (segment (start 225.55 118.25) (end 225.55 120.15) (width 0.1) (layer "B.Cu") (net 908))
  (segment (start 251.65 126.7) (end 253.45 128.5) (width 0.1) (layer "B.Cu") (net 908))
  (segment (start 170.2 98.85) (end 170.2 99.35) (width 0.1) (layer "B.Cu") (net 908))
  (segment (start 223.421 116.121) (end 225.55 118.25) (width 0.1) (layer "B.Cu") (net 908))
  (segment (start 170.5 98.55) (end 170.2 98.85) (width 0.1) (layer "B.Cu") (net 908))
  (segment (start 219.4 113.8) (end 220.4 114.8) (width 0.1) (layer "B.Cu") (net 908))
  (segment (start 222.1 114.8) (end 223.003336 115.703336) (width 0.1) (layer "B.Cu") (net 908))
  (segment (start 171.45 101.55) (end 171.2 101.8) (width 0.1) (layer "B.Cu") (net 908))
  (segment (start 171.1 100.25) (end 171.45 100.6) (width 0.1) (layer "B.Cu") (net 908))

  (zone (net 304) (net_name "VCC3V3") (layer "F.Cu") (hatch edge 0.508)
    (priority 3)
    (connect_pads yes (clearance 0.125))
    (min_thickness 0.125) (filled_areas_thickness no)
    (fill yes (thermal_gap 0.15) (thermal_bridge_width 0.151) (smoothing fillet) (radius 0.2))
    (polygon
      (pts
        (xy 121.076328 109.9)
        (xy 120.176328 109.9)
        (xy 120.176328 111.620008)
        (xy 115.896328 111.620008)
        (xy 115.496328 111.220008)
        (xy 114.206328 111.220008)
        (xy 114.206328 109.910008)
        (xy 113.371328 109.910008)
        (xy 113.371328 107.960008)
        (xy 114.586328 107.960008)
        (xy 114.586328 106.830008)
        (xy 115.706328 106.830008)
        (xy 115.696328 108.610008)
        (xy 119.896328 108.610008)
        (xy 119.896328 109.090008)
        (xy 121.076328 109.090008)
      )
    )
  )
  (zone (net 50) (net_name "Net-(U9-SW)") (layer "F.Cu") (hatch edge 0.508)
    (priority 3)
    (connect_pads yes (clearance 0.125))
    (min_thickness 0.125) (filled_areas_thickness no)
    (fill yes (thermal_gap 0.15) (thermal_bridge_width 0.151) (smoothing fillet) (radius 0.5))
    (polygon
      (pts
        (xy 120.546328 105.690008)
        (xy 122.306328 105.690008)
        (xy 122.306328 108.170008)
        (xy 121.466328 108.170008)
        (xy 121.466328 106.780008)
        (xy 119.896328 106.780008)
        (xy 119.896328 108.340008)
        (xy 116.008329 108.330008)
        (xy 116.004327 106.110008)
        (xy 119.061987 106.120032)
        (xy 119.066328 105.060008)
        (xy 119.916328 105.060008)
      )
    )
  )
  (zone (net 9) (net_name "GND") (layer "F.Cu") (hatch edge 0.508)
    (priority 6)
    (connect_pads yes (clearance 0.125))
    (min_thickness 0.125) (filled_areas_thickness no)
    (fill yes (thermal_gap 0.15) (thermal_bridge_width 0.151) (smoothing fillet) (radius 0.5))
    (polygon
      (pts
        (xy 124.646328 107.510008)
        (xy 124.646328 108.430008)
        (xy 124.046328 109.030008)
        (xy 120.046328 109.030008)
        (xy 120.046328 106.840008)
        (xy 121.476328 106.840008)
        (xy 121.476328 108.310008)
        (xy 123.766328 108.310008)
        (xy 123.766328 107.510008)
      )
    )
  )
  (zone (net 104) (net_name "VCC5V0") (layer "F.Cu") (hatch edge 0.508)
    (priority 2)
    (connect_pads yes (clearance 0.12))
    (min_thickness 0.15) (filled_areas_thickness no)
    (fill yes (thermal_gap 0.508) (thermal_bridge_width 0.508) (smoothing fillet) (radius 0.5))
    (polygon
      (pts
        (xy 131.686328 111.560008)
        (xy 121.136328 111.560008)
        (xy 121.136328 110.7)
        (xy 120.35 110.7)
        (xy 120.35 110.05)
        (xy 121.136328 110.05)
        (xy 121.136328 109.060008)
        (xy 122.416328 109.060008)
        (xy 124.136328 109.060008)
        (xy 124.84 108.35)
        (xy 125.86 108.35)
        (xy 125.866328 104.540008)
        (xy 125.556336 104.2278)
        (xy 123.326328 104.230008)
        (xy 123.331328 103.000008)
        (xy 127.814484 103)
        (xy 127.798156 100.462179)
        (xy 132.5 100.45)
        (xy 132.5 102.2)
        (xy 131.686328 103)
      )
    )
  )
  (zone (net 49) (net_name "Net-(U9-BST)") (layer "F.Cu") (hatch edge 0.508)
    (priority 1)
    (connect_pads yes (clearance 0.125))
    (min_thickness 0.125) (filled_areas_thickness no)
    (fill yes (thermal_gap 0.15) (thermal_bridge_width 0.151) (smoothing fillet) (radius 0.5))
    (polygon
      (pts
        (xy 121.366328 105.520008)
        (xy 120.616328 105.520008)
        (xy 119.916328 104.820008)
        (xy 119.226328 104.820008)
        (xy 119.226328 104.100008)
        (xy 121.366328 104.100008)
      )
    )
  )
  (zone (net 644) (net_name "Net-(U9-FB)") (layer "F.Cu") (hatch edge 0.508)
    (priority 5)
    (connect_pads yes (clearance 0.125))
    (min_thickness 0.125) (filled_areas_thickness no)
    (fill yes (thermal_gap 0.15) (thermal_bridge_width 0.151) (smoothing fillet) (radius 0.5))
    (polygon
      (pts
        (xy 125.716328 104.590008)
        (xy 125.716328 105.300008)
        (xy 123.276328 105.300008)
        (xy 123.276328 105.570008)
        (xy 122.516328 105.570008)
        (xy 122.516328 104.330008)
        (xy 125.456328 104.330008)
      )
    )
  )
  (zone (net 9) (net_name "GND") (layer "F.Cu") (hatch edge 0.508)
    (priority 5)
    (connect_pads yes (clearance 0.125))
    (min_thickness 0.125) (filled_areas_thickness no)
    (fill yes (thermal_gap 0.15) (thermal_bridge_width 0.151) (smoothing fillet) (radius 0.5))
    (polygon
      (pts
        (xy 124.668828 106.275008)
        (xy 123.343828 106.285008)
        (xy 123.346328 105.590008)
        (xy 124.666328 105.590008)
      )
    )
  )
  (zone (net 9) (net_name "GND") (layer "F.Cu") (hatch edge 0.508)
    (priority 1)
    (connect_pads yes (clearance 0.125))
    (min_thickness 0.125) (filled_areas_thickness no)
    (fill yes (thermal_gap 0.15) (thermal_bridge_width 0.151) (smoothing fillet) (radius 0.5))
    (polygon
      (pts
        (xy 114.141328 111.110008)
        (xy 112.476328 111.110008)
        (xy 112.476328 110.840008)
        (xy 112.146328 110.840008)
        (xy 112.146328 110.050008)
        (xy 114.146328 110.050008)
      )
    )
  )
  (zone (net 9) (net_name "GND") (layer "F.Cu") (hatch edge 0.508)
    (priority 1)
    (connect_pads yes (clearance 0.125))
    (min_thickness 0.125) (filled_areas_thickness no)
    (fill yes (thermal_gap 0.15) (thermal_bridge_width 0.151) (smoothing fillet) (radius 0.2))
    (polygon
      (pts
        (xy 142.75 81)
        (xy 144.95 81)
        (xy 144.950261 82.159853)
        (xy 142.113859 82.155008)
        (xy 142.119072 80.140008)
        (xy 142.748828 80.140008)
      )
    )
  )
  (zone (net 614) (net_name "Net-(U4-FB)") (layer "F.Cu") (hatch edge 0.508)
    (connect_pads yes (clearance 0.125))
    (min_thickness 0.125) (filled_areas_thickness no)
    (fill yes (thermal_gap 0.15) (thermal_bridge_width 0.151) (smoothing fillet) (radius 0.5))
    (polygon
      (pts
        (xy 140.416328 91.170008)
        (xy 141.416328 91.170008)
        (xy 141.411328 92.010008)
        (xy 138.981328 92.010008)
        (xy 138.986328 89.680008)
        (xy 140.416328 89.680008)
      )
    )
  )
  (zone (net 2) (net_name "Net-(U4-BST)") (layer "F.Cu") (hatch edge 0.508)
    (connect_pads yes (clearance 0.125))
    (min_thickness 0.125) (filled_areas_thickness no)
    (fill yes (thermal_gap 0.15) (thermal_bridge_width 0.151) (smoothing fillet) (radius 0.5))
    (polygon
      (pts
        (xy 140.276328 88.220008)
        (xy 141.326328 88.220008)
        (xy 141.326328 88.940008)
        (xy 140.396328 88.940008)
        (xy 140.396328 88.590008)
        (xy 139.026328 88.590008)
        (xy 139.026328 87.800008)
        (xy 140.276328 87.800008)
      )
    )
  )
  (zone (net 300) (net_name "VCC1V0") (layer "F.Cu") (hatch edge 0.508)
    (connect_pads yes (clearance 0.12))
    (min_thickness 0.125) (filled_areas_thickness no)
    (fill yes (thermal_gap 0.15) (thermal_bridge_width 0.151) (smoothing fillet) (radius 0.5))
    (polygon
      (pts
        (xy 142.011328 82.535008)
        (xy 142.761328 82.535008)
        (xy 142.761328 84.760008)
        (xy 142.011328 84.760008)
        (xy 142.011328 86.860008)
        (xy 143 86.860008)
        (xy 143 88.7)
        (xy 143.7 89.3)
        (xy 143.7 90.8)
        (xy 142.386336 90.798698)
        (xy 142.39 88.18)
        (xy 140.91 86.7)
        (xy 140.913828 84.330008)
        (xy 136.538828 84.330008)
        (xy 136.511328 80.985008)
        (xy 142.011328 80.985008)
      )
    )
  )
  (zone (net 3) (net_name "Net-(U4-SW)") (layer "F.Cu") (hatch edge 0.508)
    (connect_pads yes (clearance 0.12))
    (min_thickness 0.125) (filled_areas_thickness no)
    (fill yes (thermal_gap 0.15) (thermal_bridge_width 0.151) (smoothing fillet) (radius 0.5))
    (polygon
      (pts
        (xy 140.636328 87.010008)
        (xy 140.886328 87.260008)
        (xy 141.261328 87.260008)
        (xy 141.261328 88.010008)
        (xy 140.411328 88.010008)
        (xy 140.411328 87.810008)
        (xy 140.186328 87.585008)
        (xy 138.796328 87.580008)
        (xy 138.796328 89.480008)
        (xy 136.411328 89.485008)
        (xy 136.403828 84.550008)
        (xy 140.628828 84.550008)
      )
    )
  )
  (zone (net 52) (net_name "Net-(U12-SW)") (layer "F.Cu") (hatch edge 0.508)
    (priority 3)
    (connect_pads yes (clearance 0.125))
    (min_thickness 0.125) (filled_areas_thickness no)
    (fill yes (thermal_gap 0.15) (thermal_bridge_width 0.151) (smoothing fillet) (radius 0.5))
    (polygon
      (pts
        (xy 133.156328 86.240008)
        (xy 135.043828 86.250008)
        (xy 135.036328 91.735008)
        (xy 134.111328 91.735008)
        (xy 134.111328 91.210008)
        (xy 132.536328 91.210008)
        (xy 132.536328 93.085008)
        (xy 130.036328 93.085008)
        (xy 130.036328 92.260008)
        (xy 131.436328 92.260008)
        (xy 131.436328 90.560008)
        (xy 133.156328 90.570008)
      )
    )
  )
  (zone (net 51) (net_name "Net-(U12-BST)") (layer "F.Cu") (hatch edge 0.508)
    (connect_pads yes (clearance 0.125))
    (min_thickness 0.125) (filled_areas_thickness no)
    (fill yes (thermal_gap 0.15) (thermal_bridge_width 0.151) (smoothing fillet) (radius 0.5))
    (polygon
      (pts
        (xy 133.961328 91.910008)
        (xy 134.936328 91.910008)
        (xy 134.936328 92.660008)
        (xy 134.011328 92.660008)
        (xy 134.011328 92.160008)
        (xy 132.661328 92.160008)
        (xy 132.661328 91.385008)
        (xy 133.961328 91.385008)
      )
    )
  )
  (zone (net 653) (net_name "Net-(U12-FB)") (layer "F.Cu") (hatch edge 0.508)
    (connect_pads yes (clearance 0.125))
    (min_thickness 0.125) (filled_areas_thickness no)
    (fill yes (thermal_gap 0.15) (thermal_bridge_width 0.151) (smoothing fillet) (radius 0.5))
    (polygon
      (pts
        (xy 133.906328 94.040008)
        (xy 133.426328 94.040008)
        (xy 133.426328 96.490008)
        (xy 132.646328 96.490008)
        (xy 132.646328 93.290008)
        (xy 133.906328 93.290008)
      )
    )
  )
  (zone (net 9) (net_name "GND") (layer "F.Cu") (hatch edge 0.508)
    (priority 1)
    (connect_pads yes (clearance 0.125))
    (min_thickness 0.125) (filled_areas_thickness no)
    (fill yes (thermal_gap 0.15) (thermal_bridge_width 0.151) (smoothing fillet) (radius 0.5))
    (polygon
      (pts
        (xy 131.386328 92.230008)
        (xy 129.936328 92.230008)
        (xy 129.936328 94.065008)
        (xy 130.206328 94.335008)
        (xy 130.206328 95.500008)
        (xy 129.436328 95.500008)
        (xy 129.436328 90.560008)
        (xy 131.386328 90.560008)
      )
    )
  )
  (zone (net 306) (net_name "1V2_SYS") (layer "F.Cu") (hatch edge 0.508)
    (connect_pads yes (clearance 0.125))
    (min_thickness 0.125) (filled_areas_thickness no)
    (fill yes (thermal_gap 0.15) (thermal_bridge_width 0.151))
    (polygon
      (pts
        (xy 155.989415 122.662016)
        (xy 153.260656 122.662016)
        (xy 153.260656 120.702008)
        (xy 153.224328 120.6)
        (xy 153.224328 119.202008)
        (xy 153.974328 119.202008)
        (xy 154.349328 118.827008)
        (xy 155.989415 118.827008)
      )
    )
  )
  (zone (net 176) (net_name "VCC1V2") (layer "F.Cu") (hatch edge 0.508)
    (connect_pads yes (clearance 0.125))
    (min_thickness 0.125) (filled_areas_thickness no)
    (fill yes (thermal_gap 0.15) (thermal_bridge_width 0.151))
    (polygon
      (pts
        (xy 151.373742 120.964508)
        (xy 151.360656 122.787016)
        (xy 149.410656 122.787016)
        (xy 149.199328 122.577008)
        (xy 149.199328 121.977008)
        (xy 148.999328 121.777008)
        (xy 145.999328 121.777008)
        (xy 145.999328 120.927008)
        (xy 146.599328 120.327008)
        (xy 146.599328 117.827008)
        (xy 150.174328 117.827008)
        (xy 150.174914 119.139508)
      )
    )
  )
  (zone (net 9) (net_name "GND") (layer "F.Cu") (hatch edge 0.508)
    (connect_pads yes (clearance 0.125))
    (min_thickness 0.125) (filled_areas_thickness no)
    (fill yes (thermal_gap 0.15) (thermal_bridge_width 0.151))
    (polygon
      (pts
        (xy 148.899328 122.952008)
        (xy 148.449328 123.402008)
        (xy 146.399328 123.402008)
        (xy 145.899328 122.902008)
        (xy 145.899328 121.952008)
        (xy 148.899328 121.952008)
      )
    )
  )
  (zone (net 8) (net_name "Net-(U5-SW)") (layer "F.Cu") (hatch edge 0.508)
    (connect_pads yes (clearance 0.125))
    (min_thickness 0.125) (filled_areas_thickness no)
    (fill yes (thermal_gap 0.15) (thermal_bridge_width 0.151))
    (polygon
      (pts
        (xy 151.399328 115.002008)
        (xy 150.999328 115.002008)
        (xy 150.999328 116.602008)
        (xy 152.899328 116.602008)
        (xy 152.899328 119.002008)
        (xy 152.099328 119.002008)
        (xy 152.099328 117.702008)
        (xy 150.299328 117.702008)
        (xy 149.299328 116.702008)
        (xy 146.999328 116.702008)
        (xy 146.999328 114.702008)
        (xy 149.599328 114.702008)
        (xy 150.099328 114.202008)
        (xy 151.399328 114.202008)
      )
    )
  )
  (zone (net 9) (net_name "GND") (layer "F.Cu") (hatch edge 0.508)
    (connect_pads yes (clearance 0.125))
    (min_thickness 0.125) (filled_areas_thickness no)
    (fill yes (thermal_gap 0.15) (thermal_bridge_width 0.151))
    (polygon
      (pts
        (xy 151.924328 119.277008)
        (xy 152.724328 119.277008)
        (xy 152.724328 120.202008)
        (xy 151.099328 120.202008)
        (xy 150.449328 119.202008)
        (xy 150.449328 117.827008)
        (xy 151.924328 117.827008)
      )
    )
  )
  (zone (net 307) (net_name "5V0_SYS") (layer "F.Cu") (hatch edge 0.508)
    (connect_pads yes (clearance 0.125))
    (min_thickness 0.125) (filled_areas_thickness no)
    (fill yes (thermal_gap 0.15) (thermal_bridge_width 0.151))
    (polygon
      (pts
        (xy 155.249328 118.702008)
        (xy 154.299328 118.702008)
        (xy 153.899328 119.052008)
        (xy 153.049328 119.052008)
        (xy 153.049328 117.152008)
        (xy 155.249328 117.152008)
      )
    )
  )
  (zone (net 9) (net_name "GND") (layer "F.Cu") (hatch edge 0.508)
    (connect_pads yes (clearance 0.125))
    (min_thickness 0.125) (filled_areas_thickness no)
    (fill yes (thermal_gap 0.15) (thermal_bridge_width 0.151))
    (polygon
      (pts
        (xy 156.499328 118.702008)
        (xy 155.499328 118.702008)
        (xy 155.499328 116.302008)
        (xy 156.499328 116.302008)
      )
    )
  )
  (zone (net 308) (net_name "NC") (layer "F.Cu") (hatch edge 0.508)
    (priority 4)
    (connect_pads yes (clearance 0.15))
    (min_thickness 0.15) (filled_areas_thickness no)
    (fill yes (thermal_gap 0.508) (thermal_bridge_width 0.508) (smoothing fillet) (radius 0.5))
    (polygon
      (pts
        (xy 248.736328 60.660008)
        (xy 246.236328 60.660008)
        (xy 246.236328 54.060008)
        (xy 248.736328 54.060008)
      )
    )
  )
  (zone (net 145) (net_name "1V8_FT") (layer "F.Cu") (hatch edge 0.508)
    (priority 3)
    (connect_pads yes (clearance 0.15))
    (min_thickness 0.15) (filled_areas_thickness no)
    (fill yes (thermal_gap 0.508) (thermal_bridge_width 0.508) (smoothing fillet) (radius 0.5))
    (polygon
      (pts
        (xy 146.136328 102.260008)
        (xy 144.636328 102.260008)
        (xy 144.636328 99.360008)
        (xy 146.136328 99.360008)
      )
    )
  )
  (zone (net 9) (net_name "GND") (layer "F.Cu") (hatch edge 0.508)
    (priority 1)
    (connect_pads yes (clearance 0.12))
    (min_thickness 0.15) (filled_areas_thickness no)
    (fill yes (thermal_gap 0.508) (thermal_bridge_width 0.508) (smoothing fillet) (radius 0.5))
    (polygon
      (pts
        (xy 150.986328 93.460008)
        (xy 152.136328 93.460008)
        (xy 152.136328 94.410008)
        (xy 148.386328 94.410008)
        (xy 147.486328 93.510008)
        (xy 139.236328 93.560008)
        (xy 138.386328 94.410008)
        (xy 136.936328 94.410008)
        (xy 136.936328 92.310008)
        (xy 143.836328 92.310008)
        (xy 143.836328 89.610008)
        (xy 143.836328 89.235008)
        (xy 143.10066 88.49934)
        (xy 143.1 86.8)
        (xy 142.036328 86.8)
        (xy 142.036328 84.875)
        (xy 143.125 84.875)
        (xy 143.825 84.875)
        (xy 143.836328 87.060008)
        (xy 150.986328 87.060008)
      )
    )
  )
  (zone (net 9) (net_name "GND") (layer "F.Cu") (hatch edge 0.508)
    (priority 1)
    (connect_pads yes (clearance 0.15))
    (min_thickness 0.15) (filled_areas_thickness no)
    (fill yes (thermal_gap 0.508) (thermal_bridge_width 0.508) (smoothing fillet) (radius 0.5))
    (polygon
      (pts
        (xy 142.786328 80.760008)
        (xy 136.311328 80.760008)
        (xy 136.311328 87.285008)
        (xy 137.646328 87.285008)
        (xy 137.646328 88.530008)
        (xy 136.313828 88.535008)
        (xy 136.311328 89.460008)
        (xy 135.336328 89.460008)
        (xy 135.336328 86.010008)
        (xy 133.036328 86.010008)
        (xy 133.036328 82.910008)
        (xy 135.336328 82.910008)
        (xy 135.35 77.451078)
        (xy 142.8 77.45)
      )
    )
  )
  (zone (net 184) (net_name "VPP") (layer "F.Cu") (hatch edge 0.508)
    (connect_pads yes (clearance 0.15))
    (min_thickness 0.15) (filled_areas_thickness no)
    (fill yes (thermal_gap 0.508) (thermal_bridge_width 0.508) (smoothing fillet) (radius 0.5))
    (polygon
      (pts
        (xy 125.511328 87.860008)
        (xy 124.45 87.860008)
        (xy 124.45 87.325)
        (xy 122.126328 87.310008)
        (xy 122.133006 84.02002)
        (xy 122.326328 83.760008)
        (xy 122.326328 82.110008)
        (xy 125.511328 82.110008)
      )
    )
  )
  (zone (net 77) (net_name "VDDQ") (layer "F.Cu") (hatch edge 0.508)
    (connect_pads yes (clearance 0.15))
    (min_thickness 0.15) (filled_areas_thickness no)
    (fill yes (thermal_gap 0.508) (thermal_bridge_width 0.508) (smoothing fillet) (radius 0.5))
    (polygon
      (pts
        (xy 121.636328 82.360008)
        (xy 118 82.360008)
        (xy 117.3 83.060008)
        (xy 116.136328 83.060008)
        (xy 116.136328 76.860008)
        (xy 121.636328 76.860008)
      )
    )
  )
  (zone (net 186) (net_name "VTT") (layer "F.Cu") (hatch edge 0.508)
    (priority 1)
    (connect_pads yes (clearance 0.15))
    (min_thickness 0.15) (filled_areas_thickness no)
    (fill yes (thermal_gap 0.508) (thermal_bridge_width 0.508) (smoothing fillet) (radius 0.5))
    (polygon
      (pts
        (xy 182.486328 60.675)
        (xy 179.3 60.675)
        (xy 179.286328 52.510008)
        (xy 114.4 52.65)
        (xy 112 55.05)
        (xy 112 61.8)
        (xy 110.9 62.9)
        (xy 110.9 65.5)
        (xy 113.836328 68.4)
        (xy 113.836328 90.260008)
        (xy 108.286328 90.260008)
        (xy 108.286328 47.260008)
        (xy 182.5 47.25)
      )
    )
  )
  (zone (net 144) (net_name "1V8_SYS") (layer "F.Cu") (hatch edge 0.508)
    (connect_pads yes (clearance 0.15))
    (min_thickness 0.15) (filled_areas_thickness no)
    (fill yes (thermal_gap 0.508) (thermal_bridge_width 0.508) (smoothing fillet) (radius 0.5))
    (polygon
      (pts
        (xy 135.036328 82.835008)
        (xy 133.443164 82.835008)
        (xy 131.85 82.835008)
        (xy 131.85 82.3)
        (xy 129.486328 82.285008)
        (xy 129.461328 80.535008)
        (xy 135.036328 80.535008)
      )
    )
  )
  (zone (net 184) (net_name "VPP") (layer "F.Cu") (hatch edge 0.508)
    (connect_pads yes (clearance 0.15))
    (min_thickness 0.15) (filled_areas_thickness no)
    (fill yes (thermal_gap 0.508) (thermal_bridge_width 0.508) (smoothing fillet) (radius 0.5))
    (polygon
      (pts
        (xy 122.086328 60.960008)
        (xy 122.236328 60.960008)
        (xy 122.236328 63.460008)
        (xy 119.336328 63.510008)
        (xy 119.336328 56.160008)
        (xy 120.436328 56.160008)
        (xy 120.436328 54.060008)
        (xy 122.086328 54.060008)
      )
    )
  )
  (zone (net 302) (net_name "VCC1V8") (layer "F.Cu") (hatch edge 0.508)
    (connect_pads yes (clearance 0.15))
    (min_thickness 0.15) (filled_areas_thickness no)
    (fill yes (thermal_gap 0.508) (thermal_bridge_width 0.508) (smoothing fillet) (radius 0.5))
    (polygon
      (pts
        (xy 132.936328 86.010008)
        (xy 132.406328 86.005008)
        (xy 132.406328 90.455008)
        (xy 129.436328 90.460008)
        (xy 129.436328 87.760008)
        (xy 129.436328 84.7)
        (xy 131.8 84.7)
        (xy 131.8 83.285008)
        (xy 132.936328 83.285008)
      )
    )
  )
  (zone (net 103) (net_name "VIN") (layer "F.Cu") (hatch edge 0.508)
    (connect_pads yes (clearance 0.15))
    (min_thickness 0.15) (filled_areas_thickness no)
    (fill yes (thermal_gap 0.508) (thermal_bridge_width 0.508) (smoothing fillet) (radius 0.5))
    (polygon
      (pts
        (xy 116.636328 119.647157)
        (xy 112.836328 119.647157)
        (xy 112.836328 123.747157)
        (xy 109.036328 123.747157)
        (xy 109.036328 116.747157)
        (xy 116.636328 116.747157)
      )
    )
  )
  (zone (net 626) (net_name "VIN_RAW") (layer "F.Cu") (hatch edge 0.508)
    (connect_pads yes (clearance 0.15))
    (min_thickness 0.15) (filled_areas_thickness no)
    (fill yes (thermal_gap 0.508) (thermal_bridge_width 0.508) (smoothing fillet) (radius 0.5))
    (polygon
      (pts
        (xy 121.036328 126.147157)
        (xy 109.236328 126.147157)
        (xy 109.186328 124.347157)
        (xy 114.686328 124.347157)
        (xy 114.636328 120.547157)
        (xy 121.036328 120.547157)
      )
    )
  )
  (zone (net 147) (net_name "1V0_SYS") (layer "F.Cu") (hatch edge 0.508)
    (connect_pads yes (clearance 0.12))
    (min_thickness 0.15) (filled_areas_thickness no)
    (fill yes (thermal_gap 0.508) (thermal_bridge_width 0.508) (smoothing fillet) (radius 0.5))
    (polygon
      (pts
        (xy 148.736328 86.810008)
        (xy 143.936328 86.810008)
        (xy 143.95 84.825)
        (xy 145.05 84.825)
        (xy 145.05 82.525)
        (xy 145.05 80.75)
        (xy 143.086328 80.760008)
        (xy 143.086328 77.410008)
        (xy 148.736328 77.410008)
      )
    )
  )
  (zone (net 9) (net_name "GND") (layer "F.Cu") (hatch edge 0.508)
    (connect_pads yes (clearance 0.15))
    (min_thickness 0.15) (filled_areas_thickness no)
    (fill yes (thermal_gap 0.508) (thermal_bridge_width 0.508) (smoothing fillet) (radius 0.5))
    (polygon
      (pts
        (xy 121 103.375)
        (xy 119.5 103.375)
        (xy 119.5 101.875)
        (xy 121 101.875)
      )
    )
  )
  (zone (net 9) (net_name "GND") (layer "F.Cu") (hatch edge 0.508)
    (connect_pads yes (clearance 0.15))
    (min_thickness 0.15) (filled_areas_thickness no)
    (fill yes (thermal_gap 0.508) (thermal_bridge_width 0.508) (smoothing fillet) (radius 0.5))
    (polygon
      (pts
        (xy 130.25 130.5)
        (xy 127.95 132.79)
        (xy 114.375 132.785)
        (xy 114.373828 126.947157)
        (xy 121.498828 126.947157)
        (xy 121.5 122.5)
        (xy 124.5 122.5)
        (xy 124.5 125.75)
        (xy 130.25 125.75)
      )
    )
  )
  (zone (net 143) (net_name "3V3_SYS") (layer "F.Cu") (hatch edge 0.508)
    (connect_pads yes (clearance 0.15))
    (min_thickness 0.15) (filled_areas_thickness no)
    (fill yes (thermal_gap 0.508) (thermal_bridge_width 0.508) (smoothing fillet) (radius 0.5))
    (polygon
      (pts
        (xy 111.136328 109.960008)
        (xy 108.236328 109.960008)
        (xy 108.225 106.525)
        (xy 108.725 106.525)
        (xy 110.175 107.960008)
        (xy 111.136328 107.960008)
      )
    )
  )
  (zone (net 103) (net_name "VIN") (layer "F.Cu") (hatch edge 0.508)
    (connect_pads yes (clearance 0.15))
    (min_thickness 0.15) (filled_areas_thickness no)
    (fill yes (thermal_gap 0.508) (thermal_bridge_width 0.508) (smoothing fillet) (radius 0.5))
    (polygon
      (pts
        (xy 112.336328 112.210008)
        (xy 111.636328 112.210008)
        (xy 111.646328 113.200008)
        (xy 112.836328 113.200008)
        (xy 112.836328 113.960008)
        (xy 111.486328 113.960008)
        (xy 110.636328 113.110008)
        (xy 109.986328 113.110008)
        (xy 109.986116 111.049999)
        (xy 112.336116 111.060007)
      )
    )
  )
  (zone (net 103) (net_name "VIN") (layer "F.Cu") (hatch edge 0.508)
    (priority 2)
    (connect_pads yes (clearance 0.15))
    (min_thickness 0.15) (filled_areas_thickness no)
    (fill yes (thermal_gap 0.508) (thermal_bridge_width 0.508) (smoothing fillet) (radius 0.5))
    (polygon
      (pts
        (xy 111.036328 106.260008)
        (xy 114.446328 106.237508)
        (xy 114.446328 107.762508)
        (xy 110.175 107.775)
        (xy 108.836328 106.425)
        (xy 108.836328 98.747157)
        (xy 111.036328 98.747157)
      )
    )
  )
  (zone (net 103) (net_name "VIN") (layer "F.Cu") (hatch edge 0.508)
    (connect_pads yes (clearance 0.15))
    (min_thickness 0.15) (filled_areas_thickness no)
    (fill yes (thermal_gap 0.508) (thermal_bridge_width 0.508) (smoothing fillet) (radius 0.5))
    (polygon
      (pts
        (xy 119.186328 103.522157)
        (xy 118.186328 103.522157)
        (xy 118.186328 105.760008)
        (xy 116.886328 105.760008)
        (xy 116.886328 101.822157)
        (xy 118.086328 101.822157)
        (xy 118.783234 101.10624)
        (xy 118.786328 98.810008)
        (xy 119.336328 98.810008)
        (xy 119.336328 101.460008)
        (xy 119.186328 101.822157)
      )
    )
  )
  (zone (net 73) (net_name "Net-(IC1-SW)") (layer "F.Cu") (hatch edge 0.508)
    (connect_pads yes (clearance 0.15))
    (min_thickness 0.15) (filled_areas_thickness no)
    (fill yes (thermal_gap 0.508) (thermal_bridge_width 0.508) (smoothing fillet) (radius 0.5))
    (polygon
      (pts
        (xy 130.25 112.497157)
        (xy 130.25 125.372157)
        (xy 125 125.372157)
        (xy 125 119.497157)
        (xy 122.286328 119.497157)
        (xy 122.286328 113.872157)
        (xy 115.911328 113.872157)
        (xy 115.911328 113.372157)
        (xy 117.411328 113.372157)
        (xy 118.161328 112.497157)
      )
    )
  )
  (zone (net 9) (net_name "GND") (layer "F.Cu") (hatch edge 0.508)
    (connect_pads yes (clearance 0.15))
    (min_thickness 0.15) (filled_areas_thickness no)
    (fill yes (thermal_gap 0.508) (thermal_bridge_width 0.508) (smoothing fillet) (radius 0.5))
    (polygon
      (pts
        (xy 128.89881 87.860008)
        (xy 125.77381 87.860008)
        (xy 125.77381 82.110008)
        (xy 128.89881 82.110008)
      )
    )
  )
  (zone (net 9) (net_name "GND") (layer "F.Cu") (hatch edge 0.508)
    (priority 1)
    (connect_pads yes (clearance 0.15))
    (min_thickness 0.15) (filled_areas_thickness no)
    (fill yes (thermal_gap 0.508) (thermal_bridge_width 0.508) (smoothing fillet) (radius 0.5))
    (polygon
      (pts
        (xy 115.536328 101.872157)
        (xy 116.411328 101.872157)
        (xy 116.410703 105.810008)
        (xy 115.476328 105.810008)
        (xy 115.475078 106.620008)
        (xy 114.536328 106.620008)
        (xy 114.536328 106.085008)
        (xy 111.911328 106.085008)
        (xy 111.911328 99.247157)
        (xy 115.536328 99.247157)
      )
    )
  )
  (zone (net 299) (net_name "VCC0V6") (layer "F.Cu") (hatch edge 0.508)
    (priority 1)
    (connect_pads yes (clearance 0.15))
    (min_thickness 0.15) (filled_areas_thickness no)
    (fill yes (thermal_gap 0.508) (thermal_bridge_width 0.508) (smoothing fillet) (radius 0.5))
    (polygon
      (pts
        (xy 113.536328 98.210008)
        (xy 116.736328 98.210008)
        (xy 116.736328 99.060008)
        (xy 111.296328 99.060008)
        (xy 111.296328 92.630008)
        (xy 113.536328 92.630008)
      )
    )
  )
  (zone (net 9) (net_name "GND") (layer "F.Cu") (hatch edge 0.508)
    (connect_pads yes (clearance 0.15))
    (min_thickness 0.15) (filled_areas_thickness no)
    (fill yes (thermal_gap 0.508) (thermal_bridge_width 0.508) (smoothing fillet) (radius 0.5))
    (polygon
      (pts
        (xy 115.786328 98.010008)
        (xy 114.036328 98.010008)
        (xy 114.036328 76.860008)
        (xy 115.786328 76.860008)
      )
    )
  )
  (zone (net 9) (net_name "GND") (layer "F.Cu") (hatch edge 0.508)
    (connect_pads yes (clearance 0.15))
    (min_thickness 0.15) (filled_areas_thickness no)
    (fill yes (thermal_gap 0.508) (thermal_bridge_width 0.508) (smoothing fillet) (radius 0.5))
    (polygon
      (pts
        (xy 127.661328 102.497157)
        (xy 122.536328 102.497157)
        (xy 122.536328 99.660008)
        (xy 127.636328 99.660008)
      )
    )
  )
  (zone (net 303) (net_name "VCC2V5") (layer "F.Cu") (hatch edge 0.508)
    (connect_pads yes (clearance 0.15))
    (min_thickness 0.15) (filled_areas_thickness no)
    (fill yes (thermal_gap 0.508) (thermal_bridge_width 0.508) (smoothing fillet) (radius 0.5))
    (polygon
      (pts
        (xy 129.161328 96.9)
        (xy 130.061328 96.9)
        (xy 130.061328 97.75)
        (xy 129.7 98.122157)
        (xy 125.411328 98.122157)
        (xy 125.411328 91.247157)
        (xy 121.896328 91.247157)
        (xy 121.896328 89.55)
        (xy 124.375 89.55)
        (xy 124.375 88.372157)
        (xy 129.161328 88.372157)
      )
    )
  )
  (zone (net 571) (net_name "Net-(U2-SW_VPP)") (layer "F.Cu") (hatch edge 0.508)
    (connect_pads yes (clearance 0.15))
    (min_thickness 0.15) (filled_areas_thickness no)
    (fill yes (thermal_gap 0.508) (thermal_bridge_width 0.508) (smoothing fillet) (radius 0.5))
    (polygon
      (pts
        (xy 125.036328 98.122157)
        (xy 120.661328 98.122157)
        (xy 120.661328 97.497157)
        (xy 122.161328 97.497157)
        (xy 122.161328 92.497157)
        (xy 125.036328 92.497157)
      )
    )
  )
  (zone (net 1) (net_name "Net-(U2-SW)") (layer "F.Cu") (hatch edge 0.508)
    (connect_pads yes (clearance 0.15))
    (min_thickness 0.15) (filled_areas_thickness no)
    (fill yes (thermal_gap 0.15) (thermal_bridge_width 0.15) (smoothing fillet) (radius 0.5))
    (polygon
      (pts
        (xy 121.661328 97.310008)
        (xy 119.836328 97.310008)
        (xy 119.836328 98.760008)
        (xy 119.386328 98.760008)
        (xy 119.386328 97.310008)
        (xy 119.186328 97.1)
        (xy 119.186328 91.610008)
        (xy 121.66 91.610008)
      )
    )
  )
  (zone (net 307) (net_name "5V0_SYS") (layer "F.Cu") (hatch edge 0.508)
    (priority 3)
    (connect_pads yes (clearance 0.12))
    (min_thickness 0.15) (filled_areas_thickness no)
    (fill yes (thermal_gap 0.508) (thermal_bridge_width 0.508) (smoothing fillet) (radius 0.5))
    (polygon
      (pts
        (xy 130.2 97.9)
        (xy 130.2 93.23)
        (xy 131.75 93.23)
        (xy 131.75 96.7)
        (xy 133.5 96.7)
        (xy 133.5008 94.199994)
        (xy 134.1008 94.195194)
        (xy 134.1 93.4)
        (xy 135.2 93.4)
        (xy 135.2 89.6)
        (xy 138.9 89.6)
        (xy 138.9 92.3)
        (xy 136.9 92.3)
        (xy 136.9 94.9)
        (xy 135.1 94.9)
        (xy 135.1 99.4)
        (xy 133.3 99.4)
        (xy 132.2 98.3)
        (xy 131.2 98.3)
        (xy 130.8 98.7)
        (xy 130.8 100.4)
        (xy 127.8 100.4)
        (xy 127.8 99.460008)
        (xy 125.086328 99.460008)
        (xy 122.536328 99.460008)
        (xy 122.236328 99.160008)
        (xy 120.386328 99.160008)
        (xy 120.386328 98.372157)
        (xy 129.75 98.36)
      )
    )
  )
  (zone (net 301) (net_name "VDD1V2") (layer "F.Cu") (hatch edge 0.508)
    (connect_pads yes (clearance 0.15))
    (min_thickness 0.15) (filled_areas_thickness no)
    (fill yes (thermal_gap 0.508) (thermal_bridge_width 0.508) (smoothing fillet) (radius 0.5))
    (polygon
      (pts
        (xy 120.776328 91.247157)
        (xy 118.186328 91.247157)
        (xy 118.186328 97.2)
        (xy 118.636328 97.65)
        (xy 118.636328 98.260008)
        (xy 117.236328 98.260008)
        (xy 117.086328 98.110008)
        (xy 116.161328 98.110008)
        (xy 116.161328 83.860008)
        (xy 117.8 83.860008)
        (xy 118.7 84.7)
        (xy 120.806328 84.7)
      )
    )
  )
  (zone (net 305) (net_name "/Supply/VTTREF") (layer "F.Cu") (hatch edge 0.508)
    (priority 3)
    (connect_pads yes (clearance 0.125))
    (min_thickness 0.254) (filled_areas_thickness no)
    (fill yes (thermal_gap 0.508) (thermal_bridge_width 0.508) (smoothing fillet) (radius 0.5))
    (polygon
      (pts
        (xy 118.55 101.15)
        (xy 118 101.7)
        (xy 115.75 101.7)
        (xy 115.75 100.35)
        (xy 118.55 100.35)
      )
    )
  )
  (zone (net 308) (net_name "NC") (layer "F.Cu") (hatch edge 0.508)
    (connect_pads yes (clearance 0.15))
    (min_thickness 0.15) (filled_areas_thickness no)
    (fill yes (thermal_gap 0.15) (thermal_bridge_width 0.15) (smoothing fillet) (radius 0.5))
    (polygon
      (pts
        (xy 109.75 113.099743)
        (xy 108.68 113.089743)
        (xy 108.17 112.579743)
        (xy 107.65 112.579743)
        (xy 107.65 111.239743)
        (xy 108.06 111.239743)
        (xy 108.3 110.999743)
        (xy 108.3 110.149743)
        (xy 109.5 110.15)
        (xy 109.5 110.75)
        (xy 109.75 110.999743)
      )
    )
  )
  (zone (net 793) (net_name "/Supply/VTT_CNTL") (layer "F.Cu") (hatch edge 0.508)
    (connect_pads yes (clearance 0.125))
    (min_thickness 0.254) (filled_areas_thickness no)
    (fill yes (thermal_gap 0.508) (thermal_bridge_width 0.508) (smoothing fillet) (radius 0.5))
    (polygon
      (pts
        (xy 121.379494 100.352955)
        (xy 122.326539 101.3)
        (xy 122.326539 101.75)
        (xy 120.65 101.75)
        (xy 120.65 100.35)
      )
    )
  )
  (zone (net 9) (net_name "GND") (layer "F.Cu") (hatch edge 0.508)
    (priority 1)
    (connect_pads yes (clearance 0.125))
    (min_thickness 0.1) (filled_areas_thickness no)
    (fill yes (thermal_gap 0.2) (thermal_bridge_width 0.12) (smoothing fillet) (radius 1))
    (polygon
      (pts
        (xy 259.4 71.5)
        (xy 254.5 71.5)
        (xy 254.5 61.1)
        (xy 259.4 61.1)
      )
    )
  )
  (zone (net 307) (net_name "5V0_SYS") (layer "F.Cu") (hatch edge 0.508)
    (connect_pads yes (clearance 0.12))
    (min_thickness 0.15) (filled_areas_thickness no)
    (fill yes (thermal_gap 0.15) (thermal_bridge_width 0.16))
    (polygon
      (pts
        (xy 125.8 108.2)
        (xy 124.8 108.2)
        (xy 124.8 107.6)
        (xy 124.6 107.4)
        (xy 123.6 107.4)
        (xy 123.6 108.2)
        (xy 122.4 108.2)
        (xy 122.4 106.4)
        (xy 125.8 106.4)
      )
    )
  )
  (zone (net 535) (net_name "12P0V") (layer "F.Cu") (hatch edge 0.508)
    (connect_pads yes (clearance 0.125))
    (min_thickness 0.1) (filled_areas_thickness no)
    (fill yes (thermal_gap 0.2) (thermal_bridge_width 0.12))
    (polygon
      (pts
        (xy 251.7 128.25)
        (xy 249.55 128.25)
        (xy 248.75 127.45)
        (xy 248.75 124.6)
        (xy 250.9 124.6)
        (xy 251.7 125.4)
      )
    )
  )
  (zone (net 601) (net_name "Net-(U2-BST)") (layer "F.Cu") (hatch edge 0.508)
    (priority 3)
    (connect_pads yes (clearance 0.15))
    (min_thickness 0.15) (filled_areas_thickness no)
    (fill yes (thermal_gap 0.15) (thermal_bridge_width 0.15) (smoothing fillet) (radius 0.5))
    (polygon
      (pts
        (xy 119.05 98.15)
        (xy 118.85 98.15)
        (xy 118.85 97.575208)
        (xy 118.424792 97.15)
        (xy 118.424792 96.55)
        (xy 119.05 96.55)
      )
    )
  )
  (zone (net 9) (net_name "GND") (layer "F.Cu") (hatch edge 0.508)
    (connect_pads yes (clearance 0.125))
    (min_thickness 0.1) (filled_areas_thickness no)
    (fill yes (thermal_gap 0.2) (thermal_bridge_width 0.12))
    (polygon
      (pts
        (xy 245.25 128.25)
        (xy 247.4 128.249999)
        (xy 248.2 127.449999)
        (xy 248.2 124.599999)
        (xy 245.25 124.599999)
      )
    )
  )
  (zone (net 9) (net_name "GND") (layer "F.Cu") (hatch edge 0.508)
    (connect_pads (clearance 0.1))
    (min_thickness 0.254) (filled_areas_thickness no)
    (fill yes (thermal_gap 0.508) (thermal_bridge_width 0.508) (smoothing fillet) (radius 0.5))
    (polygon
      (pts
        (xy 242.5 72.290368)
        (xy 230.50966 72.29521)
        (xy 230.508942 78.309992)
        (xy 225.55 78.306791)
        (xy 225.55 79.756538)
        (xy 222.09502 83.20498)
        (xy 222.092101 85.256659)
        (xy 220.040422 85.259578)
        (xy 216.6 88.7)
        (xy 201.9 88.7)
        (xy 200.35 87.15)
        (xy 200.35 77)
        (xy 199 75.6)
        (xy 199 67.55)
        (xy 203.75 62.8)
        (xy 242.5 62.8)
      )
    )
  )
  (zone (net 9) (net_name "GND") (layer "F.Cu") (hatch edge 0.508)
    (connect_pads (clearance 0.125))
    (min_thickness 0.254) (filled_areas_thickness no)
    (fill yes (thermal_gap 0.508) (thermal_bridge_width 0.508) (smoothing fillet) (radius 0.5))
    (polygon
      (pts
        (xy 242.15 104.9)
        (xy 242.15 110.15)
        (xy 215 110.15)
        (xy 215 108.3)
        (xy 211.8 105.2)
        (xy 211.8 100.9)
        (xy 212.5 100.20101)
        (xy 237.5 100.25)
      )
    )
  )
  (zone (net 9) (net_name "GND") (layer "F.Cu") (hatch edge 0.508)
    (priority 2)
    (connect_pads yes (clearance 0.15))
    (min_thickness 0.15) (filled_areas_thickness no)
    (fill yes (thermal_gap 0.508) (thermal_bridge_width 0.508) (smoothing fillet) (radius 0.5))
    (polygon
      (pts
        (xy 169.35 110.65)
        (xy 165.4 110.65)
        (xy 165.4 106.3)
        (xy 169.35 106.3)
      )
    )
  )
  (zone (net 0) (net_name "") (layer "F.Cu") (hatch edge 0.508)
    (connect_pads no (clearance 0))
    (min_thickness 0.15) (filled_areas_thickness no)
    (keepout (tracks allowed) (vias allowed) (pads allowed) (copperpour not_allowed) (footprints allowed))
    (fill (thermal_gap 0.3) (thermal_bridge_width 0.2))
    (polygon
      (pts
        (xy 182.025 79.075)
        (xy 181.25 79.075)
        (xy 181.25 78.125)
        (xy 182.025 78.125)
      )
    )
  )
  (zone (net 304) (net_name "VCC3V3") (layer "F.Cu") (hatch edge 0.508)
    (priority 1)
    (connect_pads yes (clearance 0.15))
    (min_thickness 0.15) (filled_areas_thickness no)
    (fill yes (thermal_gap 0.15) (thermal_bridge_width 0.15) (smoothing fillet) (radius 0.5))
    (polygon
      (pts
        (xy 125.65 106.4)
        (xy 125.2 106.85)
        (xy 124.75 106.85)
        (xy 124.75 106.45)
        (xy 124.95 106.25)
        (xy 124.95 105.595008)
        (xy 125.65 105.595008)
      )
    )
  )
  (zone (net 616) (net_name "Net-(U2-VTTSNS)") (layer "F.Cu") (hatch edge 0.508)
    (priority 4)
    (connect_pads yes (clearance 0.125))
    (min_thickness 0.254) (filled_areas_thickness no)
    (fill yes (thermal_gap 0.508) (thermal_bridge_width 0.508) (smoothing fillet) (radius 0.5))
    (polygon
      (pts
        (xy 116.95 100.2)
        (xy 115.75 100.2)
        (xy 115.75 99.25)
        (xy 116.95 99.25)
      )
    )
  )
  (zone (net 9) (net_name "GND") (layer "F.Cu") (hatch edge 0.508)
    (connect_pads (clearance 0.1))
    (min_thickness 0.254) (filled_areas_thickness no)
    (fill yes (thermal_gap 0.508) (thermal_bridge_width 0.508) (smoothing fillet) (radius 0.5))
    (polygon
      (pts
        (xy 195.55 69.95)
        (xy 193.05 72.45)
        (xy 190.55 72.45)
        (xy 171.55 72.45)
        (xy 168.1 75.95)
        (xy 159.7 75.95)
        (xy 157.4 73.65)
        (xy 147.25 73.65)
        (xy 145.55 75.35)
        (xy 127.3 75.35)
        (xy 126.55 74.6)
        (xy 126.55 64.5)
        (xy 127.25 63.8)
        (xy 173.25 63.8)
        (xy 175.45 66)
        (xy 179.8 66)
        (xy 182.3 63.5)
        (xy 195.55 63.5)
      )
    )
  )
  (zone (net 9) (net_name "GND") (layer "F.Cu") (hatch edge 0.508)
    (priority 2)
    (connect_pads yes (clearance 0.15))
    (min_thickness 0.15) (filled_areas_thickness no)
    (fill yes (thermal_gap 0.508) (thermal_bridge_width 0.508) (smoothing fillet) (radius 0.5))
    (polygon
      (pts
        (xy 170.1 93.45)
        (xy 167.5 93.45)
        (xy 167.5 91.1)
        (xy 167.9 90.7)
        (xy 170.1 90.7)
      )
    )
  )
  (zone (net 178) (net_name "/Ethernet/AVDDL_PLL") (layer "F.Cu") (hatch edge 0.508)
    (connect_pads yes (clearance 0.15))
    (min_thickness 0.15) (filled_areas_thickness no)
    (fill yes (thermal_gap 0.15) (thermal_bridge_width 0.15) (smoothing fillet) (radius 0.5))
    (polygon
      (pts
        (xy 148.65 95.5)
        (xy 152.15 95.5)
        (xy 152.15 94.5)
        (xy 148.65 94.5)
      )
    )
  )
  (zone (net 147) (net_name "1V0_SYS") (layer "F.Cu") (hatch edge 0.508)
    (priority 2)
    (connect_pads yes (clearance 0.15))
    (min_thickness 0.15) (filled_areas_thickness no)
    (fill yes (thermal_gap 0.508) (thermal_bridge_width 0.508) (smoothing fillet) (radius 0.5))
    (polygon
      (pts
        (xy 170.1 98.15)
        (xy 169.45 98.8)
        (xy 169.45 102.8)
        (xy 165.4 102.8)
        (xy 165.4 100.3)
        (xy 166.6 99.1)
        (xy 167.3 99.1)
        (xy 167.55 98.85)
        (xy 167.55 94.45)
        (xy 170.1 94.45)
      )
    )
  )
  (zone (net 360) (net_name "/Ethernet/VDD") (layer "F.Cu") (hatch edge 0.508)
    (connect_pads yes (clearance 0.15))
    (min_thickness 0.254) (filled_areas_thickness no)
    (fill yes (thermal_gap 0.508) (thermal_bridge_width 0.508))
    (polygon
      (pts
        (xy 190.6 126.6)
        (xy 176.8 126.6)
        (xy 176.8 125.2)
        (xy 190.6 125.2)
      )
    )
  )
  (zone (net 604) (net_name "GNDD") (layer "F.Cu") (hatch edge 0.508)
    (connect_pads yes (clearance 0.15))
    (min_thickness 0.254) (filled_areas_thickness no)
    (fill yes (thermal_gap 0.508) (thermal_bridge_width 0.508))
    (polygon
      (pts
        (xy 196.6 131.5)
        (xy 196.5 131.6)
        (xy 189 131.6)
        (xy 186.2 134.4)
        (xy 183.5 134.4)
        (xy 183.4 134.3)
        (xy 183.4 132)
        (xy 183.5 131.9)
        (xy 184.8 131.9)
        (xy 187.5 129.2)
        (xy 196.5 129.2)
        (xy 196.6 129.3)
      )
    )
  )
  (zone (net 9) (net_name "GND") (layer "F.Cu") (hatch edge 0.508)
    (priority 1)
    (connect_pads yes (clearance 0.125))
    (min_thickness 0.1) (filled_areas_thickness no)
    (fill yes (thermal_gap 0.2) (thermal_bridge_width 0.12) (smoothing fillet) (radius 1))
    (polygon
      (pts
        (xy 142.225 135.5)
        (xy 130.875 135.5)
        (xy 130.875 123.725)
        (xy 142.225 123.725)
      )
    )
  )
  (zone (net 0) (net_name "") (layers "F.Cu" "In1.Cu") (hatch edge 0.508)
    (connect_pads (clearance 0))
    (min_thickness 0.254) (filled_areas_thickness no)
    (keepout (tracks allowed) (vias allowed) (pads allowed) (copperpour not_allowed) (footprints allowed))
    (fill (thermal_gap 0.508) (thermal_bridge_width 0.508))
    (polygon
      (pts
        (xy 257.01 80.545)
        (xy 255.36 80.545)
        (xy 255.36 78.83)
        (xy 257.01 78.83)
      )
    )
  )
  (zone (net 0) (net_name "") (layers "F.Cu" "In1.Cu") (hatch edge 0.508)
    (connect_pads (clearance 0))
    (min_thickness 0.254) (filled_areas_thickness no)
    (keepout (tracks allowed) (vias allowed) (pads allowed) (copperpour not_allowed) (footprints allowed))
    (fill (thermal_gap 0.508) (thermal_bridge_width 0.508))
    (polygon
      (pts
        (xy 192.64 102.43)
        (xy 191.6 102.43)
        (xy 191.6 101.695)
        (xy 192.64 101.695)
      )
    )
  )
  (zone (net 0) (net_name "") (layers "F.Cu" "In1.Cu") (hatch edge 0.508)
    (connect_pads (clearance 0))
    (min_thickness 0.254) (filled_areas_thickness no)
    (keepout (tracks allowed) (vias allowed) (pads allowed) (copperpour not_allowed) (footprints allowed))
    (fill (thermal_gap 0.508) (thermal_bridge_width 0.508))
    (polygon
      (pts
        (xy 255.52 100.86)
        (xy 254.695 100.86)
        (xy 253.87 100.86)
        (xy 253.87 99.145)
        (xy 255.52 99.145)
      )
    )
  )
  (zone (net 0) (net_name "") (layers "F.Cu" "In1.Cu") (hatch edge 0.508)
    (connect_pads (clearance 0))
    (min_thickness 0.254) (filled_areas_thickness no)
    (keepout (tracks allowed) (vias allowed) (pads allowed) (copperpour not_allowed) (footprints allowed))
    (fill (thermal_gap 0.508) (thermal_bridge_width 0.508))
    (polygon
      (pts
        (xy 246.87 123.735)
        (xy 245.22 123.735)
        (xy 245.22 122.02)
        (xy 246.87 122.02)
      )
    )
  )
  (zone (net 0) (net_name "") (layers "F.Cu" "In1.Cu") (hatch edge 0.508)
    (connect_pads (clearance 0))
    (min_thickness 0.254) (filled_areas_thickness no)
    (keepout (tracks allowed) (vias allowed) (pads allowed) (copperpour not_allowed) (footprints allowed))
    (fill (thermal_gap 0.508) (thermal_bridge_width 0.508))
    (polygon
      (pts
        (xy 255.54 77.995)
        (xy 253.89 77.995)
        (xy 253.89 76.28)
        (xy 255.54 76.28)
      )
    )
  )
  (zone (net 0) (net_name "") (layers "F.Cu" "In1.Cu") (hatch edge 0.508)
    (connect_pads (clearance 0))
    (min_thickness 0.254) (filled_areas_thickness no)
    (keepout (tracks allowed) (vias allowed) (pads allowed) (copperpour not_allowed) (footprints allowed))
    (fill (thermal_gap 0.508) (thermal_bridge_width 0.508))
    (polygon
      (pts
        (xy 255.53 93.235)
        (xy 253.88 93.235)
        (xy 253.88 91.52)
        (xy 255.53 91.52)
      )
    )
  )
  (zone (net 0) (net_name "") (layers "F.Cu" "In1.Cu") (hatch edge 0.508)
    (connect_pads (clearance 0))
    (min_thickness 0.254) (filled_areas_thickness no)
    (keepout (tracks allowed) (vias allowed) (pads allowed) (copperpour not_allowed) (footprints allowed))
    (fill (thermal_gap 0.508) (thermal_bridge_width 0.508))
    (polygon
      (pts
        (xy 243.665 117.575)
        (xy 243.665 119.025)
        (xy 243.45 119.225)
        (xy 242.1 119.225)
        (xy 241.95 119.075)
        (xy 241.95 117.575)
      )
    )
  )
  (zone (net 0) (net_name "") (layers "F.Cu" "In1.Cu") (hatch edge 0.508)
    (connect_pads (clearance 0))
    (min_thickness 0.254) (filled_areas_thickness no)
    (keepout (tracks allowed) (vias allowed) (pads allowed) (copperpour not_allowed) (footprints allowed))
    (fill (thermal_gap 0.508) (thermal_bridge_width 0.508))
    (polygon
      (pts
        (xy 245.6 121.19)
        (xy 243.95 121.19)
        (xy 243.95 119.625)
        (xy 244.1 119.475)
        (xy 245.6 119.475)
      )
    )
  )
  (zone (net 0) (net_name "") (layers "F.Cu" "In1.Cu") (hatch edge 0.508)
    (connect_pads (clearance 0))
    (min_thickness 0.254) (filled_areas_thickness no)
    (keepout (tracks allowed) (vias allowed) (pads allowed) (copperpour not_allowed) (footprints allowed))
    (fill (thermal_gap 0.508) (thermal_bridge_width 0.508))
    (polygon
      (pts
        (xy 251.72 121.165)
        (xy 250.07 121.165)
        (xy 250.07 119.45)
        (xy 251.72 119.45)
      )
    )
  )
  (zone (net 0) (net_name "") (layers "F.Cu" "In1.Cu") (hatch edge 0.508)
    (connect_pads (clearance 0))
    (min_thickness 0.254) (filled_areas_thickness no)
    (keepout (tracks allowed) (vias allowed) (pads allowed) (copperpour not_allowed) (footprints allowed))
    (fill (thermal_gap 0.508) (thermal_bridge_width 0.508))
    (polygon
      (pts
        (xy 253.49 119.5)
        (xy 255.115001 119.5)
        (xy 255.115001 121.215)
        (xy 253.49 121.215)
      )
    )
  )
  (zone (net 0) (net_name "") (layers "F.Cu" "In1.Cu") (hatch edge 0.508)
    (connect_pads (clearance 0))
    (min_thickness 0.254) (filled_areas_thickness no)
    (keepout (tracks allowed) (vias allowed) (pads allowed) (copperpour not_allowed) (footprints allowed))
    (fill (thermal_gap 0.508) (thermal_bridge_width 0.508))
    (polygon
      (pts
        (xy 255.52 83.075)
        (xy 253.87 83.075)
        (xy 253.87 81.36)
        (xy 255.52 81.36)
      )
    )
  )
  (zone (net 0) (net_name "") (layers "F.Cu" "In1.Cu") (hatch edge 0.508)
    (connect_pads (clearance 0))
    (min_thickness 0.254) (filled_areas_thickness no)
    (keepout (tracks allowed) (vias allowed) (pads allowed) (copperpour not_allowed) (footprints allowed))
    (fill (thermal_gap 0.508) (thermal_bridge_width 0.508))
    (polygon
      (pts
        (xy 255.54 88.155)
        (xy 253.89 88.155)
        (xy 253.89 86.44)
        (xy 255.54 86.44)
      )
    )
  )
  (zone (net 0) (net_name "") (layers "F.Cu" "In1.Cu") (hatch edge 0.508)
    (connect_pads (clearance 0))
    (min_thickness 0.254) (filled_areas_thickness no)
    (keepout (tracks allowed) (vias allowed) (pads allowed) (copperpour not_allowed) (footprints allowed))
    (fill (thermal_gap 0.508) (thermal_bridge_width 0.508))
    (polygon
      (pts
        (xy 255.52 98.31)
        (xy 253.87 98.31)
        (xy 253.87 96.595)
        (xy 255.52 96.595)
      )
    )
  )
  (zone (net 0) (net_name "") (layers "F.Cu" "In1.Cu") (hatch edge 0.508)
    (connect_pads (clearance 0))
    (min_thickness 0.254) (filled_areas_thickness no)
    (keepout (tracks allowed) (vias allowed) (pads allowed) (copperpour not_allowed) (footprints allowed))
    (fill (thermal_gap 0.508) (thermal_bridge_width 0.508))
    (polygon
      (pts
        (xy 244.53 123.325)
        (xy 242.88 123.325)
        (xy 242.88 121.61)
        (xy 244.53 121.61)
      )
    )
  )
  (zone (net 0) (net_name "") (layers "F.Cu" "In1.Cu") (hatch edge 0.508)
    (connect_pads (clearance 0))
    (min_thickness 0.254) (filled_areas_thickness no)
    (keepout (tracks allowed) (vias allowed) (pads allowed) (copperpour not_allowed) (footprints allowed))
    (fill (thermal_gap 0.508) (thermal_bridge_width 0.508))
    (polygon
      (pts
        (xy 249.38 121.165)
        (xy 247.73 121.165)
        (xy 247.73 119.45)
        (xy 249.38 119.45)
      )
    )
  )
  (zone (net 0) (net_name "") (layers "F.Cu" "In1.Cu") (hatch edge 0.508)
    (connect_pads no (clearance 0))
    (min_thickness 0.15) (filled_areas_thickness no)
    (keepout (tracks allowed) (vias allowed) (pads allowed) (copperpour not_allowed) (footprints allowed))
    (fill (thermal_gap 0.3) (thermal_bridge_width 0.2))
    (polygon
      (pts
        (xy 185.963 78.1)
        (xy 185.232 78.1)
        (xy 185.232 77.15)
        (xy 185.963 77.15)
      )
    )
  )
  (zone (net 0) (net_name "") (layers "F.Cu" "In1.Cu") (hatch edge 0.508)
    (connect_pads (clearance 0))
    (min_thickness 0.254) (filled_areas_thickness no)
    (keepout (tracks allowed) (vias allowed) (pads allowed) (copperpour not_allowed) (footprints allowed))
    (fill (thermal_gap 0.508) (thermal_bridge_width 0.508))
    (polygon
      (pts
        (xy 257.01 85.625)
        (xy 255.36 85.625)
        (xy 255.36 83.91)
        (xy 257.01 83.91)
      )
    )
  )
  (zone (net 0) (net_name "") (layers "F.Cu" "In1.Cu" "In2.Cu") (hatch edge 0.508)
    (connect_pads no (clearance 0))
    (min_thickness 0.15) (filled_areas_thickness no)
    (keepout (tracks allowed) (vias allowed) (pads allowed) (copperpour not_allowed) (footprints allowed))
    (fill (thermal_gap 0.3) (thermal_bridge_width 0.2))
    (polygon
      (pts
        (xy 197.057 84.017)
        (xy 197.057 84.066)
        (xy 197.039 84.191)
        (xy 196.974 84.323)
        (xy 196.896 84.392)
        (xy 196.783 84.452)
        (xy 196.659 84.474)
        (xy 196.526 84.45)
        (xy 196.418 84.398)
        (xy 196.325 84.305)
        (xy 196.268 84.195)
        (xy 196.262 84.067)
        (xy 196.262 84.017)
        (xy 196.262 83.067)
        (xy 196.261 83.041)
        (xy 196.267 82.927)
        (xy 196.327 82.807)
        (xy 196.417 82.717)
        (xy 196.527 82.657)
        (xy 196.657 82.647)
        (xy 196.777 82.667)
        (xy 196.887 82.717)
        (xy 196.977 82.807)
        (xy 197.037 82.927)
        (xy 197.057 83.047)
        (xy 197.057 83.067)
      )
    )
  )
  (zone (net 0) (net_name "") (layers "F.Cu" "In1.Cu" "In2.Cu") (hatch edge 0.508)
    (connect_pads (clearance 0))
    (min_thickness 0.254) (filled_areas_thickness no)
    (keepout (tracks allowed) (vias allowed) (pads allowed) (copperpour not_allowed) (footprints allowed))
    (fill (thermal_gap 0.508) (thermal_bridge_width 0.508))
    (polygon
      (pts
        (xy 194.76 96.7)
        (xy 194.87 96.76)
        (xy 194.95 96.84)
        (xy 195 96.94)
        (xy 195.02 97.06)
        (xy 195 97.18)
        (xy 194.95 97.28)
        (xy 194.87 97.36)
        (xy 194.76 97.42)
        (xy 194.69 97.43)
        (xy 193.65 97.43)
        (xy 193.535 97.42)
        (xy 193.42 97.36)
        (xy 193.34 97.28)
        (xy 193.29 97.18)
        (xy 193.27 97.06)
        (xy 193.29 96.94)
        (xy 193.34 96.84)
        (xy 193.42 96.76)
        (xy 193.53 96.7)
        (xy 193.65 96.69)
        (xy 194.65 96.69)
      )
    )
  )
  (zone (net 0) (net_name "") (layers "F.Cu" "In1.Cu" "In2.Cu") (hatch edge 0.508)
    (connect_pads (clearance 0))
    (min_thickness 0.254) (filled_areas_thickness no)
    (keepout (tracks allowed) (vias allowed) (pads allowed) (copperpour not_allowed) (footprints allowed))
    (fill (thermal_gap 0.508) (thermal_bridge_width 0.508))
    (polygon
      (pts
        (xy 148.03 61.37)
        (xy 147.17 61.37)
        (xy 147.17 60.56)
        (xy 148.03 60.56)
      )
    )
  )
  (zone (net 0) (net_name "") (layers "F.Cu" "In1.Cu" "In2.Cu") (hatch edge 0.508)
    (connect_pads (clearance 0))
    (min_thickness 0.254) (filled_areas_thickness no)
    (keepout (tracks allowed) (vias allowed) (pads allowed) (copperpour not_allowed) (footprints allowed))
    (fill (thermal_gap 0.508) (thermal_bridge_width 0.508))
    (polygon
      (pts
        (xy 194.75 94.7)
        (xy 194.86 94.76)
        (xy 194.94 94.84)
        (xy 194.99 94.94)
        (xy 195.01 95.06)
        (xy 194.99 95.18)
        (xy 194.94 95.28)
        (xy 194.86 95.36)
        (xy 194.75 95.42)
        (xy 194.68 95.43)
        (xy 193.64 95.43)
        (xy 193.525 95.42)
        (xy 193.41 95.36)
        (xy 193.33 95.28)
        (xy 193.28 95.18)
        (xy 193.26 95.06)
        (xy 193.28 94.94)
        (xy 193.33 94.84)
        (xy 193.41 94.76)
        (xy 193.52 94.7)
        (xy 193.64 94.69)
        (xy 194.64 94.69)
      )
    )
  )
  (zone (net 0) (net_name "") (layers "F.Cu" "In1.Cu" "In2.Cu") (hatch edge 0.508)
    (connect_pads (clearance 0))
    (min_thickness 0.254) (filled_areas_thickness no)
    (keepout (tracks allowed) (vias allowed) (pads allowed) (copperpour not_allowed) (footprints allowed))
    (fill (thermal_gap 0.508) (thermal_bridge_width 0.508))
    (polygon
      (pts
        (xy 194.75 88.7)
        (xy 194.86 88.76)
        (xy 194.94 88.84)
        (xy 194.99 88.94)
        (xy 195.01 89.06)
        (xy 194.99 89.18)
        (xy 194.94 89.28)
        (xy 194.86 89.36)
        (xy 194.75 89.42)
        (xy 194.68 89.43)
        (xy 193.64 89.43)
        (xy 193.525 89.42)
        (xy 193.41 89.36)
        (xy 193.33 89.28)
        (xy 193.28 89.18)
        (xy 193.26 89.06)
        (xy 193.28 88.94)
        (xy 193.33 88.84)
        (xy 193.41 88.76)
        (xy 193.52 88.7)
        (xy 193.64 88.69)
        (xy 194.64 88.69)
      )
    )
  )
  (zone (net 0) (net_name "") (layers "F.Cu" "In1.Cu" "In2.Cu") (hatch edge 0.508)
    (connect_pads (clearance 0))
    (min_thickness 0.254) (filled_areas_thickness no)
    (keepout (tracks allowed) (vias allowed) (pads allowed) (copperpour not_allowed) (footprints allowed))
    (fill (thermal_gap 0.508) (thermal_bridge_width 0.508))
    (polygon
      (pts
        (xy 221.98 61.36)
        (xy 221.12 61.36)
        (xy 221.12 60.55)
        (xy 221.98 60.55)
      )
    )
  )
  (zone (net 0) (net_name "") (layers "F.Cu" "In1.Cu" "In2.Cu") (hatch edge 0.508)
    (connect_pads no (clearance 0))
    (min_thickness 0.15) (filled_areas_thickness no)
    (keepout (tracks allowed) (vias allowed) (pads allowed) (copperpour not_allowed) (footprints allowed))
    (fill (thermal_gap 0.3) (thermal_bridge_width 0.2))
    (polygon
      (pts
        (xy 179.04 80.01)
        (xy 179.04 80.059)
        (xy 179.022 80.184)
        (xy 178.957 80.316)
        (xy 178.879 80.385)
        (xy 178.766 80.445)
        (xy 178.642 80.467)
        (xy 178.509 80.443)
        (xy 178.401 80.391)
        (xy 178.308 80.298)
        (xy 178.251 80.188)
        (xy 178.245 80.06)
        (xy 178.245 80.01)
        (xy 178.245 79.06)
        (xy 178.244 79.034)
        (xy 178.25 78.92)
        (xy 178.31 78.8)
        (xy 178.4 78.71)
        (xy 178.51 78.65)
        (xy 178.64 78.64)
        (xy 178.76 78.66)
        (xy 178.87 78.71)
        (xy 178.96 78.8)
        (xy 179.02 78.92)
        (xy 179.04 79.04)
        (xy 179.04 79.06)
      )
    )
  )
  (zone (net 0) (net_name "") (layers "F.Cu" "In1.Cu" "In2.Cu") (hatch edge 0.508)
    (connect_pads no (clearance 0))
    (min_thickness 0.15) (filled_areas_thickness no)
    (keepout (tracks allowed) (vias allowed) (pads allowed) (copperpour not_allowed) (footprints allowed))
    (fill (thermal_gap 0.3) (thermal_bridge_width 0.2))
    (polygon
      (pts
        (xy 177.037 79)
        (xy 177.037 79.049)
        (xy 177.019 79.174)
        (xy 176.959 79.288)
        (xy 176.895 79.359)
        (xy 176.781 79.4)
        (xy 176.657 79.41)
        (xy 176.513 79.398)
        (xy 176.427 79.35)
        (xy 176.337 79.262)
        (xy 176.251 79.137)
        (xy 176.242 79.05)
        (xy 176.242 79)
        (xy 176.242 78.05)
        (xy 176.241 78.024)
        (xy 176.247 77.91)
        (xy 176.307 77.79)
        (xy 176.397 77.7)
        (xy 176.507 77.64)
        (xy 176.637 77.63)
        (xy 176.757 77.65)
        (xy 176.867 77.7)
        (xy 176.957 77.79)
        (xy 177.017 77.91)
        (xy 177.037 78.03)
        (xy 177.037 78.05)
      )
    )
  )
  (zone (net 0) (net_name "") (layers "F.Cu" "In1.Cu" "In2.Cu") (hatch edge 0.508)
    (connect_pads (clearance 0))
    (min_thickness 0.254) (filled_areas_thickness no)
    (keepout (tracks allowed) (vias allowed) (pads allowed) (copperpour not_allowed) (footprints allowed))
    (fill (thermal_gap 0.508) (thermal_bridge_width 0.508))
    (polygon
      (pts
        (xy 194.75 98.71)
        (xy 194.86 98.77)
        (xy 194.94 98.85)
        (xy 194.99 98.95)
        (xy 195.01 99.07)
        (xy 194.99 99.19)
        (xy 194.94 99.29)
        (xy 194.86 99.37)
        (xy 194.75 99.43)
        (xy 194.68 99.44)
        (xy 193.64 99.44)
        (xy 193.525 99.43)
        (xy 193.41 99.37)
        (xy 193.33 99.29)
        (xy 193.28 99.19)
        (xy 193.26 99.07)
        (xy 193.28 98.95)
        (xy 193.33 98.85)
        (xy 193.41 98.77)
        (xy 193.52 98.71)
        (xy 193.64 98.7)
        (xy 194.64 98.7)
      )
    )
  )
  (zone (net 0) (net_name "") (layers "F.Cu" "In1.Cu" "In2.Cu") (hatch edge 0.508)
    (connect_pads (clearance 0))
    (min_thickness 0.254) (filled_areas_thickness no)
    (keepout (tracks allowed) (vias allowed) (pads allowed) (copperpour not_allowed) (footprints allowed))
    (fill (thermal_gap 0.508) (thermal_bridge_width 0.508))
    (polygon
      (pts
        (xy 148.82 57.04)
        (xy 148.09 57.04)
        (xy 148.09 56.23)
        (xy 148.82 56.23)
      )
    )
  )
  (zone (net 0) (net_name "") (layers "F.Cu" "In1.Cu" "In2.Cu") (hatch edge 0.508)
    (connect_pads (clearance 0))
    (min_thickness 0.254) (filled_areas_thickness no)
    (keepout (tracks allowed) (vias allowed) (pads allowed) (copperpour not_allowed) (footprints allowed))
    (fill (thermal_gap 0.508) (thermal_bridge_width 0.508))
    (polygon
      (pts
        (xy 194.75 92.7)
        (xy 194.86 92.76)
        (xy 194.94 92.84)
        (xy 194.99 92.94)
        (xy 195.01 93.06)
        (xy 194.99 93.18)
        (xy 194.94 93.28)
        (xy 194.86 93.36)
        (xy 194.75 93.42)
        (xy 194.68 93.43)
        (xy 193.64 93.43)
        (xy 193.525 93.42)
        (xy 193.41 93.36)
        (xy 193.33 93.28)
        (xy 193.28 93.18)
        (xy 193.26 93.06)
        (xy 193.28 92.94)
        (xy 193.33 92.84)
        (xy 193.41 92.76)
        (xy 193.52 92.7)
        (xy 193.64 92.69)
        (xy 194.64 92.69)
      )
    )
  )
  (zone (net 0) (net_name "") (layers "F.Cu" "In1.Cu" "In2.Cu") (hatch edge 0.508)
    (connect_pads no (clearance 0))
    (min_thickness 0.15) (filled_areas_thickness no)
    (keepout (tracks allowed) (vias allowed) (pads allowed) (copperpour not_allowed) (footprints allowed))
    (fill (thermal_gap 0.3) (thermal_bridge_width 0.2))
    (polygon
      (pts
        (xy 197.207 81.028)
        (xy 197.207 81.077)
        (xy 197.189 81.202)
        (xy 197.126 81.318)
        (xy 197.047 81.394)
        (xy 196.957 81.417)
        (xy 196.805 81.426)
        (xy 196.65 81.42)
        (xy 196.556 81.381)
        (xy 196.475 81.299)
        (xy 196.418 81.206)
        (xy 196.412 81.078)
        (xy 196.412 81.028)
        (xy 196.412 80.078)
        (xy 196.411 80.052)
        (xy 196.417 79.938)
        (xy 196.477 79.818)
        (xy 196.567 79.728)
        (xy 196.677 79.668)
        (xy 196.807 79.658)
        (xy 196.927 79.678)
        (xy 197.037 79.728)
        (xy 197.127 79.818)
        (xy 197.187 79.938)
        (xy 197.207 80.058)
        (xy 197.207 80.078)
      )
    )
  )
  (zone (net 0) (net_name "") (layers "F.Cu" "In1.Cu" "In2.Cu") (hatch edge 0.508)
    (connect_pads (clearance 0))
    (min_thickness 0.254) (filled_areas_thickness no)
    (keepout (tracks allowed) (vias allowed) (pads allowed) (copperpour not_allowed) (footprints allowed))
    (fill (thermal_gap 0.508) (thermal_bridge_width 0.508))
    (polygon
      (pts
        (xy 222.79 57.04)
        (xy 222.06 57.04)
        (xy 222.06 56.23)
        (xy 222.79 56.23)
      )
    )
  )
  (zone (net 0) (net_name "") (layers "F.Cu" "In1.Cu" "In2.Cu") (hatch edge 0.508)
    (connect_pads (clearance 0))
    (min_thickness 0.254) (filled_areas_thickness no)
    (keepout (tracks allowed) (vias allowed) (pads allowed) (copperpour not_allowed) (footprints allowed))
    (fill (thermal_gap 0.508) (thermal_bridge_width 0.508))
    (polygon
      (pts
        (xy 194.75 100.7)
        (xy 194.86 100.76)
        (xy 194.94 100.84)
        (xy 194.99 100.94)
        (xy 195.01 101.06)
        (xy 194.99 101.18)
        (xy 194.94 101.28)
        (xy 194.86 101.36)
        (xy 194.75 101.42)
        (xy 194.68 101.43)
        (xy 193.64 101.43)
        (xy 193.525 101.42)
        (xy 193.41 101.36)
        (xy 193.33 101.28)
        (xy 193.28 101.18)
        (xy 193.26 101.06)
        (xy 193.28 100.94)
        (xy 193.33 100.84)
        (xy 193.41 100.76)
        (xy 193.52 100.7)
        (xy 193.64 100.69)
        (xy 194.64 100.69)
      )
    )
  )
  (zone (net 0) (net_name "") (layers "F.Cu" "In1.Cu" "In2.Cu") (hatch edge 0.508)
    (connect_pads (clearance 0))
    (min_thickness 0.254) (filled_areas_thickness no)
    (keepout (tracks allowed) (vias allowed) (pads allowed) (copperpour not_allowed) (footprints allowed))
    (fill (thermal_gap 0.508) (thermal_bridge_width 0.508))
    (polygon
      (pts
        (xy 192.75 95.69)
        (xy 192.86 95.75)
        (xy 192.94 95.83)
        (xy 192.99 95.93)
        (xy 193.01 96.05)
        (xy 192.99 96.17)
        (xy 192.94 96.27)
        (xy 192.86 96.35)
        (xy 192.75 96.41)
        (xy 192.68 96.42)
        (xy 191.64 96.42)
        (xy 191.525 96.41)
        (xy 191.41 96.35)
        (xy 191.33 96.27)
        (xy 191.28 96.17)
        (xy 191.26 96.05)
        (xy 191.28 95.93)
        (xy 191.33 95.83)
        (xy 191.41 95.75)
        (xy 191.52 95.69)
        (xy 191.64 95.68)
        (xy 192.64 95.68)
      )
    )
  )
  (zone (net 0) (net_name "") (layers "F.Cu" "In1.Cu" "In2.Cu") (hatch edge 0.508)
    (connect_pads (clearance 0))
    (min_thickness 0.254) (filled_areas_thickness no)
    (keepout (tracks allowed) (vias allowed) (pads allowed) (copperpour not_allowed) (footprints allowed))
    (fill (thermal_gap 0.508) (thermal_bridge_width 0.508))
    (polygon
      (pts
        (xy 194.75 90.7)
        (xy 194.86 90.76)
        (xy 194.94 90.84)
        (xy 194.99 90.94)
        (xy 195.01 91.06)
        (xy 194.99 91.18)
        (xy 194.94 91.28)
        (xy 194.86 91.36)
        (xy 194.75 91.42)
        (xy 194.68 91.43)
        (xy 193.64 91.43)
        (xy 193.525 91.42)
        (xy 193.41 91.36)
        (xy 193.33 91.28)
        (xy 193.28 91.18)
        (xy 193.26 91.06)
        (xy 193.28 90.94)
        (xy 193.33 90.84)
        (xy 193.41 90.76)
        (xy 193.52 90.7)
        (xy 193.64 90.69)
        (xy 194.64 90.69)
      )
    )
  )
  (zone (net 0) (net_name "") (layers "F.Cu" "In1.Cu" "In2.Cu" "In3.Cu" "In4.Cu" "In5.Cu") (hatch edge 0.508)
    (connect_pads (clearance 0))
    (min_thickness 0.254) (filled_areas_thickness no)
    (keepout (tracks allowed) (vias allowed) (pads allowed) (copperpour not_allowed) (footprints allowed))
    (fill (thermal_gap 0.508) (thermal_bridge_width 0.508))
    (polygon
      (pts
        (xy 158.16 56.99)
        (xy 157.43 56.99)
        (xy 157.43 56.28)
        (xy 158.16 56.28)
      )
    )
  )
  (zone (net 0) (net_name "") (layers "F.Cu" "In1.Cu" "In2.Cu" "In3.Cu" "In4.Cu" "In5.Cu") (hatch edge 0.508)
    (connect_pads no (clearance 0))
    (min_thickness 0.15) (filled_areas_thickness no)
    (keepout (tracks allowed) (vias allowed) (pads allowed) (copperpour not_allowed) (footprints allowed))
    (fill (thermal_gap 0.3) (thermal_bridge_width 0.2))
    (polygon
      (pts
        (xy 193.658 79.465)
        (xy 193.533 79.445)
        (xy 193.401001 79.379999)
        (xy 193.332 79.302)
        (xy 193.272001 79.189)
        (xy 193.25 79.065)
        (xy 193.274 78.932)
        (xy 193.326001 78.824)
        (xy 193.419 78.731001)
        (xy 193.529 78.674)
        (xy 193.648 78.658)
        (xy 194.645 78.658)
        (xy 194.779 78.674)
        (xy 194.897 78.734)
        (xy 194.983 78.823)
        (xy 195.04 78.933)
        (xy 195.06 79.06)
        (xy 195.04 79.189)
        (xy 194.981 79.306)
        (xy 194.889 79.393)
        (xy 194.781 79.446)
        (xy 194.657 79.466)
      )
    )
  )
  (zone (net 0) (net_name "") (layers "F.Cu" "In1.Cu" "In2.Cu" "In3.Cu" "In4.Cu" "In5.Cu") (hatch edge 0.508)
    (connect_pads (clearance 0))
    (min_thickness 0.254) (filled_areas_thickness no)
    (keepout (tracks allowed) (vias allowed) (pads allowed) (copperpour not_allowed) (footprints allowed))
    (fill (thermal_gap 0.508) (thermal_bridge_width 0.508))
    (polygon
      (pts
        (xy 212.64 61.33)
        (xy 211.79 61.33)
        (xy 211.79 60.6)
        (xy 212.64 60.6)
      )
    )
  )
  (zone (net 0) (net_name "") (layers "F.Cu" "In1.Cu" "In2.Cu" "In3.Cu" "In4.Cu" "In5.Cu") (hatch edge 0.508)
    (connect_pads no (clearance 0))
    (min_thickness 0.15) (filled_areas_thickness no)
    (keepout (tracks allowed) (vias allowed) (pads allowed) (copperpour not_allowed) (footprints allowed))
    (fill (thermal_gap 0.3) (thermal_bridge_width 0.2))
    (polygon
      (pts
        (xy 195.06047 85.064379)
        (xy 195.04047 85.189379)
        (xy 194.975469 85.321378)
        (xy 194.89747 85.390379)
        (xy 194.78447 85.450378)
        (xy 194.66047 85.47238)
        (xy 194.52747 85.448379)
        (xy 194.41947 85.396378)
        (xy 194.326472 85.303379)
        (xy 194.26947 85.193379)
        (xy 194.253471 85.074379)
        (xy 194.25347 84.077379)
        (xy 194.26947 83.943379)
        (xy 194.32947 83.825379)
        (xy 194.41847 83.739379)
        (xy 194.52847 83.682378)
        (xy 194.65547 83.662379)
        (xy 194.78447 83.682379)
        (xy 194.90147 83.741379)
        (xy 194.988471 83.833379)
        (xy 195.04147 83.941379)
        (xy 195.06147 84.065379)
      )
    )
  )
  (zone (net 0) (net_name "") (layers "F.Cu" "In1.Cu" "In2.Cu" "In3.Cu" "In4.Cu" "In5.Cu") (hatch edge 0.508)
    (connect_pads (clearance 0))
    (min_thickness 0.254) (filled_areas_thickness no)
    (keepout (tracks allowed) (vias allowed) (pads allowed) (copperpour not_allowed) (footprints allowed))
    (fill (thermal_gap 0.508) (thermal_bridge_width 0.508))
    (polygon
      (pts
        (xy 231.34 61.32)
        (xy 230.49 61.32)
        (xy 230.49 60.61)
        (xy 231.34 60.61)
      )
    )
  )
  (zone (net 0) (net_name "") (layers "F.Cu" "In1.Cu" "In2.Cu" "In3.Cu" "In4.Cu" "In5.Cu") (hatch edge 0.508)
    (connect_pads (clearance 0))
    (min_thickness 0.254) (filled_areas_thickness no)
    (keepout (tracks allowed) (vias allowed) (pads allowed) (copperpour not_allowed) (footprints allowed))
    (fill (thermal_gap 0.508) (thermal_bridge_width 0.508))
    (polygon
      (pts
        (xy 157.33 61.335)
        (xy 156.6 61.335)
        (xy 156.6 60.6)
        (xy 157.33 60.6)
      )
    )
  )
  (zone (net 0) (net_name "") (layers "F.Cu" "In1.Cu" "In2.Cu" "In3.Cu" "In4.Cu" "In5.Cu") (hatch edge 0.508)
    (connect_pads (clearance 0))
    (min_thickness 0.254) (filled_areas_thickness no)
    (keepout (tracks allowed) (vias allowed) (pads allowed) (copperpour not_allowed) (footprints allowed))
    (fill (thermal_gap 0.508) (thermal_bridge_width 0.508))
    (polygon
      (pts
        (xy 232.14 56.99)
        (xy 231.41 56.99)
        (xy 231.41 56.28)
        (xy 232.14 56.28)
      )
    )
  )
  (zone (net 0) (net_name "") (layers "F.Cu" "In1.Cu" "In2.Cu" "In3.Cu" "In4.Cu" "In5.Cu") (hatch edge 0.508)
    (connect_pads (clearance 0))
    (min_thickness 0.254) (filled_areas_thickness no)
    (keepout (tracks allowed) (vias allowed) (pads allowed) (copperpour not_allowed) (footprints allowed))
    (fill (thermal_gap 0.508) (thermal_bridge_width 0.508))
    (polygon
      (pts
        (xy 139.47 56.99)
        (xy 138.74 56.99)
        (xy 138.74 56.28)
        (xy 139.47 56.28)
      )
    )
  )
  (zone (net 0) (net_name "") (layers "F.Cu" "In1.Cu" "In2.Cu" "In3.Cu" "In4.Cu" "In5.Cu") (hatch edge 0.508)
    (connect_pads (clearance 0))
    (min_thickness 0.254) (filled_areas_thickness no)
    (keepout (tracks allowed) (vias allowed) (pads allowed) (copperpour not_allowed) (footprints allowed))
    (fill (thermal_gap 0.508) (thermal_bridge_width 0.508))
    (polygon
      (pts
        (xy 213.44 57.01)
        (xy 212.71 57.01)
        (xy 212.71 56.27)
        (xy 213.44 56.27)
      )
    )
  )
  (zone (net 0) (net_name "") (layers "F.Cu" "In1.Cu" "In2.Cu" "In3.Cu" "In4.Cu" "In5.Cu") (hatch edge 0.508)
    (connect_pads no (clearance 0))
    (min_thickness 0.15) (filled_areas_thickness no)
    (keepout (tracks allowed) (vias allowed) (pads allowed) (copperpour not_allowed) (footprints allowed))
    (fill (thermal_gap 0.3) (thermal_bridge_width 0.2))
    (polygon
      (pts
        (xy 192.654 77.363)
        (xy 192.605 77.363)
        (xy 192.48 77.345)
        (xy 192.348001 77.279999)
        (xy 192.279 77.202)
        (xy 192.219001 77.089)
        (xy 192.197 76.965)
        (xy 192.221 76.832)
        (xy 192.273001 76.724)
        (xy 192.366 76.631001)
        (xy 192.476 76.574)
        (xy 192.604 76.568)
        (xy 192.654 76.567999)
        (xy 193.429 76.569)
        (xy 193.559 76.573)
        (xy 193.67 76.634)
        (xy 193.76 76.724)
        (xy 193.817 76.837)
        (xy 193.834 76.962)
        (xy 193.814 77.088)
        (xy 193.753 77.204)
        (xy 193.67 77.288)
        (xy 193.556 77.344)
        (xy 193.438 77.363)
      )
    )
  )
  (zone (net 0) (net_name "") (layers "F.Cu" "In1.Cu" "In2.Cu" "In3.Cu" "In4.Cu" "In5.Cu") (hatch edge 0.508)
    (connect_pads no (clearance 0))
    (min_thickness 0.15) (filled_areas_thickness no)
    (keepout (tracks allowed) (vias allowed) (pads allowed) (copperpour not_allowed) (footprints allowed))
    (fill (thermal_gap 0.3) (thermal_bridge_width 0.2))
    (polygon
      (pts
        (xy 194.65491 82.464261)
        (xy 194.52991 82.444261)
        (xy 194.397911 82.37926)
        (xy 194.32891 82.301261)
        (xy 194.268911 82.188261)
        (xy 194.24691 82.064261)
        (xy 194.27091 81.931261)
        (xy 194.322911 81.823261)
        (xy 194.41591 81.730262)
        (xy 194.52591 81.673261)
        (xy 194.64491 81.657261)
        (xy 195.64191 81.657261)
        (xy 195.77591 81.673261)
        (xy 195.89391 81.733261)
        (xy 195.97991 81.822261)
        (xy 196.03691 81.932261)
        (xy 196.05691 82.059261)
        (xy 196.03691 82.188261)
        (xy 195.97791 82.305261)
        (xy 195.88591 82.392261)
        (xy 195.77791 82.445261)
        (xy 195.65391 82.465261)
      )
    )
  )
  (zone (net 0) (net_name "") (layers "F.Cu" "In1.Cu" "In2.Cu" "In3.Cu" "In4.Cu" "In5.Cu") (hatch edge 0.508)
    (connect_pads (clearance 0))
    (min_thickness 0.254) (filled_areas_thickness no)
    (keepout (tracks allowed) (vias allowed) (pads allowed) (copperpour not_allowed) (footprints allowed))
    (fill (thermal_gap 0.508) (thermal_bridge_width 0.508))
    (polygon
      (pts
        (xy 138.7 61.325)
        (xy 137.84 61.325)
        (xy 137.84 60.59)
        (xy 138.7 60.59)
      )
    )
  )
  (zone (net 0) (net_name "") (layers "F.Cu" "In1.Cu" "In2.Cu" "In3.Cu" "In4.Cu" "In5.Cu") (hatch edge 0.508)
    (connect_pads (clearance 0))
    (min_thickness 0.254) (filled_areas_thickness no)
    (keepout (tracks allowed) (vias allowed) (pads allowed) (copperpour not_allowed) (footprints allowed))
    (fill (thermal_gap 0.508) (thermal_bridge_width 0.508))
    (polygon
      (pts
        (xy 192.73 93.7)
        (xy 192.84 93.76)
        (xy 192.92 93.84)
        (xy 192.97 93.94)
        (xy 192.99 94.06)
        (xy 192.97 94.18)
        (xy 192.92 94.28)
        (xy 192.84 94.36)
        (xy 192.73 94.42)
        (xy 192.66 94.43)
        (xy 191.62 94.43)
        (xy 191.505 94.42)
        (xy 191.39 94.36)
        (xy 191.31 94.28)
        (xy 191.26 94.18)
        (xy 191.24 94.06)
        (xy 191.26 93.94)
        (xy 191.31 93.84)
        (xy 191.39 93.76)
        (xy 191.5 93.7)
        (xy 191.62 93.69)
        (xy 192.62 93.69)
      )
    )
  )
  (zone (net 0) (net_name "") (layers "F.Cu" "In1.Cu" "In2.Cu" "In3.Cu" "In4.Cu" "In5.Cu" "In6.Cu" "In7.Cu") (hatch edge 0.508)
    (connect_pads (clearance 0))
    (min_thickness 0.254) (filled_areas_thickness no)
    (keepout (tracks allowed) (vias allowed) (pads allowed) (copperpour not_allowed) (footprints allowed))
    (fill (thermal_gap 0.508) (thermal_bridge_width 0.508))
    (polygon
      (pts
        (xy 204.04 57)
        (xy 203.31 57)
        (xy 203.31 56.26)
        (xy 204.04 56.26)
      )
    )
  )
  (zone (net 0) (net_name "") (layers "F.Cu" "In1.Cu" "In2.Cu" "In3.Cu" "In4.Cu" "In5.Cu" "In6.Cu" "In7.Cu") (hatch edge 0.508)
    (connect_pads (clearance 0))
    (min_thickness 0.254) (filled_areas_thickness no)
    (keepout (tracks allowed) (vias allowed) (pads allowed) (copperpour not_allowed) (footprints allowed))
    (fill (thermal_gap 0.508) (thermal_bridge_width 0.508))
    (polygon
      (pts
        (xy 203.35 61.33)
        (xy 202.5 61.33)
        (xy 202.5 60.6)
        (xy 203.35 60.6)
      )
    )
  )
  (zone (net 0) (net_name "") (layers "F.Cu" "In1.Cu" "In2.Cu" "In3.Cu" "In4.Cu" "In5.Cu" "In6.Cu" "In7.Cu" "In8.Cu" "In9.Cu" "In10.Cu" "B.Cu") (hatch edge 0.508)
    (connect_pads (clearance 0))
    (min_thickness 0.254) (filled_areas_thickness no)
    (keepout (tracks allowed) (vias allowed) (pads allowed) (copperpour not_allowed) (footprints allowed))
    (fill (thermal_gap 0.508) (thermal_bridge_width 0.508))
    (polygon
      (pts
        (xy 246.29 114.31)
        (xy 245.55 114.31)
        (xy 245.55 113.64)
        (xy 246.29 113.64)
      )
    )
  )
  (zone (net 0) (net_name "") (layers "F.Cu" "In1.Cu" "In2.Cu" "In3.Cu" "In4.Cu" "In5.Cu" "In6.Cu" "In7.Cu" "In8.Cu" "In9.Cu" "In10.Cu" "B.Cu") (hatch edge 0.508)
    (connect_pads (clearance 0))
    (min_thickness 0.254) (filled_areas_thickness no)
    (keepout (tracks allowed) (vias allowed) (pads allowed) (copperpour not_allowed) (footprints allowed))
    (fill (thermal_gap 0.508) (thermal_bridge_width 0.508))
    (polygon
      (pts
        (xy 130.14 56.99)
        (xy 129.41 56.99)
        (xy 129.41 56.28)
        (xy 130.14 56.28)
      )
    )
  )
  (zone (net 0) (net_name "") (layers "F.Cu" "In1.Cu" "In2.Cu" "In3.Cu" "In4.Cu" "In5.Cu" "In6.Cu" "In7.Cu" "In8.Cu" "In9.Cu" "In10.Cu" "B.Cu") (hatch edge 0.508)
    (connect_pads (clearance 0))
    (min_thickness 0.254) (filled_areas_thickness no)
    (keepout (tracks allowed) (vias allowed) (pads allowed) (copperpour not_allowed) (footprints allowed))
    (fill (thermal_gap 0.508) (thermal_bridge_width 0.508))
    (polygon
      (pts
        (xy 245.56 119.98)
        (xy 246.295 119.98)
        (xy 246.295 120.65)
        (xy 245.559999 120.65)
      )
    )
  )
  (zone (net 0) (net_name "") (layers "F.Cu" "In1.Cu" "In2.Cu" "In3.Cu" "In4.Cu" "In5.Cu" "In6.Cu" "In7.Cu" "In8.Cu" "In9.Cu" "In10.Cu" "B.Cu") (hatch edge 0.508)
    (connect_pads (clearance 0))
    (min_thickness 0.254) (filled_areas_thickness no)
    (keepout (tracks allowed) (vias allowed) (pads allowed) (copperpour not_allowed) (footprints allowed))
    (fill (thermal_gap 0.508) (thermal_bridge_width 0.508))
    (polygon
      (pts
        (xy 245.02 93.98)
        (xy 244.28 93.98)
        (xy 244.28 93.31)
        (xy 245.02 93.31)
      )
    )
  )
  (zone (net 0) (net_name "") (layers "F.Cu" "In1.Cu" "In2.Cu" "In3.Cu" "In4.Cu" "In5.Cu" "In6.Cu" "In7.Cu" "In8.Cu" "In9.Cu" "In10.Cu" "B.Cu") (hatch edge 0.508)
    (connect_pads (clearance 0))
    (min_thickness 0.254) (filled_areas_thickness no)
    (keepout (tracks allowed) (vias allowed) (pads allowed) (copperpour not_allowed) (footprints allowed))
    (fill (thermal_gap 0.508) (thermal_bridge_width 0.508))
    (polygon
      (pts
        (xy 253.905 118.1)
        (xy 253.175 118.1)
        (xy 253.175 117.43)
        (xy 253.905 117.43)
      )
    )
  )
  (zone (net 0) (net_name "") (layers "F.Cu" "In1.Cu" "In2.Cu" "In3.Cu" "In4.Cu" "In5.Cu" "In6.Cu" "In7.Cu" "In8.Cu" "In9.Cu" "In10.Cu" "B.Cu") (hatch edge 0.508)
    (connect_pads (clearance 0))
    (min_thickness 0.254) (filled_areas_thickness no)
    (keepout (tracks allowed) (vias allowed) (pads allowed) (copperpour not_allowed) (footprints allowed))
    (fill (thermal_gap 0.508) (thermal_bridge_width 0.508))
    (polygon
      (pts
        (xy 240.68 61.32)
        (xy 239.82 61.32)
        (xy 239.82 60.61)
        (xy 240.68 60.61)
      )
    )
  )
  (zone (net 0) (net_name "") (layers "F.Cu" "In1.Cu" "In2.Cu" "In3.Cu" "In4.Cu" "In5.Cu" "In6.Cu" "In7.Cu" "In8.Cu" "In9.Cu" "In10.Cu" "B.Cu") (hatch edge 0.508)
    (connect_pads (clearance 0))
    (min_thickness 0.254) (filled_areas_thickness no)
    (keepout (tracks allowed) (vias allowed) (pads allowed) (copperpour not_allowed) (footprints allowed))
    (fill (thermal_gap 0.508) (thermal_bridge_width 0.508))
    (polygon
      (pts
        (xy 255.17 110.5)
        (xy 254.44 110.5)
        (xy 254.44 109.83)
        (xy 255.17 109.83)
      )
    )
  )
  (zone (net 0) (net_name "") (layers "F.Cu" "In1.Cu" "In2.Cu" "In3.Cu" "In4.Cu" "In5.Cu" "In6.Cu" "In7.Cu" "In8.Cu" "In9.Cu" "In10.Cu" "B.Cu") (hatch edge 0.508)
    (connect_pads (clearance 0))
    (min_thickness 0.254) (filled_areas_thickness no)
    (keepout (tracks allowed) (vias allowed) (pads allowed) (copperpour not_allowed) (footprints allowed))
    (fill (thermal_gap 0.508) (thermal_bridge_width 0.508))
    (polygon
      (pts
        (xy 256.445 123.2)
        (xy 255.715 123.2)
        (xy 255.715 122.53)
        (xy 256.445 122.53)
      )
    )
  )
  (zone (net 0) (net_name "") (layers "F.Cu" "In1.Cu" "In2.Cu" "In3.Cu" "In4.Cu" "In5.Cu" "In6.Cu" "In7.Cu" "In8.Cu" "In9.Cu" "In10.Cu" "B.Cu") (hatch edge 0.508)
    (connect_pads (clearance 0))
    (min_thickness 0.254) (filled_areas_thickness no)
    (keepout (tracks allowed) (vias allowed) (pads allowed) (copperpour not_allowed) (footprints allowed))
    (fill (thermal_gap 0.508) (thermal_bridge_width 0.508))
    (polygon
      (pts
        (xy 248.83 110.48)
        (xy 248.09 110.48)
        (xy 248.09 109.81)
        (xy 248.83 109.81)
      )
    )
  )
  (zone (net 0) (net_name "") (layers "F.Cu" "In1.Cu" "In2.Cu" "In3.Cu" "In4.Cu" "In5.Cu" "In6.Cu" "In7.Cu" "In8.Cu" "In9.Cu" "In10.Cu" "B.Cu") (hatch edge 0.508)
    (connect_pads (clearance 0))
    (min_thickness 0.254) (filled_areas_thickness no)
    (keepout (tracks allowed) (vias allowed) (pads allowed) (copperpour not_allowed) (footprints allowed))
    (fill (thermal_gap 0.508) (thermal_bridge_width 0.508))
    (polygon
      (pts
        (xy 245.02 113.02)
        (xy 244.28 113.02)
        (xy 244.28 112.35)
        (xy 245.02 112.35)
      )
    )
  )
  (zone (net 0) (net_name "") (layers "F.Cu" "In1.Cu" "In2.Cu" "In3.Cu" "In4.Cu" "In5.Cu" "In6.Cu" "In7.Cu" "In8.Cu" "In9.Cu" "In10.Cu" "B.Cu") (hatch edge 0.508)
    (connect_pads (clearance 0))
    (min_thickness 0.254) (filled_areas_thickness no)
    (keepout (tracks allowed) (vias allowed) (pads allowed) (copperpour not_allowed) (footprints allowed))
    (fill (thermal_gap 0.508) (thermal_bridge_width 0.508))
    (polygon
      (pts
        (xy 246.29 99.06)
        (xy 245.55 99.06)
        (xy 245.55 98.39)
        (xy 246.29 98.39)
      )
    )
  )
  (zone (net 0) (net_name "") (layers "F.Cu" "In1.Cu" "In2.Cu" "In3.Cu" "In4.Cu" "In5.Cu" "In6.Cu" "In7.Cu" "In8.Cu" "In9.Cu" "In10.Cu" "B.Cu") (hatch edge 0.508)
    (connect_pads (clearance 0))
    (min_thickness 0.254) (filled_areas_thickness no)
    (keepout (tracks allowed) (vias allowed) (pads allowed) (copperpour not_allowed) (footprints allowed))
    (fill (thermal_gap 0.508) (thermal_bridge_width 0.508))
    (polygon
      (pts
        (xy 247.56 113.02)
        (xy 246.82 113.02)
        (xy 246.82 112.35)
        (xy 247.56 112.35)
      )
    )
  )
  (zone (net 0) (net_name "") (layers "F.Cu" "In1.Cu" "In2.Cu" "In3.Cu" "In4.Cu" "In5.Cu" "In6.Cu" "In7.Cu" "In8.Cu" "In9.Cu" "In10.Cu" "B.Cu") (hatch edge 0.508)
    (connect_pads (clearance 0))
    (min_thickness 0.254) (filled_areas_thickness no)
    (keepout (tracks allowed) (vias allowed) (pads allowed) (copperpour not_allowed) (footprints allowed))
    (fill (thermal_gap 0.508) (thermal_bridge_width 0.508))
    (polygon
      (pts
        (xy 248.83 102.85)
        (xy 248.09 102.85)
        (xy 248.09 102.18)
        (xy 248.83 102.18)
      )
    )
  )
  (zone (net 0) (net_name "") (layers "F.Cu" "In1.Cu" "In2.Cu" "In3.Cu" "In4.Cu" "In5.Cu" "In6.Cu" "In7.Cu" "In8.Cu" "In9.Cu" "In10.Cu" "B.Cu") (hatch edge 0.508)
    (connect_pads no (clearance 0))
    (min_thickness 0.15) (filled_areas_thickness no)
    (keepout (tracks allowed) (vias allowed) (pads allowed) (copperpour not_allowed) (footprints allowed))
    (fill (thermal_gap 0.3) (thermal_bridge_width 0.2))
    (polygon
      (pts
        (xy 192.648 83.533)
        (xy 192.766 83.55)
        (xy 192.871 83.602)
        (xy 192.95 83.684)
        (xy 193.002 83.787)
        (xy 193.026 83.905)
        (xy 193.005 84.026)
        (xy 192.951 84.125)
        (xy 192.882 84.199)
        (xy 192.768 84.261)
        (xy 192.65 84.282)
        (xy 191.647 84.282)
        (xy 191.534 84.262)
        (xy 191.43 84.211)
        (xy 191.345 84.125)
        (xy 191.292 84.024)
        (xy 191.277 83.928)
        (xy 191.277 83.888)
        (xy 191.291 83.792)
        (xy 191.34 83.689)
        (xy 191.426 83.606)
        (xy 191.532 83.548)
        (xy 191.649 83.531)
      )
    )
  )
  (zone (net 0) (net_name "") (layers "F.Cu" "In1.Cu" "In2.Cu" "In3.Cu" "In4.Cu" "In5.Cu" "In6.Cu" "In7.Cu" "In8.Cu" "In9.Cu" "In10.Cu" "B.Cu") (hatch edge 0.508)
    (connect_pads (clearance 0))
    (min_thickness 0.254) (filled_areas_thickness no)
    (keepout (tracks allowed) (vias allowed) (pads allowed) (copperpour not_allowed) (footprints allowed))
    (fill (thermal_gap 0.508) (thermal_bridge_width 0.508))
    (polygon
      (pts
        (xy 256.42 77.47)
        (xy 255.75 77.47)
        (xy 255.75 76.7)
        (xy 256.085 76.7)
        (xy 256.42 76.7)
      )
    )
  )
  (zone (net 0) (net_name "") (layers "F.Cu" "In1.Cu" "In2.Cu" "In3.Cu" "In4.Cu" "In5.Cu" "In6.Cu" "In7.Cu" "In8.Cu" "In9.Cu" "In10.Cu" "B.Cu") (hatch edge 0.508)
    (connect_pads (clearance 0))
    (min_thickness 0.254) (filled_areas_thickness no)
    (keepout (tracks allowed) (vias allowed) (pads allowed) (copperpour not_allowed) (footprints allowed))
    (fill (thermal_gap 0.508) (thermal_bridge_width 0.508))
    (polygon
      (pts
        (xy 255.17 105.51)
        (xy 254.44 105.51)
        (xy 254.44 104.74)
        (xy 254.815 104.74)
        (xy 255.17 104.74)
      )
    )
  )
  (zone (net 0) (net_name "") (layers "F.Cu" "In1.Cu" "In2.Cu" "In3.Cu" "In4.Cu" "In5.Cu" "In6.Cu" "In7.Cu" "In8.Cu" "In9.Cu" "In10.Cu" "B.Cu") (hatch edge 0.508)
    (connect_pads (clearance 0))
    (min_thickness 0.254) (filled_areas_thickness no)
    (keepout (tracks allowed) (vias allowed) (pads allowed) (copperpour not_allowed) (footprints allowed))
    (fill (thermal_gap 0.508) (thermal_bridge_width 0.508))
    (polygon
      (pts
        (xy 256.44 82.64)
        (xy 255.74 82.64)
        (xy 255.74 81.87)
        (xy 256.085 81.87)
        (xy 256.44 81.87)
      )
    )
  )
  (zone (net 0) (net_name "") (layers "F.Cu" "In1.Cu" "In2.Cu" "In3.Cu" "In4.Cu" "In5.Cu" "In6.Cu" "In7.Cu" "In8.Cu" "In9.Cu" "In10.Cu" "B.Cu") (hatch edge 0.508)
    (connect_pads (clearance 0))
    (min_thickness 0.254) (filled_areas_thickness no)
    (keepout (tracks allowed) (vias allowed) (pads allowed) (copperpour not_allowed) (footprints allowed))
    (fill (thermal_gap 0.508) (thermal_bridge_width 0.508))
    (polygon
      (pts
        (xy 256.44 102.96)
        (xy 255.72 102.96)
        (xy 255.72 102.19)
        (xy 256.085 102.19)
        (xy 256.44 102.19)
      )
    )
  )
  (zone (net 0) (net_name "") (layers "F.Cu" "In1.Cu" "In2.Cu" "In3.Cu" "In4.Cu" "In5.Cu" "In6.Cu" "In7.Cu" "In8.Cu" "In9.Cu" "In10.Cu" "B.Cu") (hatch edge 0.508)
    (connect_pads (clearance 0))
    (min_thickness 0.254) (filled_areas_thickness no)
    (keepout (tracks allowed) (vias allowed) (pads allowed) (copperpour not_allowed) (footprints allowed))
    (fill (thermal_gap 0.508) (thermal_bridge_width 0.508))
    (polygon
      (pts
        (xy 246.29 110.5)
        (xy 245.55 110.5)
        (xy 245.55 109.83)
        (xy 246.29 109.83)
      )
    )
  )
  (zone (net 0) (net_name "") (layers "F.Cu" "In1.Cu" "In2.Cu" "In3.Cu" "In4.Cu" "In5.Cu" "In6.Cu" "In7.Cu" "In8.Cu" "In9.Cu" "In10.Cu" "B.Cu") (hatch edge 0.508)
    (connect_pads (clearance 0))
    (min_thickness 0.254) (filled_areas_thickness no)
    (keepout (tracks allowed) (vias allowed) (pads allowed) (copperpour not_allowed) (footprints allowed))
    (fill (thermal_gap 0.508) (thermal_bridge_width 0.508))
    (polygon
      (pts
        (xy 247.58 116.82)
        (xy 246.79 116.82)
        (xy 246.79 116.15)
        (xy 247.58 116.15)
      )
    )
  )
  (zone (net 0) (net_name "") (layers "F.Cu" "In1.Cu" "In2.Cu" "In3.Cu" "In4.Cu" "In5.Cu" "In6.Cu" "In7.Cu" "In8.Cu" "In9.Cu" "In10.Cu" "B.Cu") (hatch edge 0.508)
    (connect_pads (clearance 0))
    (min_thickness 0.254) (filled_areas_thickness no)
    (keepout (tracks allowed) (vias allowed) (pads allowed) (copperpour not_allowed) (footprints allowed))
    (fill (thermal_gap 0.508) (thermal_bridge_width 0.508))
    (polygon
      (pts
        (xy 253.9 123.2)
        (xy 253.165 123.2)
        (xy 253.165 122.53)
        (xy 253.9 122.53)
      )
    )
  )
  (zone (net 0) (net_name "") (layers "F.Cu" "In1.Cu" "In2.Cu" "In3.Cu" "In4.Cu" "In5.Cu" "In6.Cu" "In7.Cu" "In8.Cu" "In9.Cu" "In10.Cu" "B.Cu") (hatch edge 0.508)
    (connect_pads (clearance 0))
    (min_thickness 0.254) (filled_areas_thickness no)
    (keepout (tracks allowed) (vias allowed) (pads allowed) (copperpour not_allowed) (footprints allowed))
    (fill (thermal_gap 0.508) (thermal_bridge_width 0.508))
    (polygon
      (pts
        (xy 257.405 99.63)
        (xy 258.105 99.63)
        (xy 258.105 100.4)
        (xy 257.78 100.4)
        (xy 257.405 100.4)
      )
    )
  )
  (zone (net 0) (net_name "") (layers "F.Cu" "In1.Cu" "In2.Cu" "In3.Cu" "In4.Cu" "In5.Cu" "In6.Cu" "In7.Cu" "In8.Cu" "In9.Cu" "In10.Cu" "B.Cu") (hatch edge 0.508)
    (connect_pads (clearance 0))
    (min_thickness 0.254) (filled_areas_thickness no)
    (keepout (tracks allowed) (vias allowed) (pads allowed) (copperpour not_allowed) (footprints allowed))
    (fill (thermal_gap 0.508) (thermal_bridge_width 0.508))
    (polygon
      (pts
        (xy 255.2 80.09)
        (xy 254.41 80.09)
        (xy 254.41 79.32)
        (xy 254.805 79.32)
        (xy 255.2 79.32)
      )
    )
  )
  (zone (net 0) (net_name "") (layers "F.Cu" "In1.Cu" "In2.Cu" "In3.Cu" "In4.Cu" "In5.Cu" "In6.Cu" "In7.Cu" "In8.Cu" "In9.Cu" "In10.Cu" "B.Cu") (hatch edge 0.508)
    (connect_pads (clearance 0))
    (min_thickness 0.254) (filled_areas_thickness no)
    (keepout (tracks allowed) (vias allowed) (pads allowed) (copperpour not_allowed) (footprints allowed))
    (fill (thermal_gap 0.508) (thermal_bridge_width 0.508))
    (polygon
      (pts
        (xy 256.44 108.01)
        (xy 255.72 108.01)
        (xy 255.72 107.24)
        (xy 256.115 107.24)
        (xy 256.44 107.24)
      )
    )
  )
  (zone (net 0) (net_name "") (layers "F.Cu" "In1.Cu" "In2.Cu" "In3.Cu" "In4.Cu" "In5.Cu" "In6.Cu" "In7.Cu" "In8.Cu" "In9.Cu" "In10.Cu" "B.Cu") (hatch edge 0.508)
    (connect_pads (clearance 0))
    (min_thickness 0.254) (filled_areas_thickness no)
    (keepout (tracks allowed) (vias allowed) (pads allowed) (copperpour not_allowed) (footprints allowed))
    (fill (thermal_gap 0.508) (thermal_bridge_width 0.508))
    (polygon
      (pts
        (xy 247.56 105.43)
        (xy 246.82 105.43)
        (xy 246.82 104.76)
        (xy 247.56 104.76)
      )
    )
  )
  (zone (net 0) (net_name "") (layers "F.Cu" "In1.Cu" "In2.Cu" "In3.Cu" "In4.Cu" "In5.Cu" "In6.Cu" "In7.Cu" "In8.Cu" "In9.Cu" "In10.Cu" "B.Cu") (hatch edge 0.508)
    (connect_pads (clearance 0))
    (min_thickness 0.254) (filled_areas_thickness no)
    (keepout (tracks allowed) (vias allowed) (pads allowed) (copperpour not_allowed) (footprints allowed))
    (fill (thermal_gap 0.508) (thermal_bridge_width 0.508))
    (polygon
      (pts
        (xy 247.55 120.67)
        (xy 246.81 120.67)
        (xy 246.81 120)
        (xy 247.55 120)
      )
    )
  )
  (zone (net 0) (net_name "") (layers "F.Cu" "In1.Cu" "In2.Cu" "In3.Cu" "In4.Cu" "In5.Cu" "In6.Cu" "In7.Cu" "In8.Cu" "In9.Cu" "In10.Cu" "B.Cu") (hatch edge 0.508)
    (connect_pads (clearance 0))
    (min_thickness 0.254) (filled_areas_thickness no)
    (keepout (tracks allowed) (vias allowed) (pads allowed) (copperpour not_allowed) (footprints allowed))
    (fill (thermal_gap 0.508) (thermal_bridge_width 0.508))
    (polygon
      (pts
        (xy 256.455 118.1)
        (xy 255.715 118.1)
        (xy 255.715 117.43)
        (xy 256.455 117.43)
      )
    )
  )
  (zone (net 0) (net_name "") (layers "F.Cu" "In1.Cu" "In2.Cu" "In3.Cu" "In4.Cu" "In5.Cu" "In6.Cu" "In7.Cu" "In8.Cu" "In9.Cu" "In10.Cu" "B.Cu") (hatch edge 0.508)
    (connect_pads (clearance 0))
    (min_thickness 0.254) (filled_areas_thickness no)
    (keepout (tracks allowed) (vias allowed) (pads allowed) (copperpour not_allowed) (footprints allowed))
    (fill (thermal_gap 0.508) (thermal_bridge_width 0.508))
    (polygon
      (pts
        (xy 256.43 92.76)
        (xy 255.71 92.76)
        (xy 255.71 91.99)
        (xy 256.085 91.99)
        (xy 256.43 91.99)
      )
    )
  )
  (zone (net 0) (net_name "") (layers "F.Cu" "In1.Cu" "In2.Cu" "In3.Cu" "In4.Cu" "In5.Cu" "In6.Cu" "In7.Cu" "In8.Cu" "In9.Cu" "In10.Cu" "B.Cu") (hatch edge 0.508)
    (connect_pads (clearance 0))
    (min_thickness 0.254) (filled_areas_thickness no)
    (keepout (tracks allowed) (vias allowed) (pads allowed) (copperpour not_allowed) (footprints allowed))
    (fill (thermal_gap 0.508) (thermal_bridge_width 0.508))
    (polygon
      (pts
        (xy 248.83 114.31)
        (xy 248.09 114.31)
        (xy 248.09 113.64)
        (xy 248.83 113.64)
      )
    )
  )
  (zone (net 0) (net_name "") (layers "F.Cu" "In1.Cu" "In2.Cu" "In3.Cu" "In4.Cu" "In5.Cu" "In6.Cu" "In7.Cu" "In8.Cu" "In9.Cu" "In10.Cu" "B.Cu") (hatch edge 0.508)
    (connect_pads (clearance 0))
    (min_thickness 0.254) (filled_areas_thickness no)
    (keepout (tracks allowed) (vias allowed) (pads allowed) (copperpour not_allowed) (footprints allowed))
    (fill (thermal_gap 0.508) (thermal_bridge_width 0.508))
    (polygon
      (pts
        (xy 246.83 122.519999)
        (xy 247.565001 122.52)
        (xy 247.565 123.189999)
        (xy 246.830001 123.19)
      )
    )
  )
  (zone (net 0) (net_name "") (layers "F.Cu" "In1.Cu" "In2.Cu" "In3.Cu" "In4.Cu" "In5.Cu" "In6.Cu" "In7.Cu" "In8.Cu" "In9.Cu" "In10.Cu" "B.Cu") (hatch edge 0.508)
    (connect_pads (clearance 0))
    (min_thickness 0.254) (filled_areas_thickness no)
    (keepout (tracks allowed) (vias allowed) (pads allowed) (copperpour not_allowed) (footprints allowed))
    (fill (thermal_gap 0.508) (thermal_bridge_width 0.508))
    (polygon
      (pts
        (xy 256.43 97.88)
        (xy 255.73 97.88)
        (xy 255.73 97.11)
        (xy 256.085 97.11)
        (xy 256.43 97.11)
      )
    )
  )
  (zone (net 0) (net_name "") (layers "F.Cu" "In1.Cu" "In2.Cu" "In3.Cu" "In4.Cu" "In5.Cu" "In6.Cu" "In7.Cu" "In8.Cu" "In9.Cu" "In10.Cu" "B.Cu") (hatch edge 0.508)
    (connect_pads (clearance 0))
    (min_thickness 0.254) (filled_areas_thickness no)
    (keepout (tracks allowed) (vias allowed) (pads allowed) (copperpour not_allowed) (footprints allowed))
    (fill (thermal_gap 0.508) (thermal_bridge_width 0.508))
    (polygon
      (pts
        (xy 247.56 101.59)
        (xy 246.82 101.59)
        (xy 246.82 100.92)
        (xy 247.56 100.92)
      )
    )
  )
  (zone (net 0) (net_name "") (layers "F.Cu" "In1.Cu" "In2.Cu" "In3.Cu" "In4.Cu" "In5.Cu" "In6.Cu" "In7.Cu" "In8.Cu" "In9.Cu" "In10.Cu" "B.Cu") (hatch edge 0.508)
    (connect_pads (clearance 0))
    (min_thickness 0.254) (filled_areas_thickness no)
    (keepout (tracks allowed) (vias allowed) (pads allowed) (copperpour not_allowed) (footprints allowed))
    (fill (thermal_gap 0.508) (thermal_bridge_width 0.508))
    (polygon
      (pts
        (xy 247.56 93.98)
        (xy 246.82 93.98)
        (xy 246.82 93.31)
        (xy 247.56 93.31)
      )
    )
  )
  (zone (net 0) (net_name "") (layers "F.Cu" "In1.Cu" "In2.Cu" "In3.Cu" "In4.Cu" "In5.Cu" "In6.Cu" "In7.Cu" "In8.Cu" "In9.Cu" "In10.Cu" "B.Cu") (hatch edge 0.508)
    (connect_pads (clearance 0))
    (min_thickness 0.254) (filled_areas_thickness no)
    (keepout (tracks allowed) (vias allowed) (pads allowed) (copperpour not_allowed) (footprints allowed))
    (fill (thermal_gap 0.508) (thermal_bridge_width 0.508))
    (polygon
      (pts
        (xy 252.66 120.65)
        (xy 251.87 120.65)
        (xy 251.87 119.98)
        (xy 252.66 119.98)
      )
    )
  )
  (zone (net 0) (net_name "") (layers "F.Cu" "In1.Cu" "In2.Cu" "In3.Cu" "In4.Cu" "In5.Cu" "In6.Cu" "In7.Cu" "In8.Cu" "In9.Cu" "In10.Cu" "B.Cu") (hatch edge 0.508)
    (connect_pads (clearance 0))
    (min_thickness 0.254) (filled_areas_thickness no)
    (keepout (tracks allowed) (vias allowed) (pads allowed) (copperpour not_allowed) (footprints allowed))
    (fill (thermal_gap 0.508) (thermal_bridge_width 0.508))
    (polygon
      (pts
        (xy 248.82 99.12)
        (xy 248.08 99.12)
        (xy 248.08 98.45)
        (xy 248.82 98.45)
      )
    )
  )
  (zone (net 0) (net_name "") (layers "F.Cu" "In1.Cu" "In2.Cu" "In3.Cu" "In4.Cu" "In5.Cu" "In6.Cu" "In7.Cu" "In8.Cu" "In9.Cu" "In10.Cu" "B.Cu") (hatch edge 0.508)
    (connect_pads (clearance 0))
    (min_thickness 0.254) (filled_areas_thickness no)
    (keepout (tracks allowed) (vias allowed) (pads allowed) (copperpour not_allowed) (footprints allowed))
    (fill (thermal_gap 0.508) (thermal_bridge_width 0.508))
    (polygon
      (pts
        (xy 246.29 102.88)
        (xy 245.55 102.88)
        (xy 245.55 102.21)
        (xy 246.29 102.21)
      )
    )
  )
  (zone (net 0) (net_name "") (layers "F.Cu" "In1.Cu" "In2.Cu" "In3.Cu" "In4.Cu" "In5.Cu" "In6.Cu" "In7.Cu" "In8.Cu" "In9.Cu" "In10.Cu" "B.Cu") (hatch edge 0.508)
    (connect_pads (clearance 0))
    (min_thickness 0.254) (filled_areas_thickness no)
    (keepout (tracks allowed) (vias allowed) (pads allowed) (copperpour not_allowed) (footprints allowed))
    (fill (thermal_gap 0.508) (thermal_bridge_width 0.508))
    (polygon
      (pts
        (xy 245.02 97.77)
        (xy 244.28 97.77)
        (xy 244.28 97.1)
        (xy 245.02 97.1)
      )
    )
  )
  (zone (net 0) (net_name "") (layers "F.Cu" "In1.Cu" "In2.Cu" "In3.Cu" "In4.Cu" "In5.Cu" "In6.Cu" "In7.Cu" "In8.Cu" "In9.Cu" "In10.Cu" "B.Cu") (hatch edge 0.508)
    (connect_pads (clearance 0))
    (min_thickness 0.254) (filled_areas_thickness no)
    (keepout (tracks allowed) (vias allowed) (pads allowed) (copperpour not_allowed) (footprints allowed))
    (fill (thermal_gap 0.508) (thermal_bridge_width 0.508))
    (polygon
      (pts
        (xy 129.34 61.31)
        (xy 128.48 61.31)
        (xy 128.48 60.6)
        (xy 129.34 60.6)
      )
    )
  )
  (zone (net 0) (net_name "") (layers "F.Cu" "In1.Cu" "In2.Cu" "In3.Cu" "In4.Cu" "In5.Cu" "In6.Cu" "In7.Cu" "In8.Cu" "In9.Cu" "In10.Cu" "B.Cu") (hatch edge 0.508)
    (connect_pads (clearance 0))
    (min_thickness 0.254) (filled_areas_thickness no)
    (keepout (tracks allowed) (vias allowed) (pads allowed) (copperpour not_allowed) (footprints allowed))
    (fill (thermal_gap 0.508) (thermal_bridge_width 0.508))
    (polygon
      (pts
        (xy 246.29 91.5)
        (xy 245.55 91.5)
        (xy 245.55 90.83)
        (xy 246.29 90.83)
      )
    )
  )
  (zone (net 0) (net_name "") (layers "F.Cu" "In1.Cu" "In2.Cu" "In3.Cu" "In4.Cu" "In5.Cu" "In6.Cu" "In7.Cu" "In8.Cu" "In9.Cu" "In10.Cu" "B.Cu") (hatch edge 0.508)
    (connect_pads (clearance 0))
    (min_thickness 0.254) (filled_areas_thickness no)
    (keepout (tracks allowed) (vias allowed) (pads allowed) (copperpour not_allowed) (footprints allowed))
    (fill (thermal_gap 0.508) (thermal_bridge_width 0.508))
    (polygon
      (pts
        (xy 240.126237 115.576238)
        (xy 240.595962 115.106515)
        (xy 241.069722 115.580277)
        (xy 240.6 116.05)
      )
    )
  )
  (zone (net 0) (net_name "") (layers "F.Cu" "In1.Cu" "In2.Cu" "In3.Cu" "In4.Cu" "In5.Cu" "In6.Cu" "In7.Cu" "In8.Cu" "In9.Cu" "In10.Cu" "B.Cu") (hatch edge 0.508)
    (connect_pads (clearance 0))
    (min_thickness 0.254) (filled_areas_thickness no)
    (keepout (tracks allowed) (vias allowed) (pads allowed) (copperpour not_allowed) (footprints allowed))
    (fill (thermal_gap 0.508) (thermal_bridge_width 0.508))
    (polygon
      (pts
        (xy 245.02 105.44)
        (xy 244.28 105.44)
        (xy 244.28 104.77)
        (xy 245.02 104.77)
      )
    )
  )
  (zone (net 0) (net_name "") (layers "F.Cu" "In1.Cu" "In2.Cu" "In3.Cu" "In4.Cu" "In5.Cu" "In6.Cu" "In7.Cu" "In8.Cu" "In9.Cu" "In10.Cu" "B.Cu") (hatch edge 0.508)
    (connect_pads (clearance 0))
    (min_thickness 0.254) (filled_areas_thickness no)
    (keepout (tracks allowed) (vias allowed) (pads allowed) (copperpour not_allowed) (footprints allowed))
    (fill (thermal_gap 0.508) (thermal_bridge_width 0.508))
    (polygon
      (pts
        (xy 255.17 85.15)
        (xy 254.44 85.15)
        (xy 254.44 84.38)
        (xy 254.805 84.38)
        (xy 255.17 84.38)
      )
    )
  )
  (zone (net 0) (net_name "") (layers "F.Cu" "In1.Cu" "In2.Cu" "In3.Cu" "In4.Cu" "In5.Cu" "In6.Cu" "In7.Cu" "In8.Cu" "In9.Cu" "In10.Cu" "B.Cu") (hatch edge 0.508)
    (connect_pads no (clearance 0))
    (min_thickness 0.15) (filled_areas_thickness no)
    (keepout (tracks allowed) (vias allowed) (pads allowed) (copperpour not_allowed) (footprints allowed))
    (fill (thermal_gap 0.3) (thermal_bridge_width 0.2))
    (polygon
      (pts
        (xy 192.638 82.857)
        (xy 192.756 82.875)
        (xy 192.861 82.932)
        (xy 192.939 83.011)
        (xy 192.991 83.114)
        (xy 193.01 83.231)
        (xy 192.992 83.347)
        (xy 192.94 83.451)
        (xy 192.87 83.522)
        (xy 192.778143 83.551645)
        (xy 192.660143 83.572645)
        (xy 191.657143 83.572645)
        (xy 191.544143 83.552645)
        (xy 191.440143 83.501645)
        (xy 191.355143 83.415645)
        (xy 191.302143 83.314645)
        (xy 191.287143 83.218645)
        (xy 191.287143 83.178645)
        (xy 191.301143 83.082645)
        (xy 191.350143 82.979645)
        (xy 191.436143 82.896645)
        (xy 191.542143 82.838645)
        (xy 191.659143 82.821645)
      )
    )
  )
  (zone (net 0) (net_name "") (layers "F.Cu" "In1.Cu" "In2.Cu" "In3.Cu" "In4.Cu" "In5.Cu" "In6.Cu" "In7.Cu" "In8.Cu" "In9.Cu" "In10.Cu" "B.Cu") (hatch edge 0.508)
    (connect_pads (clearance 0))
    (min_thickness 0.254) (filled_areas_thickness no)
    (keepout (tracks allowed) (vias allowed) (pads allowed) (copperpour not_allowed) (footprints allowed))
    (fill (thermal_gap 0.508) (thermal_bridge_width 0.508))
    (polygon
      (pts
        (xy 247.56 90.21)
        (xy 246.82 90.21)
        (xy 246.82 89.54)
        (xy 247.56 89.54)
      )
    )
  )
  (zone (net 0) (net_name "") (layers "F.Cu" "In1.Cu" "In2.Cu" "In3.Cu" "In4.Cu" "In5.Cu" "In6.Cu" "In7.Cu" "In8.Cu" "In9.Cu" "In10.Cu" "B.Cu") (hatch edge 0.508)
    (connect_pads (clearance 0))
    (min_thickness 0.254) (filled_areas_thickness no)
    (keepout (tracks allowed) (vias allowed) (pads allowed) (copperpour not_allowed) (footprints allowed))
    (fill (thermal_gap 0.508) (thermal_bridge_width 0.508))
    (polygon
      (pts
        (xy 248.83 91.47)
        (xy 248.09 91.47)
        (xy 248.09 90.8)
        (xy 248.83 90.8)
      )
    )
  )
  (zone (net 0) (net_name "") (layers "F.Cu" "In1.Cu" "In2.Cu" "In3.Cu" "In4.Cu" "In5.Cu" "In6.Cu" "In7.Cu" "In8.Cu" "In9.Cu" "In10.Cu" "B.Cu") (hatch edge 0.508)
    (connect_pads (clearance 0))
    (min_thickness 0.254) (filled_areas_thickness no)
    (keepout (tracks allowed) (vias allowed) (pads allowed) (copperpour not_allowed) (footprints allowed))
    (fill (thermal_gap 0.508) (thermal_bridge_width 0.508))
    (polygon
      (pts
        (xy 245.02 101.63)
        (xy 244.28 101.63)
        (xy 244.28 100.96)
        (xy 245.02 100.96)
      )
    )
  )
  (zone (net 0) (net_name "") (layers "F.Cu" "In1.Cu" "In2.Cu" "In3.Cu" "In4.Cu" "In5.Cu" "In6.Cu" "In7.Cu" "In8.Cu" "In9.Cu" "In10.Cu" "B.Cu") (hatch edge 0.508)
    (connect_pads (clearance 0))
    (min_thickness 0.254) (filled_areas_thickness no)
    (keepout (tracks allowed) (vias allowed) (pads allowed) (copperpour not_allowed) (footprints allowed))
    (fill (thermal_gap 0.508) (thermal_bridge_width 0.508))
    (polygon
      (pts
        (xy 241.45 56.985)
        (xy 240.72 56.985)
        (xy 240.72 56.275)
        (xy 241.45 56.275)
      )
    )
  )
  (zone (net 0) (net_name "") (layers "F.Cu" "In1.Cu" "In2.Cu" "In3.Cu" "In4.Cu" "In5.Cu" "In6.Cu" "In7.Cu" "In8.Cu" "In9.Cu" "In10.Cu" "B.Cu") (hatch edge 0.508)
    (connect_pads (clearance 0))
    (min_thickness 0.254) (filled_areas_thickness no)
    (keepout (tracks allowed) (vias allowed) (pads allowed) (copperpour not_allowed) (footprints allowed))
    (fill (thermal_gap 0.508) (thermal_bridge_width 0.508))
    (polygon
      (pts
        (xy 248.83 95.27)
        (xy 248.09 95.27)
        (xy 248.09 94.6)
        (xy 248.83 94.6)
      )
    )
  )
  (zone (net 0) (net_name "") (layers "F.Cu" "In1.Cu" "In2.Cu" "In3.Cu" "In4.Cu" "In5.Cu" "In6.Cu" "In7.Cu" "In8.Cu" "In9.Cu" "In10.Cu" "B.Cu") (hatch edge 0.508)
    (connect_pads (clearance 0))
    (min_thickness 0.254) (filled_areas_thickness no)
    (keepout (tracks allowed) (vias allowed) (pads allowed) (copperpour not_allowed) (footprints allowed))
    (fill (thermal_gap 0.508) (thermal_bridge_width 0.508))
    (polygon
      (pts
        (xy 245.05 116.85)
        (xy 244.26 116.85)
        (xy 244.26 116.18)
        (xy 245.05 116.18)
      )
    )
  )
  (zone (net 0) (net_name "") (layers "F.Cu" "In1.Cu" "In2.Cu" "In3.Cu" "In4.Cu" "In5.Cu" "In6.Cu" "In7.Cu" "In8.Cu" "In9.Cu" "In10.Cu" "B.Cu") (hatch edge 0.508)
    (connect_pads (clearance 0))
    (min_thickness 0.254) (filled_areas_thickness no)
    (keepout (tracks allowed) (vias allowed) (pads allowed) (copperpour not_allowed) (footprints allowed))
    (fill (thermal_gap 0.508) (thermal_bridge_width 0.508))
    (polygon
      (pts
        (xy 242.199999 122.124999)
        (xy 242.935 122.125)
        (xy 242.934999 122.794999)
        (xy 242.2 122.795)
      )
    )
  )
  (zone (net 0) (net_name "") (layers "F.Cu" "In1.Cu" "In2.Cu" "In3.Cu" "In4.Cu" "In5.Cu" "In6.Cu" "In7.Cu" "In8.Cu" "In9.Cu" "In10.Cu" "B.Cu") (hatch edge 0.508)
    (connect_pads (clearance 0))
    (min_thickness 0.254) (filled_areas_thickness no)
    (keepout (tracks allowed) (vias allowed) (pads allowed) (copperpour not_allowed) (footprints allowed))
    (fill (thermal_gap 0.508) (thermal_bridge_width 0.508))
    (polygon
      (pts
        (xy 248.82 87.67)
        (xy 248.08 87.67)
        (xy 248.08 87)
        (xy 248.82 87)
      )
    )
  )
  (zone (net 0) (net_name "") (layers "F.Cu" "In1.Cu" "In2.Cu" "In3.Cu" "In4.Cu" "In5.Cu" "In6.Cu" "In7.Cu" "In8.Cu" "In9.Cu" "In10.Cu" "B.Cu") (hatch edge 0.508)
    (connect_pads (clearance 0))
    (min_thickness 0.254) (filled_areas_thickness no)
    (keepout (tracks allowed) (vias allowed) (pads allowed) (copperpour not_allowed) (footprints allowed))
    (fill (thermal_gap 0.508) (thermal_bridge_width 0.508))
    (polygon
      (pts
        (xy 246.29 95.25)
        (xy 245.55 95.25)
        (xy 245.55 94.58)
        (xy 246.29 94.58)
      )
    )
  )
  (zone (net 0) (net_name "") (layers "F.Cu" "In1.Cu" "In2.Cu" "In3.Cu" "In4.Cu" "In5.Cu" "In6.Cu" "In7.Cu" "In8.Cu" "In9.Cu" "In10.Cu" "B.Cu") (hatch edge 0.508)
    (connect_pads (clearance 0))
    (min_thickness 0.254) (filled_areas_thickness no)
    (keepout (tracks allowed) (vias allowed) (pads allowed) (copperpour not_allowed) (footprints allowed))
    (fill (thermal_gap 0.508) (thermal_bridge_width 0.508))
    (polygon
      (pts
        (xy 256.45 113.05)
        (xy 255.71 113.05)
        (xy 255.71 112.38)
        (xy 256.45 112.38)
      )
    )
  )
  (zone (net 0) (net_name "") (layers "F.Cu" "In1.Cu" "In2.Cu" "In3.Cu" "In4.Cu" "In5.Cu" "In6.Cu" "In7.Cu" "In8.Cu" "In9.Cu" "In10.Cu" "B.Cu") (hatch edge 0.508)
    (connect_pads (clearance 0))
    (min_thickness 0.254) (filled_areas_thickness no)
    (keepout (tracks allowed) (vias allowed) (pads allowed) (copperpour not_allowed) (footprints allowed))
    (fill (thermal_gap 0.508) (thermal_bridge_width 0.508))
    (polygon
      (pts
        (xy 247.57 97.83)
        (xy 246.83 97.83)
        (xy 246.83 97.16)
        (xy 247.57 97.16)
      )
    )
  )
  (zone (net 0) (net_name "") (layers "F.Cu" "In1.Cu" "In2.Cu" "In3.Cu" "In4.Cu" "In5.Cu" "In6.Cu" "In7.Cu" "In8.Cu" "In9.Cu" "In10.Cu" "B.Cu") (hatch edge 0.508)
    (connect_pads (clearance 0))
    (min_thickness 0.254) (filled_areas_thickness no)
    (keepout (tracks allowed) (vias allowed) (pads allowed) (copperpour not_allowed) (footprints allowed))
    (fill (thermal_gap 0.508) (thermal_bridge_width 0.508))
    (polygon
      (pts
        (xy 256.44 87.69)
        (xy 255.71 87.69)
        (xy 255.71 86.92)
        (xy 256.085 86.92)
        (xy 256.44 86.92)
      )
    )
  )
  (zone (net 0) (net_name "") (layers "F.Cu" "In1.Cu" "In2.Cu" "In3.Cu" "In4.Cu" "In5.Cu" "In6.Cu" "In7.Cu" "In8.Cu" "In9.Cu" "In10.Cu" "B.Cu") (hatch edge 0.508)
    (connect_pads (clearance 0))
    (min_thickness 0.254) (filled_areas_thickness no)
    (keepout (tracks allowed) (vias allowed) (pads allowed) (copperpour not_allowed) (footprints allowed))
    (fill (thermal_gap 0.508) (thermal_bridge_width 0.508))
    (polygon
      (pts
        (xy 255.17 80.09)
        (xy 254.45 80.09)
        (xy 254.45 79.32)
        (xy 254.775 79.32)
        (xy 255.17 79.32)
      )
    )
  )
  (zone (net 0) (net_name "") (layers "F.Cu" "In1.Cu" "In2.Cu" "In3.Cu" "In4.Cu" "In5.Cu" "In6.Cu" "In7.Cu" "In8.Cu" "In9.Cu" "In10.Cu" "B.Cu") (hatch edge 0.508)
    (connect_pads (clearance 0))
    (min_thickness 0.254) (filled_areas_thickness no)
    (keepout (tracks allowed) (vias allowed) (pads allowed) (copperpour not_allowed) (footprints allowed))
    (fill (thermal_gap 0.508) (thermal_bridge_width 0.508))
    (polygon
      (pts
        (xy 253.895 100.37)
        (xy 253.215 100.37)
        (xy 253.215 99.6)
        (xy 253.54 99.6)
        (xy 253.895 99.6)
      )
    )
  )
  (zone (net 0) (net_name "") (layers "F.Cu" "In1.Cu" "In2.Cu" "In3.Cu" "In4.Cu" "In5.Cu" "In7.Cu" "In9.Cu" "In10.Cu" "B.Cu") (hatch edge 0.508)
    (connect_pads no (clearance 0))
    (min_thickness 0.15) (filled_areas_thickness no)
    (keepout (tracks allowed) (vias allowed) (pads allowed) (copperpour not_allowed) (footprints allowed))
    (fill (thermal_gap 0.3) (thermal_bridge_width 0.2))
    (polygon
      (pts
        (xy 180.635 84.687)
        (xy 180.753 84.704)
        (xy 180.858 84.756)
        (xy 180.937 84.838)
        (xy 180.989 84.941)
        (xy 181.013 85.059)
        (xy 180.992 85.18)
        (xy 180.938 85.279)
        (xy 180.869 85.353)
        (xy 180.755 85.415)
        (xy 180.637 85.436)
        (xy 179.634 85.436)
        (xy 179.521 85.416)
        (xy 179.417 85.365)
        (xy 179.332 85.279)
        (xy 179.279 85.178)
        (xy 179.264 85.082)
        (xy 179.264 85.042)
        (xy 179.278 84.946)
        (xy 179.327 84.843)
        (xy 179.413 84.76)
        (xy 179.519 84.702)
        (xy 179.636 84.685)
      )
    )
  )
  (zone (net 0) (net_name "") (layers "F.Cu" "In1.Cu" "In2.Cu" "In3.Cu" "In4.Cu" "In5.Cu" "In7.Cu" "In9.Cu" "In10.Cu" "B.Cu") (hatch edge 0.508)
    (connect_pads no (clearance 0))
    (min_thickness 0.15) (filled_areas_thickness no)
    (keepout (tracks allowed) (vias allowed) (pads allowed) (copperpour not_allowed) (footprints allowed))
    (fill (thermal_gap 0.3) (thermal_bridge_width 0.2))
    (polygon
      (pts
        (xy 181.634 83.688)
        (xy 181.752 83.705)
        (xy 181.857 83.757)
        (xy 181.936 83.839)
        (xy 181.988 83.942)
        (xy 182.012 84.06)
        (xy 181.991 84.181)
        (xy 181.937 84.28)
        (xy 181.868 84.354)
        (xy 181.754 84.416)
        (xy 181.636 84.437)
        (xy 180.633 84.437)
        (xy 180.52 84.417)
        (xy 180.416 84.366)
        (xy 180.331 84.28)
        (xy 180.278 84.179)
        (xy 180.263 84.083)
        (xy 180.263 84.043)
        (xy 180.277 83.947)
        (xy 180.326 83.844)
        (xy 180.412 83.761)
        (xy 180.518 83.703)
        (xy 180.635 83.686)
      )
    )
  )
  (zone (net 0) (net_name "") (layers "F.Cu" "In2.Cu" "In4.Cu" "In5.Cu" "In6.Cu" "In7.Cu" "In8.Cu" "In9.Cu" "In10.Cu" "B.Cu") (hatch edge 0.508)
    (connect_pads (clearance 0))
    (min_thickness 0.254) (filled_areas_thickness no)
    (keepout (tracks allowed) (vias allowed) (pads allowed) (copperpour not_allowed) (footprints allowed))
    (fill (thermal_gap 0.508) (thermal_bridge_width 0.508))
    (polygon
      (pts
        (xy 192.75 99.7)
        (xy 192.86 99.76)
        (xy 192.94 99.84)
        (xy 192.99 99.94)
        (xy 193.01 100.06)
        (xy 192.99 100.18)
        (xy 192.94 100.28)
        (xy 192.86 100.36)
        (xy 192.75 100.42)
        (xy 192.68 100.43)
        (xy 191.64 100.43)
        (xy 191.525 100.42)
        (xy 191.41 100.36)
        (xy 191.33 100.28)
        (xy 191.28 100.18)
        (xy 191.26 100.06)
        (xy 191.28 99.94)
        (xy 191.33 99.84)
        (xy 191.41 99.76)
        (xy 191.52 99.7)
        (xy 191.64 99.69)
        (xy 192.64 99.69)
      )
    )
  )
  (zone (net 0) (net_name "") (layers "F.Cu" "In2.Cu" "In4.Cu" "In5.Cu" "In6.Cu" "In7.Cu" "In8.Cu" "In10.Cu" "B.Cu") (hatch edge 0.508)
    (connect_pads (clearance 0))
    (min_thickness 0.254) (filled_areas_thickness no)
    (keepout (tracks allowed) (vias allowed) (pads allowed) (copperpour not_allowed) (footprints allowed))
    (fill (thermal_gap 0.508) (thermal_bridge_width 0.508))
    (polygon
      (pts
        (xy 192.75 97.705)
        (xy 192.86 97.765)
        (xy 192.94 97.845)
        (xy 192.99 97.945)
        (xy 193.01 98.065)
        (xy 192.99 98.185)
        (xy 192.94 98.285)
        (xy 192.86 98.365)
        (xy 192.75 98.425)
        (xy 192.68 98.435)
        (xy 191.64 98.435)
        (xy 191.525 98.425)
        (xy 191.41 98.365)
        (xy 191.33 98.285)
        (xy 191.28 98.185)
        (xy 191.26 98.065)
        (xy 191.28 97.945)
        (xy 191.33 97.845)
        (xy 191.41 97.765)
        (xy 191.52 97.705)
        (xy 191.64 97.695)
        (xy 192.64 97.695)
      )
    )
  )
  (zone (net 9) (net_name "GND") (layer "In1.Cu") (hatch edge 0.508)
    (connect_pads yes (clearance 0.1))
    (min_thickness 0.15) (filled_areas_thickness no)
    (fill yes (thermal_gap 0.508) (thermal_bridge_width 0.15) (smoothing fillet) (radius 0.5))
    (polygon
      (pts
        (xy 259.886328 136.010008)
        (xy 106.986328 136.010008)
        (xy 106.986328 46.010008)
        (xy 259.886328 46.010008)
      )
    )
  )
  (zone (net 0) (net_name "") (layer "In1.Cu") (hatch edge 0.508)
    (connect_pads no (clearance 0))
    (min_thickness 0.15) (filled_areas_thickness no)
    (keepout (tracks allowed) (vias allowed) (pads allowed) (copperpour not_allowed) (footprints allowed))
    (fill (thermal_gap 0.3) (thermal_bridge_width 0.2))
    (polygon
      (pts
        (xy 185.935112 80.961981)
        (xy 185.198693 80.977875)
        (xy 185.138693 80.167875)
        (xy 185.865112 80.081981)
      )
    )
  )
  (zone (net 0) (net_name "") (layers "In1.Cu" "In2.Cu" "In3.Cu" "In4.Cu") (hatch edge 0.508)
    (connect_pads no (clearance 0))
    (min_thickness 0.15) (filled_areas_thickness no)
    (keepout (tracks allowed) (vias allowed) (pads allowed) (copperpour not_allowed) (footprints allowed))
    (fill (thermal_gap 0.3) (thermal_bridge_width 0.2))
    (polygon
      (pts
        (xy 180.012 78.05)
        (xy 179.265 78.05)
        (xy 179.265 77.06)
        (xy 180.012 77.06)
      )
    )
  )
  (zone (net 0) (net_name "") (layers "In1.Cu" "In2.Cu" "In3.Cu" "In4.Cu") (hatch edge 0.508)
    (connect_pads no (clearance 0))
    (min_thickness 0.15) (filled_areas_thickness no)
    (keepout (tracks allowed) (vias allowed) (pads allowed) (copperpour not_allowed) (footprints allowed))
    (fill (thermal_gap 0.3) (thermal_bridge_width 0.2))
    (polygon
      (pts
        (xy 179.73 83.415)
        (xy 178.77 83.415)
        (xy 178.77 82.67)
        (xy 179.73 82.67)
      )
    )
  )
  (zone (net 0) (net_name "") (layers "In1.Cu" "In2.Cu" "In3.Cu" "In4.Cu") (hatch edge 0.508)
    (connect_pads no (clearance 0))
    (min_thickness 0.15) (filled_areas_thickness no)
    (keepout (tracks allowed) (vias allowed) (pads allowed) (copperpour not_allowed) (footprints allowed))
    (fill (thermal_gap 0.3) (thermal_bridge_width 0.2))
    (polygon
      (pts
        (xy 179.66 82.407)
        (xy 178.7 82.407)
        (xy 178.7 81.662)
        (xy 179.66 81.662)
      )
    )
  )
  (zone (net 9) (net_name "GND") (layer "In2.Cu") (hatch edge 0.508)
    (priority 1)
    (connect_pads no (clearance 0.2))
    (min_thickness 0.5) (filled_areas_thickness no)
    (fill yes (thermal_gap 1) (thermal_bridge_width 1) (smoothing fillet) (radius 1))
    (polygon
      (pts
        (xy 148.35 109.8)
        (xy 148.35 110.5)
        (xy 142.65 116.2)
        (xy 132.2 116.2)
        (xy 132.2 106.3)
        (xy 137.15 106.3)
        (xy 138.35 105.1)
        (xy 143.65 105.1)
      )
    )
  )
  (zone (net 147) (net_name "1V0_SYS") (layer "In2.Cu") (hatch edge 0.508)
    (priority 2)
    (connect_pads yes (clearance 0.15))
    (min_thickness 0.15) (filled_areas_thickness no)
    (fill yes (thermal_gap 0.508) (thermal_bridge_width 0.508) (smoothing fillet) (radius 0.5))
    (polygon
      (pts
        (xy 192 90.2)
        (xy 192 95.55)
        (xy 191.5 96)
        (xy 191.5 96.7)
        (xy 191.5 96.8)
        (xy 191.8 97)
        (xy 191.8 97.2)
        (xy 191.5 97.5)
        (xy 191.5 98.7)
        (xy 191.55 98.75)
        (xy 191.55 99.275)
        (xy 191.125 99.7)
        (xy 191.0125 100.1375)
        (xy 190.85 100.3)
        (xy 190.5 100.3)
        (xy 190.5 98.4)
        (xy 189.7 97.6)
        (xy 175.6 97.6)
        (xy 175.3 97.9)
        (xy 170.4 97.9)
        (xy 169.5 98.8)
        (xy 169.5 100.95)
        (xy 167.95 102.45)
        (xy 154 102.5)
        (xy 153.150219 101.638366)
        (xy 148.45 101.65)
        (xy 143.1 96.3)
        (xy 143.1 78)
        (xy 149.8 78)
        (xy 149.8 92.75)
        (xy 154.05 97)
        (xy 164.45 96.95)
        (xy 166.85 94.55)
        (xy 166.85 87.55)
        (xy 168.55 85.85)
        (xy 187.55 85.85)
      )
    )
  )
  (zone (net 9) (net_name "GND") (layer "In2.Cu") (hatch edge 0.508)
    (priority 1)
    (connect_pads (clearance 0.125))
    (min_thickness 0.254) (filled_areas_thickness no)
    (fill yes (thermal_gap 0.508) (thermal_bridge_width 0.508) (smoothing fillet) (radius 0.5))
    (polygon
      (pts
        (xy 231.4 105.4)
        (xy 231.4 107.55)
        (xy 232.975 109.15)
        (xy 232.975 111.275)
        (xy 239.7 118)
        (xy 239.7 119.9)
        (xy 225.6 119.9)
        (xy 223.5 122)
        (xy 209.2 122)
        (xy 200.1 112.9)
        (xy 200.1 110)
        (xy 199.6 109.5)
        (xy 191.7 109.5)
        (xy 191.3 109.1)
        (xy 191.3 105.5)
        (xy 191.7 105.1)
        (xy 194 105.1)
        (xy 194.3 105.4)
        (xy 210.9 105.4)
        (xy 213 103.3)
        (xy 229.3 103.3)
      )
    )
  )
  (zone (net 9) (net_name "GND") (layer "In2.Cu") (hatch edge 0.508)
    (connect_pads (clearance 0.2))
    (min_thickness 0.15) (filled_areas_thickness no)
    (fill yes (thermal_gap 0.508) (thermal_bridge_width 0.15))
    (polygon
      (pts
        (xy 251.43 121.98)
        (xy 251.92 121.98)
        (xy 252.99 123.05)
        (xy 252.99 123.54)
        (xy 253.53 124.079487)
        (xy 257.6 124.079487)
        (xy 257.6 117.929487)
        (xy 257.6 111.75)
        (xy 259.05 110.3)
        (xy 259.049997 95.45)
        (xy 256.65 93.050853)
        (xy 260 93.05)
        (xy 259.9 136)
        (xy 218.7 136)
        (xy 218.7 128)
        (xy 238.3 128)
        (xy 240.1 126.2)
        (xy 240.1 122.45)
        (xy 238.7 121.05)
        (xy 237.3 119.65)
        (xy 237.3 119.15)
        (xy 239.35 119.15)
        (xy 241.7 121.474487)
        (xy 250.925 121.474487)
      )
    )
  )
  (zone (net 9) (net_name "GND") (layer "In2.Cu") (hatch edge 0.508)
    (connect_pads yes (clearance 0.15))
    (min_thickness 0.15) (filled_areas_thickness no)
    (fill yes (thermal_gap 0.3) (thermal_bridge_width 0.2) (smoothing fillet) (radius 0.5))
    (polygon
      (pts
        (xy 169.38 79.95)
        (xy 164 79.95)
        (xy 160.1 83.9)
        (xy 160.1 90)
        (xy 158.9 91.16)
        (xy 150.11 91.16)
        (xy 150.11 77.75)
        (xy 142.7 77.7)
        (xy 142.66861 96.5)
        (xy 133.6 96.5)
        (xy 133.627604 99.727848)
        (xy 127.3 106)
        (xy 127.286905 128.205141)
        (xy 142.6 128.1)
        (xy 142.6 136)
        (xy 107.100682 135.974386)
        (xy 107 46)
        (xy 259.9 46)
        (xy 259.984566 93.607746)
        (xy 255.4 93.6)
        (xy 255.02 93.22)
        (xy 253.99 93.22)
        (xy 253.89 93.12)
        (xy 253.885817 92.084167)
        (xy 252.201735 90.398249)
        (xy 242.85 90.4)
        (xy 241.550014 89.116547)
        (xy 202.85 89.15)
        (xy 201.95 88.25)
        (xy 196.6 88.25)
        (xy 196.600113 86.599393)
        (xy 214.125 86.624393)
        (xy 228.275 72.475)
        (xy 228.249937 53.872426)
        (xy 216.2 53.9)
        (xy 216.2 58.7)
        (xy 197.5 77.4)
        (xy 196.3 77.4)
        (xy 196.3 76)
        (xy 200.4 71.85)
        (xy 200.4 54.85)
        (xy 199.5 53.95)
        (xy 161.825 53.95)
        (xy 161.84 58.56)
        (xy 164.55 58.575)
        (xy 164.54 63.34)
        (xy 157.375 63.35)
        (xy 154.65 60.65)
        (xy 154.65 53.95)
        (xy 141.95 53.95)
        (xy 140.9 55)
        (xy 140.9 69.2)
        (xy 148.1 76.55)
        (xy 169.38 76.55)
      )
    )
  )
  (zone (net 307) (net_name "5V0_SYS") (layer "In2.Cu") (hatch edge 0.508)
    (priority 1)
    (connect_pads (clearance 0.125))
    (min_thickness 0.254) (filled_areas_thickness no)
    (fill yes (thermal_gap 0.508) (thermal_bridge_width 0.508))
    (polygon
      (pts
        (xy 133.9 100.9)
        (xy 131.9 102.9)
        (xy 131.9 118)
        (xy 130.1 119.8)
        (xy 130.1 122.7)
        (xy 131 123.6)
        (xy 139.2 123.6)
        (xy 141.5 121.3)
        (xy 151.5 121.3)
        (xy 153 119.8)
        (xy 153 117.1)
        (xy 155.25 117.1)
        (xy 157.2 117.1)
        (xy 157.2 122)
        (xy 153 126.2)
        (xy 144.6 126.2)
        (xy 144.4 126.4)
        (xy 142.6 128.2)
        (xy 127.2 128.2)
        (xy 124.8 125.8)
        (xy 124.8 109.9)
        (xy 124.8 107.3)
        (xy 121.3 103.8)
        (xy 121.3 101.2)
        (xy 131 101.2)
        (xy 132.3 99.9)
        (xy 132.3 96.5)
        (xy 133.9 96.5)
      )
    )
  )
  (zone (net 606) (net_name "/Ethernet/PAIR_36") (layers "In2.Cu" "B.Cu") (hatch edge 0.508)
    (priority 1)
    (connect_pads (clearance 0.125))
    (min_thickness 0.1) (filled_areas_thickness no)
    (fill yes (thermal_gap 0.2) (thermal_bridge_width 0.12))
    (polygon
      (pts
        (xy 183.3 121)
        (xy 183.3 121.2)
        (xy 183.1 121.4)
        (xy 181.6 121.4)
        (xy 181.29 121.09)
        (xy 181.29 120.8)
        (xy 183.1 120.8)
      )
    )
  )
  (zone (net 605) (net_name "/Ethernet/PAIR_12") (layers "In2.Cu" "B.Cu") (hatch edge 0.508)
    (priority 1)
    (connect_pads (clearance 0.125))
    (min_thickness 0.1) (filled_areas_thickness no)
    (fill yes (thermal_gap 0.2) (thermal_bridge_width 0.12))
    (polygon
      (pts
        (xy 183 118.4)
        (xy 182.8 118.6)
        (xy 181.56 118.6)
        (xy 181.56 118.2)
        (xy 182.16 117.6)
        (xy 183 117.6)
      )
    )
  )
  (zone (net 9) (net_name "GND") (layer "In3.Cu") (hatch edge 0.508)
    (connect_pads yes (clearance 0.1))
    (min_thickness 0.15) (filled_areas_thickness no)
    (fill yes (thermal_gap 0.3) (thermal_bridge_width 0.2) (smoothing fillet) (radius 0.5))
    (polygon
      (pts
        (xy 259.886328 136)
        (xy 106.986328 136)
        (xy 106.986328 46)
        (xy 259.886328 46)
      )
    )
  )
  (zone (net 0) (net_name "") (layer "In3.Cu") (hatch edge 0.508)
    (connect_pads no (clearance 0))
    (min_thickness 0.15) (filled_areas_thickness no)
    (keepout (tracks allowed) (vias allowed) (pads allowed) (copperpour not_allowed) (footprints allowed))
    (fill (thermal_gap 0.3) (thermal_bridge_width 0.2))
    (polygon
      (pts
        (xy 197.07532 80.06)
        (xy 197.054363 79.95464)
        (xy 196.994681 79.865319)
        (xy 196.90536 79.805637)
        (xy 196.8 79.78468)
        (xy 196.69464 79.805637)
        (xy 196.605319 79.865319)
        (xy 196.545637 79.95464)
        (xy 196.52468 80.06)
        (xy 196.545637 80.16536)
        (xy 196.605319 80.254681)
        (xy 196.69464 80.314363)
        (xy 196.8 80.33532)
        (xy 196.90536 80.314363)
        (xy 196.994681 80.254681)
        (xy 197.054363 80.16536)
      )
    )
  )
  (zone (net 0) (net_name "") (layer "In3.Cu") (hatch edge 0.508)
    (connect_pads no (clearance 0))
    (min_thickness 0.15) (filled_areas_thickness no)
    (keepout (tracks allowed) (vias allowed) (pads allowed) (copperpour not_allowed) (footprints allowed))
    (fill (thermal_gap 0.3) (thermal_bridge_width 0.2))
    (polygon
      (pts
        (xy 195.930957 83.05764)
        (xy 195.91 82.95228)
        (xy 195.850318 82.862959)
        (xy 195.760997 82.803277)
        (xy 195.655637 82.78232)
        (xy 195.550277 82.803277)
        (xy 195.460956 82.862959)
        (xy 195.401274 82.95228)
        (xy 195.380317 83.05764)
        (xy 195.401274 83.163)
        (xy 195.460956 83.252321)
        (xy 195.550277 83.312003)
        (xy 195.655637 83.33296)
        (xy 195.760997 83.312003)
        (xy 195.850318 83.252321)
        (xy 195.91 83.163)
      )
    )
  )
  (zone (net 0) (net_name "") (layer "In3.Cu") (hatch edge 0.508)
    (connect_pads no (clearance 0))
    (min_thickness 0.15) (filled_areas_thickness no)
    (keepout (tracks allowed) (vias allowed) (pads allowed) (copperpour not_allowed) (footprints allowed))
    (fill (thermal_gap 0.3) (thermal_bridge_width 0.2))
    (polygon
      (pts
        (xy 172.92696 85.073637)
        (xy 172.906003 84.968277)
        (xy 172.846321 84.878956)
        (xy 172.757 84.819274)
        (xy 172.65164 84.798317)
        (xy 172.54628 84.819274)
        (xy 172.456959 84.878956)
        (xy 172.397277 84.968277)
        (xy 172.37632 85.073637)
        (xy 172.397277 85.178997)
        (xy 172.456959 85.268318)
        (xy 172.54628 85.328)
        (xy 172.65164 85.348957)
        (xy 172.757 85.328)
        (xy 172.846321 85.268318)
        (xy 172.906003 85.178997)
      )
    )
  )
  (zone (net 0) (net_name "") (layer "In3.Cu") (hatch edge 0.508)
    (connect_pads no (clearance 0))
    (min_thickness 0.15) (filled_areas_thickness no)
    (keepout (tracks allowed) (vias allowed) (pads allowed) (copperpour not_allowed) (footprints allowed))
    (fill (thermal_gap 0.3) (thermal_bridge_width 0.2))
    (polygon
      (pts
        (xy 187.913001 82.063681)
        (xy 187.892044 81.958321)
        (xy 187.832362 81.869)
        (xy 187.743041 81.809318)
        (xy 187.637681 81.788361)
        (xy 187.532321 81.809318)
        (xy 187.443 81.869)
        (xy 187.383318 81.958321)
        (xy 187.362361 82.063681)
        (xy 187.383318 82.169041)
        (xy 187.443 82.258362)
        (xy 187.532321 82.318044)
        (xy 187.637681 82.339001)
        (xy 187.743041 82.318044)
        (xy 187.832362 82.258362)
        (xy 187.892044 82.169041)
      )
    )
  )
  (zone (net 0) (net_name "") (layer "In3.Cu") (hatch edge 0.508)
    (connect_pads no (clearance 0))
    (min_thickness 0.15) (filled_areas_thickness no)
    (keepout (tracks allowed) (vias allowed) (pads allowed) (copperpour not_allowed) (footprints allowed))
    (fill (thermal_gap 0.3) (thermal_bridge_width 0.2))
    (polygon
      (pts
        (xy 174.91032 82.06032)
        (xy 174.889363 81.95496)
        (xy 174.829681 81.865639)
        (xy 174.74036 81.805957)
        (xy 174.635 81.785)
        (xy 174.52964 81.805957)
        (xy 174.440319 81.865639)
        (xy 174.380637 81.95496)
        (xy 174.35968 82.06032)
        (xy 174.380637 82.16568)
        (xy 174.440319 82.255001)
        (xy 174.52964 82.314683)
        (xy 174.635 82.33564)
        (xy 174.74036 82.314683)
        (xy 174.829681 82.255001)
        (xy 174.889363 82.16568)
      )
    )
  )
  (zone (net 0) (net_name "") (layer "In3.Cu") (hatch edge 0.508)
    (connect_pads no (clearance 0))
    (min_thickness 0.15) (filled_areas_thickness no)
    (keepout (tracks allowed) (vias allowed) (pads allowed) (copperpour not_allowed) (footprints allowed))
    (fill (thermal_gap 0.3) (thermal_bridge_width 0.2))
    (polygon
      (pts
        (xy 180.910001 79.062681)
        (xy 180.889044 78.957321)
        (xy 180.829362 78.868)
        (xy 180.740041 78.808318)
        (xy 180.634681 78.787361)
        (xy 180.529321 78.808318)
        (xy 180.44 78.868)
        (xy 180.380318 78.957321)
        (xy 180.359361 79.062681)
        (xy 180.380318 79.168041)
        (xy 180.44 79.257362)
        (xy 180.529321 79.317044)
        (xy 180.634681 79.338001)
        (xy 180.740041 79.317044)
        (xy 180.829362 79.257362)
        (xy 180.889044 79.168041)
      )
    )
  )
  (zone (net 0) (net_name "") (layer "In3.Cu") (hatch edge 0.508)
    (connect_pads no (clearance 0))
    (min_thickness 0.15) (filled_areas_thickness no)
    (keepout (tracks allowed) (vias allowed) (pads allowed) (copperpour not_allowed) (footprints allowed))
    (fill (thermal_gap 0.3) (thermal_bridge_width 0.2))
    (polygon
      (pts
        (xy 182.912001 80.057681)
        (xy 182.891044 79.952321)
        (xy 182.831362 79.863)
        (xy 182.742041 79.803318)
        (xy 182.636681 79.782361)
        (xy 182.531321 79.803318)
        (xy 182.442 79.863)
        (xy 182.382318 79.952321)
        (xy 182.361361 80.057681)
        (xy 182.382318 80.163041)
        (xy 182.442 80.252362)
        (xy 182.531321 80.312044)
        (xy 182.636681 80.333001)
        (xy 182.742041 80.312044)
        (xy 182.831362 80.252362)
        (xy 182.891044 80.163041)
      )
    )
  )
  (zone (net 0) (net_name "") (layer "In3.Cu") (hatch edge 0.508)
    (connect_pads no (clearance 0))
    (min_thickness 0.15) (filled_areas_thickness no)
    (keepout (tracks allowed) (vias allowed) (pads allowed) (copperpour not_allowed) (footprints allowed))
    (fill (thermal_gap 0.3) (thermal_bridge_width 0.2))
    (polygon
      (pts
        (xy 194.91232 95.05732)
        (xy 194.891363 94.95196)
        (xy 194.831681 94.862639)
        (xy 194.74236 94.802957)
        (xy 194.637 94.782)
        (xy 194.53164 94.802957)
        (xy 194.442319 94.862639)
        (xy 194.382637 94.95196)
        (xy 194.36168 95.05732)
        (xy 194.382637 95.16268)
        (xy 194.442319 95.252001)
        (xy 194.53164 95.311683)
        (xy 194.637 95.33264)
        (xy 194.74236 95.311683)
        (xy 194.831681 95.252001)
        (xy 194.891363 95.16268)
      )
    )
  )
  (zone (net 0) (net_name "") (layer "In3.Cu") (hatch edge 0.508)
    (connect_pads no (clearance 0))
    (min_thickness 0.15) (filled_areas_thickness no)
    (keepout (tracks allowed) (vias allowed) (pads allowed) (copperpour not_allowed) (footprints allowed))
    (fill (thermal_gap 0.3) (thermal_bridge_width 0.2))
    (polygon
      (pts
        (xy 193.911641 101.064362)
        (xy 193.890684 100.959002)
        (xy 193.831002 100.869681)
        (xy 193.741681 100.809999)
        (xy 193.636321 100.789042)
        (xy 193.530961 100.809999)
        (xy 193.44164 100.869681)
        (xy 193.381958 100.959002)
        (xy 193.361001 101.064362)
        (xy 193.381958 101.169722)
        (xy 193.44164 101.259043)
        (xy 193.530961 101.318725)
        (xy 193.636321 101.339682)
        (xy 193.741681 101.318725)
        (xy 193.831002 101.259043)
        (xy 193.890684 101.169722)
      )
    )
  )
  (zone (net 0) (net_name "") (layer "In3.Cu") (hatch edge 0.508)
    (connect_pads no (clearance 0))
    (min_thickness 0.15) (filled_areas_thickness no)
    (keepout (tracks allowed) (vias allowed) (pads allowed) (copperpour not_allowed) (footprints allowed))
    (fill (thermal_gap 0.3) (thermal_bridge_width 0.2))
    (polygon
      (pts
        (xy 188.91368 77.069637)
        (xy 188.892723 76.964277)
        (xy 188.833041 76.874956)
        (xy 188.74372 76.815274)
        (xy 188.63836 76.794317)
        (xy 188.533 76.815274)
        (xy 188.443679 76.874956)
        (xy 188.383997 76.964277)
        (xy 188.36304 77.069637)
        (xy 188.383997 77.174997)
        (xy 188.443679 77.264318)
        (xy 188.533 77.324)
        (xy 188.63836 77.344957)
        (xy 188.74372 77.324)
        (xy 188.833041 77.264318)
        (xy 188.892723 77.174997)
      )
    )
  )
  (zone (net 0) (net_name "") (layer "In3.Cu") (hatch edge 0.508)
    (connect_pads no (clearance 0))
    (min_thickness 0.15) (filled_areas_thickness no)
    (keepout (tracks allowed) (vias allowed) (pads allowed) (copperpour not_allowed) (footprints allowed))
    (fill (thermal_gap 0.3) (thermal_bridge_width 0.2))
    (polygon
      (pts
        (xy 193.90632 95.06132)
        (xy 193.885363 94.95596)
        (xy 193.825681 94.866639)
        (xy 193.73636 94.806957)
        (xy 193.631 94.786)
        (xy 193.52564 94.806957)
        (xy 193.436319 94.866639)
        (xy 193.376637 94.95596)
        (xy 193.35568 95.06132)
        (xy 193.376637 95.16668)
        (xy 193.436319 95.256001)
        (xy 193.52564 95.315683)
        (xy 193.631 95.33664)
        (xy 193.73636 95.315683)
        (xy 193.825681 95.256001)
        (xy 193.885363 95.16668)
      )
    )
  )
  (zone (net 0) (net_name "") (layer "In3.Cu") (hatch edge 0.508)
    (connect_pads no (clearance 0))
    (min_thickness 0.15) (filled_areas_thickness no)
    (keepout (tracks allowed) (vias allowed) (pads allowed) (copperpour not_allowed) (footprints allowed))
    (fill (thermal_gap 0.3) (thermal_bridge_width 0.2))
    (polygon
      (pts
        (xy 174.91264 83.058)
        (xy 174.891683 82.95264)
        (xy 174.832001 82.863319)
        (xy 174.74268 82.803637)
        (xy 174.63732 82.78268)
        (xy 174.53196 82.803637)
        (xy 174.442639 82.863319)
        (xy 174.382957 82.95264)
        (xy 174.362 83.058)
        (xy 174.382957 83.16336)
        (xy 174.442639 83.252681)
        (xy 174.53196 83.312363)
        (xy 174.63732 83.33332)
        (xy 174.74268 83.312363)
        (xy 174.832001 83.252681)
        (xy 174.891683 83.16336)
      )
    )
  )
  (zone (net 0) (net_name "") (layer "In3.Cu") (hatch edge 0.508)
    (connect_pads no (clearance 0))
    (min_thickness 0.15) (filled_areas_thickness no)
    (keepout (tracks allowed) (vias allowed) (pads allowed) (copperpour not_allowed) (footprints allowed))
    (fill (thermal_gap 0.3) (thermal_bridge_width 0.2))
    (polygon
      (pts
        (xy 194.913091 91.061091)
        (xy 194.892134 90.955731)
        (xy 194.832452 90.86641)
        (xy 194.743131 90.806728)
        (xy 194.637771 90.785771)
        (xy 194.532411 90.806728)
        (xy 194.44309 90.86641)
        (xy 194.383408 90.955731)
        (xy 194.362451 91.061091)
        (xy 194.383408 91.166451)
        (xy 194.44309 91.255772)
        (xy 194.532411 91.315454)
        (xy 194.637771 91.336411)
        (xy 194.743131 91.315454)
        (xy 194.832452 91.255772)
        (xy 194.892134 91.166451)
      )
    )
  )
  (zone (net 0) (net_name "") (layer "In3.Cu") (hatch edge 0.508)
    (connect_pads no (clearance 0))
    (min_thickness 0.15) (filled_areas_thickness no)
    (keepout (tracks allowed) (vias allowed) (pads allowed) (copperpour not_allowed) (footprints allowed))
    (fill (thermal_gap 0.3) (thermal_bridge_width 0.2))
    (polygon
      (pts
        (xy 193.912412 91.062773)
        (xy 193.891455 90.957413)
        (xy 193.831773 90.868092)
        (xy 193.742452 90.80841)
        (xy 193.637092 90.787453)
        (xy 193.531732 90.80841)
        (xy 193.442411 90.868092)
        (xy 193.382729 90.957413)
        (xy 193.361772 91.062773)
        (xy 193.382729 91.168133)
        (xy 193.442411 91.257454)
        (xy 193.531732 91.317136)
        (xy 193.637092 91.338093)
        (xy 193.742452 91.317136)
        (xy 193.831773 91.257454)
        (xy 193.891455 91.168133)
      )
    )
  )
  (zone (net 0) (net_name "") (layer "In3.Cu") (hatch edge 0.508)
    (connect_pads no (clearance 0))
    (min_thickness 0.15) (filled_areas_thickness no)
    (keepout (tracks allowed) (vias allowed) (pads allowed) (copperpour not_allowed) (footprints allowed))
    (fill (thermal_gap 0.3) (thermal_bridge_width 0.2))
    (polygon
      (pts
        (xy 181.91232 81.06068)
        (xy 181.891363 80.95532)
        (xy 181.831681 80.865999)
        (xy 181.74236 80.806317)
        (xy 181.637 80.78536)
        (xy 181.53164 80.806317)
        (xy 181.442319 80.865999)
        (xy 181.382637 80.95532)
        (xy 181.36168 81.06068)
        (xy 181.382637 81.16604)
        (xy 181.442319 81.255361)
        (xy 181.53164 81.315043)
        (xy 181.637 81.336)
        (xy 181.74236 81.315043)
        (xy 181.831681 81.255361)
        (xy 181.891363 81.16604)
      )
    )
  )
  (zone (net 0) (net_name "") (layer "In3.Cu") (hatch edge 0.508)
    (connect_pads no (clearance 0))
    (min_thickness 0.15) (filled_areas_thickness no)
    (keepout (tracks allowed) (vias allowed) (pads allowed) (copperpour not_allowed) (footprints allowed))
    (fill (thermal_gap 0.3) (thermal_bridge_width 0.2))
    (polygon
      (pts
        (xy 185.872957 77.20136)
        (xy 185.852 77.096)
        (xy 185.792318 77.006679)
        (xy 185.702997 76.946997)
        (xy 185.597637 76.92604)
        (xy 185.492277 76.946997)
        (xy 185.402956 77.006679)
        (xy 185.343274 77.096)
        (xy 185.322317 77.20136)
        (xy 185.343274 77.30672)
        (xy 185.402956 77.396041)
        (xy 185.492277 77.455723)
        (xy 185.597637 77.47668)
        (xy 185.702997 77.455723)
        (xy 185.792318 77.396041)
        (xy 185.852 77.30672)
      )
    )
  )
  (zone (net 0) (net_name "") (layer "In3.Cu") (hatch edge 0.508)
    (connect_pads no (clearance 0))
    (min_thickness 0.15) (filled_areas_thickness no)
    (keepout (tracks allowed) (vias allowed) (pads allowed) (copperpour not_allowed) (footprints allowed))
    (fill (thermal_gap 0.3) (thermal_bridge_width 0.2))
    (polygon
      (pts
        (xy 195.795639 81.067319)
        (xy 195.774682 80.961959)
        (xy 195.715 80.872638)
        (xy 195.625679 80.812956)
        (xy 195.520319 80.791999)
        (xy 195.414959 80.812956)
        (xy 195.325638 80.872638)
        (xy 195.265956 80.961959)
        (xy 195.244999 81.067319)
        (xy 195.265956 81.172679)
        (xy 195.325638 81.262)
        (xy 195.414959 81.321682)
        (xy 195.520319 81.342639)
        (xy 195.625679 81.321682)
        (xy 195.715 81.262)
        (xy 195.774682 81.172679)
      )
    )
  )
  (zone (net 0) (net_name "") (layer "In3.Cu") (hatch edge 0.508)
    (connect_pads no (clearance 0))
    (min_thickness 0.15) (filled_areas_thickness no)
    (keepout (tracks allowed) (vias allowed) (pads allowed) (copperpour not_allowed) (footprints allowed))
    (fill (thermal_gap 0.3) (thermal_bridge_width 0.2))
    (polygon
      (pts
        (xy 194.910639 89.059681)
        (xy 194.889682 88.954321)
        (xy 194.83 88.865)
        (xy 194.740679 88.805318)
        (xy 194.635319 88.784361)
        (xy 194.529959 88.805318)
        (xy 194.440638 88.865)
        (xy 194.380956 88.954321)
        (xy 194.359999 89.059681)
        (xy 194.380956 89.165041)
        (xy 194.440638 89.254362)
        (xy 194.529959 89.314044)
        (xy 194.635319 89.335001)
        (xy 194.740679 89.314044)
        (xy 194.83 89.254362)
        (xy 194.889682 89.165041)
      )
    )
  )
  (zone (net 0) (net_name "") (layer "In3.Cu") (hatch edge 0.508)
    (connect_pads no (clearance 0))
    (min_thickness 0.15) (filled_areas_thickness no)
    (keepout (tracks allowed) (vias allowed) (pads allowed) (copperpour not_allowed) (footprints allowed))
    (fill (thermal_gap 0.3) (thermal_bridge_width 0.2))
    (polygon
      (pts
        (xy 193.913641 97.062362)
        (xy 193.892684 96.957002)
        (xy 193.833002 96.867681)
        (xy 193.743681 96.807999)
        (xy 193.638321 96.787042)
        (xy 193.532961 96.807999)
        (xy 193.44364 96.867681)
        (xy 193.383958 96.957002)
        (xy 193.363001 97.062362)
        (xy 193.383958 97.167722)
        (xy 193.44364 97.257043)
        (xy 193.532961 97.316725)
        (xy 193.638321 97.337682)
        (xy 193.743681 97.316725)
        (xy 193.833002 97.257043)
        (xy 193.892684 97.167722)
      )
    )
  )
  (zone (net 0) (net_name "") (layer "In3.Cu") (hatch edge 0.508)
    (connect_pads no (clearance 0))
    (min_thickness 0.15) (filled_areas_thickness no)
    (keepout (tracks allowed) (vias allowed) (pads allowed) (copperpour not_allowed) (footprints allowed))
    (fill (thermal_gap 0.3) (thermal_bridge_width 0.2))
    (polygon
      (pts
        (xy 173.909904 82.062998)
        (xy 173.888947 81.957638)
        (xy 173.829265 81.868317)
        (xy 173.739944 81.808635)
        (xy 173.634584 81.787678)
        (xy 173.529224 81.808635)
        (xy 173.439903 81.868317)
        (xy 173.380221 81.957638)
        (xy 173.359264 82.062998)
        (xy 173.380221 82.168358)
        (xy 173.439903 82.257679)
        (xy 173.529224 82.317361)
        (xy 173.634584 82.338318)
        (xy 173.739944 82.317361)
        (xy 173.829265 82.257679)
        (xy 173.888947 82.168358)
      )
    )
  )
  (zone (net 0) (net_name "") (layer "In3.Cu") (hatch edge 0.508)
    (connect_pads no (clearance 0))
    (min_thickness 0.15) (filled_areas_thickness no)
    (keepout (tracks allowed) (vias allowed) (pads allowed) (copperpour not_allowed) (footprints allowed))
    (fill (thermal_gap 0.3) (thermal_bridge_width 0.2))
    (polygon
      (pts
        (xy 193.90996 89.061363)
        (xy 193.889003 88.956003)
        (xy 193.829321 88.866682)
        (xy 193.74 88.807)
        (xy 193.63464 88.786043)
        (xy 193.52928 88.807)
        (xy 193.439959 88.866682)
        (xy 193.380277 88.956003)
        (xy 193.35932 89.061363)
        (xy 193.380277 89.166723)
        (xy 193.439959 89.256044)
        (xy 193.52928 89.315726)
        (xy 193.63464 89.336683)
        (xy 193.74 89.315726)
        (xy 193.829321 89.256044)
        (xy 193.889003 89.166723)
      )
    )
  )
  (zone (net 0) (net_name "") (layer "In3.Cu") (hatch edge 0.508)
    (connect_pads no (clearance 0))
    (min_thickness 0.15) (filled_areas_thickness no)
    (keepout (tracks allowed) (vias allowed) (pads allowed) (copperpour not_allowed) (footprints allowed))
    (fill (thermal_gap 0.3) (thermal_bridge_width 0.2))
    (polygon
      (pts
        (xy 189.90968 82.063363)
        (xy 189.888723 81.958003)
        (xy 189.829041 81.868682)
        (xy 189.73972 81.809)
        (xy 189.63436 81.788043)
        (xy 189.529 81.809)
        (xy 189.439679 81.868682)
        (xy 189.379997 81.958003)
        (xy 189.35904 82.063363)
        (xy 189.379997 82.168723)
        (xy 189.439679 82.258044)
        (xy 189.529 82.317726)
        (xy 189.63436 82.338683)
        (xy 189.73972 82.317726)
        (xy 189.829041 82.258044)
        (xy 189.888723 82.168723)
      )
    )
  )
  (zone (net 0) (net_name "") (layer "In3.Cu") (hatch edge 0.508)
    (connect_pads no (clearance 0))
    (min_thickness 0.15) (filled_areas_thickness no)
    (keepout (tracks allowed) (vias allowed) (pads allowed) (copperpour not_allowed) (footprints allowed))
    (fill (thermal_gap 0.3) (thermal_bridge_width 0.2))
    (polygon
      (pts
        (xy 172.91164 82.063)
        (xy 172.890683 81.95764)
        (xy 172.831001 81.868319)
        (xy 172.74168 81.808637)
        (xy 172.63632 81.78768)
        (xy 172.53096 81.808637)
        (xy 172.441639 81.868319)
        (xy 172.381957 81.95764)
        (xy 172.361 82.063)
        (xy 172.381957 82.16836)
        (xy 172.441639 82.257681)
        (xy 172.53096 82.317363)
        (xy 172.63632 82.33832)
        (xy 172.74168 82.317363)
        (xy 172.831001 82.257681)
        (xy 172.890683 82.16836)
      )
    )
  )
  (zone (net 0) (net_name "") (layer "In3.Cu") (hatch edge 0.508)
    (connect_pads no (clearance 0))
    (min_thickness 0.15) (filled_areas_thickness no)
    (keepout (tracks allowed) (vias allowed) (pads allowed) (copperpour not_allowed) (footprints allowed))
    (fill (thermal_gap 0.3) (thermal_bridge_width 0.2))
    (polygon
      (pts
        (xy 176.90996 83.059363)
        (xy 176.889003 82.954003)
        (xy 176.829321 82.864682)
        (xy 176.74 82.805)
        (xy 176.63464 82.784043)
        (xy 176.52928 82.805)
        (xy 176.439959 82.864682)
        (xy 176.380277 82.954003)
        (xy 176.35932 83.059363)
        (xy 176.380277 83.164723)
        (xy 176.439959 83.254044)
        (xy 176.52928 83.313726)
        (xy 176.63464 83.334683)
        (xy 176.74 83.313726)
        (xy 176.829321 83.254044)
        (xy 176.889003 83.164723)
      )
    )
  )
  (zone (net 0) (net_name "") (layer "In3.Cu") (hatch edge 0.508)
    (connect_pads no (clearance 0))
    (min_thickness 0.15) (filled_areas_thickness no)
    (keepout (tracks allowed) (vias allowed) (pads allowed) (copperpour not_allowed) (footprints allowed))
    (fill (thermal_gap 0.3) (thermal_bridge_width 0.2))
    (polygon
      (pts
        (xy 179.912503 80.057038)
        (xy 179.891546 79.951678)
        (xy 179.831864 79.862357)
        (xy 179.742543 79.802675)
        (xy 179.637183 79.781718)
        (xy 179.531823 79.802675)
        (xy 179.442502 79.862357)
        (xy 179.38282 79.951678)
        (xy 179.361863 80.057038)
        (xy 179.38282 80.162398)
        (xy 179.442502 80.251719)
        (xy 179.531823 80.311401)
        (xy 179.637183 80.332358)
        (xy 179.742543 80.311401)
        (xy 179.831864 80.251719)
        (xy 179.891546 80.162398)
      )
    )
  )
  (zone (net 0) (net_name "") (layer "In3.Cu") (hatch edge 0.508)
    (connect_pads no (clearance 0))
    (min_thickness 0.15) (filled_areas_thickness no)
    (keepout (tracks allowed) (vias allowed) (pads allowed) (copperpour not_allowed) (footprints allowed))
    (fill (thermal_gap 0.3) (thermal_bridge_width 0.2))
    (polygon
      (pts
        (xy 194.91432 97.06068)
        (xy 194.893363 96.95532)
        (xy 194.833681 96.865999)
        (xy 194.74436 96.806317)
        (xy 194.639 96.78536)
        (xy 194.53364 96.806317)
        (xy 194.444319 96.865999)
        (xy 194.384637 96.95532)
        (xy 194.36368 97.06068)
        (xy 194.384637 97.16604)
        (xy 194.444319 97.255361)
        (xy 194.53364 97.315043)
        (xy 194.639 97.336)
        (xy 194.74436 97.315043)
        (xy 194.833681 97.255361)
        (xy 194.893363 97.16604)
      )
    )
  )
  (zone (net 0) (net_name "") (layer "In3.Cu") (hatch edge 0.508)
    (connect_pads no (clearance 0))
    (min_thickness 0.15) (filled_areas_thickness no)
    (keepout (tracks allowed) (vias allowed) (pads allowed) (copperpour not_allowed) (footprints allowed))
    (fill (thermal_gap 0.3) (thermal_bridge_width 0.2))
    (polygon
      (pts
        (xy 185.84368 80.975637)
        (xy 185.822723 80.870277)
        (xy 185.763041 80.780956)
        (xy 185.67372 80.721274)
        (xy 185.56836 80.700317)
        (xy 185.463 80.721274)
        (xy 185.373679 80.780956)
        (xy 185.313997 80.870277)
        (xy 185.29304 80.975637)
        (xy 185.313997 81.080997)
        (xy 185.373679 81.170318)
        (xy 185.463 81.23)
        (xy 185.56836 81.250957)
        (xy 185.67372 81.23)
        (xy 185.763041 81.170318)
        (xy 185.822723 81.080997)
      )
    )
  )
  (zone (net 0) (net_name "") (layer "In3.Cu") (hatch edge 0.508)
    (connect_pads no (clearance 0))
    (min_thickness 0.15) (filled_areas_thickness no)
    (keepout (tracks allowed) (vias allowed) (pads allowed) (copperpour not_allowed) (footprints allowed))
    (fill (thermal_gap 0.3) (thermal_bridge_width 0.2))
    (polygon
      (pts
        (xy 190.28096 76.517363)
        (xy 190.260003 76.412003)
        (xy 190.200321 76.322682)
        (xy 190.111 76.263)
        (xy 190.00564 76.242043)
        (xy 189.90028 76.263)
        (xy 189.810959 76.322682)
        (xy 189.751277 76.412003)
        (xy 189.73032 76.517363)
        (xy 189.751277 76.622723)
        (xy 189.810959 76.712044)
        (xy 189.90028 76.771726)
        (xy 190.00564 76.792683)
        (xy 190.111 76.771726)
        (xy 190.200321 76.712044)
        (xy 190.260003 76.622723)
      )
    )
  )
  (zone (net 0) (net_name "") (layer "In3.Cu") (hatch edge 0.508)
    (connect_pads no (clearance 0))
    (min_thickness 0.15) (filled_areas_thickness no)
    (keepout (tracks allowed) (vias allowed) (pads allowed) (copperpour not_allowed) (footprints allowed))
    (fill (thermal_gap 0.3) (thermal_bridge_width 0.2))
    (polygon
      (pts
        (xy 180.910001 80.05968)
        (xy 180.889044 79.95432)
        (xy 180.829362 79.864999)
        (xy 180.740041 79.805317)
        (xy 180.634681 79.78436)
        (xy 180.529321 79.805317)
        (xy 180.44 79.864999)
        (xy 180.380318 79.95432)
        (xy 180.359361 80.05968)
        (xy 180.380318 80.16504)
        (xy 180.44 80.254361)
        (xy 180.529321 80.314043)
        (xy 180.634681 80.335)
        (xy 180.740041 80.314043)
        (xy 180.829362 80.254361)
        (xy 180.889044 80.16504)
      )
    )
  )
  (zone (net 0) (net_name "") (layer "In3.Cu") (hatch edge 0.508)
    (connect_pads no (clearance 0))
    (min_thickness 0.15) (filled_areas_thickness no)
    (keepout (tracks allowed) (vias allowed) (pads allowed) (copperpour not_allowed) (footprints allowed))
    (fill (thermal_gap 0.3) (thermal_bridge_width 0.2))
    (polygon
      (pts
        (xy 195.933957 85.05664)
        (xy 195.913 84.95128)
        (xy 195.853318 84.861959)
        (xy 195.763997 84.802277)
        (xy 195.658637 84.78132)
        (xy 195.553277 84.802277)
        (xy 195.463956 84.861959)
        (xy 195.404274 84.95128)
        (xy 195.383317 85.05664)
        (xy 195.404274 85.162)
        (xy 195.463956 85.251321)
        (xy 195.553277 85.311003)
        (xy 195.658637 85.33196)
        (xy 195.763997 85.311003)
        (xy 195.853318 85.251321)
        (xy 195.913 85.162)
      )
    )
  )
  (zone (net 0) (net_name "") (layer "In3.Cu") (hatch edge 0.508)
    (connect_pads no (clearance 0))
    (min_thickness 0.15) (filled_areas_thickness no)
    (keepout (tracks allowed) (vias allowed) (pads allowed) (copperpour not_allowed) (footprints allowed))
    (fill (thermal_gap 0.3) (thermal_bridge_width 0.2))
    (polygon
      (pts
        (xy 176.911001 79.040681)
        (xy 176.890044 78.935321)
        (xy 176.830362 78.846)
        (xy 176.741041 78.786318)
        (xy 176.635681 78.765361)
        (xy 176.530321 78.786318)
        (xy 176.441 78.846)
        (xy 176.381318 78.935321)
        (xy 176.360361 79.040681)
        (xy 176.381318 79.146041)
        (xy 176.441 79.235362)
        (xy 176.530321 79.295044)
        (xy 176.635681 79.316001)
        (xy 176.741041 79.295044)
        (xy 176.830362 79.235362)
        (xy 176.890044 79.146041)
      )
    )
  )
  (zone (net 0) (net_name "") (layer "In3.Cu") (hatch edge 0.508)
    (connect_pads no (clearance 0))
    (min_thickness 0.15) (filled_areas_thickness no)
    (keepout (tracks allowed) (vias allowed) (pads allowed) (copperpour not_allowed) (footprints allowed))
    (fill (thermal_gap 0.3) (thermal_bridge_width 0.2))
    (polygon
      (pts
        (xy 185.842957 80.97536)
        (xy 185.822 80.87)
        (xy 185.762318 80.780679)
        (xy 185.672997 80.720997)
        (xy 185.567637 80.70004)
        (xy 185.462277 80.720997)
        (xy 185.372956 80.780679)
        (xy 185.313274 80.87)
        (xy 185.292317 80.97536)
        (xy 185.313274 81.08072)
        (xy 185.372956 81.170041)
        (xy 185.462277 81.229723)
        (xy 185.567637 81.25068)
        (xy 185.672997 81.229723)
        (xy 185.762318 81.170041)
        (xy 185.822 81.08072)
      )
    )
  )
  (zone (net 0) (net_name "") (layer "In3.Cu") (hatch edge 0.508)
    (connect_pads no (clearance 0))
    (min_thickness 0.15) (filled_areas_thickness no)
    (keepout (tracks allowed) (vias allowed) (pads allowed) (copperpour not_allowed) (footprints allowed))
    (fill (thermal_gap 0.3) (thermal_bridge_width 0.2))
    (polygon
      (pts
        (xy 187.893914 81.060213)
        (xy 187.872957 80.954853)
        (xy 187.813275 80.865532)
        (xy 187.723954 80.80585)
        (xy 187.618594 80.784893)
        (xy 187.513234 80.80585)
        (xy 187.423913 80.865532)
        (xy 187.364231 80.954853)
        (xy 187.343274 81.060213)
        (xy 187.364231 81.165573)
        (xy 187.423913 81.254894)
        (xy 187.513234 81.314576)
        (xy 187.618594 81.335533)
        (xy 187.723954 81.314576)
        (xy 187.813275 81.254894)
        (xy 187.872957 81.165573)
      )
    )
  )
  (zone (net 0) (net_name "") (layer "In3.Cu") (hatch edge 0.508)
    (connect_pads no (clearance 0))
    (min_thickness 0.15) (filled_areas_thickness no)
    (keepout (tracks allowed) (vias allowed) (pads allowed) (copperpour not_allowed) (footprints allowed))
    (fill (thermal_gap 0.3) (thermal_bridge_width 0.2))
    (polygon
      (pts
        (xy 196.931326 78.060027)
        (xy 196.910369 77.954667)
        (xy 196.850687 77.865346)
        (xy 196.761366 77.805664)
        (xy 196.656006 77.784707)
        (xy 196.550646 77.805664)
        (xy 196.461325 77.865346)
        (xy 196.401643 77.954667)
        (xy 196.380686 78.060027)
        (xy 196.401643 78.165387)
        (xy 196.461325 78.254708)
        (xy 196.550646 78.31439)
        (xy 196.656006 78.335347)
        (xy 196.761366 78.31439)
        (xy 196.850687 78.254708)
        (xy 196.910369 78.165387)
      )
    )
  )
  (zone (net 0) (net_name "") (layer "In3.Cu") (hatch edge 0.508)
    (connect_pads no (clearance 0))
    (min_thickness 0.15) (filled_areas_thickness no)
    (keepout (tracks allowed) (vias allowed) (pads allowed) (copperpour not_allowed) (footprints allowed))
    (fill (thermal_gap 0.3) (thermal_bridge_width 0.2))
    (polygon
      (pts
        (xy 196.931583 86.063168)
        (xy 196.910626 85.957808)
        (xy 196.850944 85.868487)
        (xy 196.761623 85.808805)
        (xy 196.656263 85.787848)
        (xy 196.550903 85.808805)
        (xy 196.461582 85.868487)
        (xy 196.4019 85.957808)
        (xy 196.380943 86.063168)
        (xy 196.4019 86.168528)
        (xy 196.461582 86.257849)
        (xy 196.550903 86.317531)
        (xy 196.656263 86.338488)
        (xy 196.761623 86.317531)
        (xy 196.850944 86.257849)
        (xy 196.910626 86.168528)
      )
    )
  )
  (zone (net 0) (net_name "") (layer "In3.Cu") (hatch edge 0.508)
    (connect_pads no (clearance 0))
    (min_thickness 0.15) (filled_areas_thickness no)
    (keepout (tracks allowed) (vias allowed) (pads allowed) (copperpour not_allowed) (footprints allowed))
    (fill (thermal_gap 0.3) (thermal_bridge_width 0.2))
    (polygon
      (pts
        (xy 191.90996 102.064363)
        (xy 191.889003 101.959003)
        (xy 191.829321 101.869682)
        (xy 191.74 101.81)
        (xy 191.63464 101.789043)
        (xy 191.52928 101.81)
        (xy 191.439959 101.869682)
        (xy 191.380277 101.959003)
        (xy 191.35932 102.064363)
        (xy 191.380277 102.169723)
        (xy 191.439959 102.259044)
        (xy 191.52928 102.318726)
        (xy 191.63464 102.339683)
        (xy 191.74 102.318726)
        (xy 191.829321 102.259044)
        (xy 191.889003 102.169723)
      )
    )
  )
  (zone (net 0) (net_name "") (layer "In3.Cu") (hatch edge 0.508)
    (connect_pads no (clearance 0))
    (min_thickness 0.15) (filled_areas_thickness no)
    (keepout (tracks allowed) (vias allowed) (pads allowed) (copperpour not_allowed) (footprints allowed))
    (fill (thermal_gap 0.3) (thermal_bridge_width 0.2))
    (polygon
      (pts
        (xy 196.93232 79.06332)
        (xy 196.911363 78.95796)
        (xy 196.851681 78.868639)
        (xy 196.76236 78.808957)
        (xy 196.657 78.788)
        (xy 196.55164 78.808957)
        (xy 196.462319 78.868639)
        (xy 196.402637 78.95796)
        (xy 196.38168 79.06332)
        (xy 196.402637 79.16868)
        (xy 196.462319 79.258001)
        (xy 196.55164 79.317683)
        (xy 196.657 79.33864)
        (xy 196.76236 79.317683)
        (xy 196.851681 79.258001)
        (xy 196.911363 79.16868)
      )
    )
  )
  (zone (net 0) (net_name "") (layer "In3.Cu") (hatch edge 0.508)
    (connect_pads no (clearance 0))
    (min_thickness 0.15) (filled_areas_thickness no)
    (keepout (tracks allowed) (vias allowed) (pads allowed) (copperpour not_allowed) (footprints allowed))
    (fill (thermal_gap 0.3) (thermal_bridge_width 0.2))
    (polygon
      (pts
        (xy 186.930639 85.063681)
        (xy 186.909682 84.958321)
        (xy 186.85 84.869)
        (xy 186.760679 84.809318)
        (xy 186.655319 84.788361)
        (xy 186.549959 84.809318)
        (xy 186.460638 84.869)
        (xy 186.400956 84.958321)
        (xy 186.379999 85.063681)
        (xy 186.400956 85.169041)
        (xy 186.460638 85.258362)
        (xy 186.549959 85.318044)
        (xy 186.655319 85.339001)
        (xy 186.760679 85.318044)
        (xy 186.85 85.258362)
        (xy 186.909682 85.169041)
      )
    )
  )
  (zone (net 0) (net_name "") (layer "In3.Cu") (hatch edge 0.508)
    (connect_pads no (clearance 0))
    (min_thickness 0.15) (filled_areas_thickness no)
    (keepout (tracks allowed) (vias allowed) (pads allowed) (copperpour not_allowed) (footprints allowed))
    (fill (thermal_gap 0.3) (thermal_bridge_width 0.2))
    (polygon
      (pts
        (xy 178.91196 80.060363)
        (xy 178.891003 79.955003)
        (xy 178.831321 79.865682)
        (xy 178.742 79.806)
        (xy 178.63664 79.785043)
        (xy 178.53128 79.806)
        (xy 178.441959 79.865682)
        (xy 178.382277 79.955003)
        (xy 178.36132 80.060363)
        (xy 178.382277 80.165723)
        (xy 178.441959 80.255044)
        (xy 178.53128 80.314726)
        (xy 178.63664 80.335683)
        (xy 178.742 80.314726)
        (xy 178.831321 80.255044)
        (xy 178.891003 80.165723)
      )
    )
  )
  (zone (net 0) (net_name "") (layer "In3.Cu") (hatch edge 0.508)
    (connect_pads no (clearance 0))
    (min_thickness 0.15) (filled_areas_thickness no)
    (keepout (tracks allowed) (vias allowed) (pads allowed) (copperpour not_allowed) (footprints allowed))
    (fill (thermal_gap 0.3) (thermal_bridge_width 0.2))
    (polygon
      (pts
        (xy 188.04468 78.037637)
        (xy 188.023723 77.932277)
        (xy 187.964041 77.842956)
        (xy 187.87472 77.783274)
        (xy 187.76936 77.762317)
        (xy 187.664 77.783274)
        (xy 187.574679 77.842956)
        (xy 187.514997 77.932277)
        (xy 187.49404 78.037637)
        (xy 187.514997 78.142997)
        (xy 187.574679 78.232318)
        (xy 187.664 78.292)
        (xy 187.76936 78.312957)
        (xy 187.87472 78.292)
        (xy 187.964041 78.232318)
        (xy 188.023723 78.142997)
      )
    )
  )
  (zone (net 143) (net_name "3V3_SYS") (layer "In3.Cu") (hatch edge 0.508)
    (priority 2)
    (connect_pads yes (clearance 0.12))
    (min_thickness 0.15) (filled_areas_thickness no)
    (fill yes (thermal_gap 0.508) (thermal_bridge_width 0.508) (smoothing fillet) (radius 0.5))
    (polygon
      (pts
        (xy 193 88.7)
        (xy 190.5 88.7)
        (xy 190.5 91.9)
        (xy 191 92.4)
        (xy 191 93)
        (xy 190.5 93.5)
        (xy 190.5 105.6)
        (xy 187.9 108.2)
        (xy 179.6 108.2)
        (xy 174.7 113.1)
        (xy 171.925 115.875)
        (xy 152 115.875)
        (xy 147.025 120.9)
        (xy 142.8 120.9)
        (xy 142.8 136)
        (xy 107 136)
        (xy 106.9 70.7)
        (xy 143 70.7)
        (xy 148.1 76)
        (xy 169.9 76)
        (xy 170.55 76.65)
        (xy 170.55 79.2)
        (xy 172.25 80.9)
        (xy 174.4 80.9)
        (xy 176.3 82.8)
        (xy 177.8 82.8)
        (xy 177.8 85.6)
        (xy 193 85.6)
      )
    )
  )
  (zone (net 0) (net_name "") (layer "In3.Cu") (hatch edge 0.508)
    (connect_pads no (clearance 0))
    (min_thickness 0.15) (filled_areas_thickness no)
    (keepout (tracks allowed) (vias allowed) (pads allowed) (copperpour not_allowed) (footprints allowed))
    (fill (thermal_gap 0.3) (thermal_bridge_width 0.2))
    (polygon
      (pts
        (xy 196.92796 84.060363)
        (xy 196.907003 83.955003)
        (xy 196.847321 83.865682)
        (xy 196.758 83.806)
        (xy 196.65264 83.785043)
        (xy 196.54728 83.806)
        (xy 196.457959 83.865682)
        (xy 196.398277 83.955003)
        (xy 196.37732 84.060363)
        (xy 196.398277 84.165723)
        (xy 196.457959 84.255044)
        (xy 196.54728 84.314726)
        (xy 196.65264 84.335683)
        (xy 196.758 84.314726)
        (xy 196.847321 84.255044)
        (xy 196.907003 84.165723)
      )
    )
  )
  (zone (net 0) (net_name "") (layer "In3.Cu") (hatch edge 0.508)
    (connect_pads no (clearance 0))
    (min_thickness 0.15) (filled_areas_thickness no)
    (keepout (tracks allowed) (vias allowed) (pads allowed) (copperpour not_allowed) (footprints allowed))
    (fill (thermal_gap 0.3) (thermal_bridge_width 0.2))
    (polygon
      (pts
        (xy 193.91332 93.06132)
        (xy 193.892363 92.95596)
        (xy 193.832681 92.866639)
        (xy 193.74336 92.806957)
        (xy 193.638 92.786)
        (xy 193.53264 92.806957)
        (xy 193.443319 92.866639)
        (xy 193.383637 92.95596)
        (xy 193.36268 93.06132)
        (xy 193.383637 93.16668)
        (xy 193.443319 93.256001)
        (xy 193.53264 93.315683)
        (xy 193.638 93.33664)
        (xy 193.74336 93.315683)
        (xy 193.832681 93.256001)
        (xy 193.892363 93.16668)
      )
    )
  )
  (zone (net 0) (net_name "") (layer "In3.Cu") (hatch edge 0.508)
    (connect_pads no (clearance 0))
    (min_thickness 0.15) (filled_areas_thickness no)
    (keepout (tracks allowed) (vias allowed) (pads allowed) (copperpour not_allowed) (footprints allowed))
    (fill (thermal_gap 0.3) (thermal_bridge_width 0.2))
    (polygon
      (pts
        (xy 194.91232 101.06268)
        (xy 194.891363 100.95732)
        (xy 194.831681 100.867999)
        (xy 194.74236 100.808317)
        (xy 194.637 100.78736)
        (xy 194.53164 100.808317)
        (xy 194.442319 100.867999)
        (xy 194.382637 100.95732)
        (xy 194.36168 101.06268)
        (xy 194.382637 101.16804)
        (xy 194.442319 101.257361)
        (xy 194.53164 101.317043)
        (xy 194.637 101.338)
        (xy 194.74236 101.317043)
        (xy 194.831681 101.257361)
        (xy 194.891363 101.16804)
      )
    )
  )
  (zone (net 0) (net_name "") (layer "In3.Cu") (hatch edge 0.508)
    (connect_pads no (clearance 0))
    (min_thickness 0.15) (filled_areas_thickness no)
    (keepout (tracks allowed) (vias allowed) (pads allowed) (copperpour not_allowed) (footprints allowed))
    (fill (thermal_gap 0.3) (thermal_bridge_width 0.2))
    (polygon
      (pts
        (xy 186.911639 84.081681)
        (xy 186.890682 83.976321)
        (xy 186.831 83.887)
        (xy 186.741679 83.827318)
        (xy 186.636319 83.806361)
        (xy 186.530959 83.827318)
        (xy 186.441638 83.887)
        (xy 186.381956 83.976321)
        (xy 186.360999 84.081681)
        (xy 186.381956 84.187041)
        (xy 186.441638 84.276362)
        (xy 186.530959 84.336044)
        (xy 186.636319 84.357001)
        (xy 186.741679 84.336044)
        (xy 186.831 84.276362)
        (xy 186.890682 84.187041)
      )
    )
  )
  (zone (net 0) (net_name "") (layer "In3.Cu") (hatch edge 0.508)
    (connect_pads no (clearance 0))
    (min_thickness 0.15) (filled_areas_thickness no)
    (keepout (tracks allowed) (vias allowed) (pads allowed) (copperpour not_allowed) (footprints allowed))
    (fill (thermal_gap 0.3) (thermal_bridge_width 0.2))
    (polygon
      (pts
        (xy 196.93096 83.058363)
        (xy 196.910003 82.953003)
        (xy 196.850321 82.863682)
        (xy 196.761 82.804)
        (xy 196.65564 82.783043)
        (xy 196.55028 82.804)
        (xy 196.460959 82.863682)
        (xy 196.401277 82.953003)
        (xy 196.38032 83.058363)
        (xy 196.401277 83.163723)
        (xy 196.460959 83.253044)
        (xy 196.55028 83.312726)
        (xy 196.65564 83.333683)
        (xy 196.761 83.312726)
        (xy 196.850321 83.253044)
        (xy 196.910003 83.163723)
      )
    )
  )
  (zone (net 0) (net_name "") (layer "In3.Cu") (hatch edge 0.508)
    (connect_pads no (clearance 0))
    (min_thickness 0.15) (filled_areas_thickness no)
    (keepout (tracks allowed) (vias allowed) (pads allowed) (copperpour not_allowed) (footprints allowed))
    (fill (thermal_gap 0.3) (thermal_bridge_width 0.2))
    (polygon
      (pts
        (xy 177.89696 78.995363)
        (xy 177.876003 78.890003)
        (xy 177.816321 78.800682)
        (xy 177.727 78.741)
        (xy 177.62164 78.720043)
        (xy 177.51628 78.741)
        (xy 177.426959 78.800682)
        (xy 177.367277 78.890003)
        (xy 177.34632 78.995363)
        (xy 177.367277 79.100723)
        (xy 177.426959 79.190044)
        (xy 177.51628 79.249726)
        (xy 177.62164 79.270683)
        (xy 177.727 79.249726)
        (xy 177.816321 79.190044)
        (xy 177.876003 79.100723)
      )
    )
  )
  (zone (net 0) (net_name "") (layer "In3.Cu") (hatch edge 0.508)
    (connect_pads no (clearance 0))
    (min_thickness 0.15) (filled_areas_thickness no)
    (keepout (tracks allowed) (vias allowed) (pads allowed) (copperpour not_allowed) (footprints allowed))
    (fill (thermal_gap 0.3) (thermal_bridge_width 0.2))
    (polygon
      (pts
        (xy 175.915031 83.064089)
        (xy 175.894074 82.958729)
        (xy 175.834392 82.869408)
        (xy 175.745071 82.809726)
        (xy 175.639711 82.788769)
        (xy 175.534351 82.809726)
        (xy 175.44503 82.869408)
        (xy 175.385348 82.958729)
        (xy 175.364391 83.064089)
        (xy 175.385348 83.169449)
        (xy 175.44503 83.25877)
        (xy 175.534351 83.318452)
        (xy 175.639711 83.339409)
        (xy 175.745071 83.318452)
        (xy 175.834392 83.25877)
        (xy 175.894074 83.169449)
      )
    )
  )
  (zone (net 0) (net_name "") (layer "In3.Cu") (hatch edge 0.508)
    (connect_pads no (clearance 0))
    (min_thickness 0.15) (filled_areas_thickness no)
    (keepout (tracks allowed) (vias allowed) (pads allowed) (copperpour not_allowed) (footprints allowed))
    (fill (thermal_gap 0.3) (thermal_bridge_width 0.2))
    (polygon
      (pts
        (xy 185.874957 78.05736)
        (xy 185.854 77.952)
        (xy 185.794318 77.862679)
        (xy 185.704997 77.802997)
        (xy 185.599637 77.78204)
        (xy 185.494277 77.802997)
        (xy 185.404956 77.862679)
        (xy 185.345274 77.952)
        (xy 185.324317 78.05736)
        (xy 185.345274 78.16272)
        (xy 185.404956 78.252041)
        (xy 185.494277 78.311723)
        (xy 185.599637 78.33268)
        (xy 185.704997 78.311723)
        (xy 185.794318 78.252041)
        (xy 185.854 78.16272)
      )
    )
  )
  (zone (net 0) (net_name "") (layer "In3.Cu") (hatch edge 0.508)
    (connect_pads no (clearance 0))
    (min_thickness 0.15) (filled_areas_thickness no)
    (keepout (tracks allowed) (vias allowed) (pads allowed) (copperpour not_allowed) (footprints allowed))
    (fill (thermal_gap 0.3) (thermal_bridge_width 0.2))
    (polygon
      (pts
        (xy 193.9134 99.059735)
        (xy 193.892443 98.954375)
        (xy 193.832761 98.865054)
        (xy 193.74344 98.805372)
        (xy 193.63808 98.784415)
        (xy 193.53272 98.805372)
        (xy 193.443399 98.865054)
        (xy 193.383717 98.954375)
        (xy 193.36276 99.059735)
        (xy 193.383717 99.165095)
        (xy 193.443399 99.254416)
        (xy 193.53272 99.314098)
        (xy 193.63808 99.335055)
        (xy 193.74344 99.314098)
        (xy 193.832761 99.254416)
        (xy 193.892443 99.165095)
      )
    )
  )
  (zone (net 0) (net_name "") (layer "In3.Cu") (hatch edge 0.508)
    (connect_pads no (clearance 0))
    (min_thickness 0.15) (filled_areas_thickness no)
    (keepout (tracks allowed) (vias allowed) (pads allowed) (copperpour not_allowed) (footprints allowed))
    (fill (thermal_gap 0.3) (thermal_bridge_width 0.2))
    (polygon
      (pts
        (xy 196.93 85.059)
        (xy 196.909043 84.95364)
        (xy 196.849361 84.864319)
        (xy 196.76004 84.804637)
        (xy 196.65468 84.78368)
        (xy 196.54932 84.804637)
        (xy 196.459999 84.864319)
        (xy 196.400317 84.95364)
        (xy 196.37936 85.059)
        (xy 196.400317 85.16436)
        (xy 196.459999 85.253681)
        (xy 196.54932 85.313363)
        (xy 196.65468 85.33432)
        (xy 196.76004 85.313363)
        (xy 196.849361 85.253681)
        (xy 196.909043 85.16436)
      )
    )
  )
  (zone (net 0) (net_name "") (layer "In3.Cu") (hatch edge 0.508)
    (connect_pads no (clearance 0))
    (min_thickness 0.15) (filled_areas_thickness no)
    (keepout (tracks allowed) (vias allowed) (pads allowed) (copperpour not_allowed) (footprints allowed))
    (fill (thermal_gap 0.3) (thermal_bridge_width 0.2))
    (polygon
      (pts
        (xy 178.91196 79.042363)
        (xy 178.891003 78.937003)
        (xy 178.831321 78.847682)
        (xy 178.742 78.788)
        (xy 178.63664 78.767043)
        (xy 178.53128 78.788)
        (xy 178.441959 78.847682)
        (xy 178.382277 78.937003)
        (xy 178.36132 79.042363)
        (xy 178.382277 79.147723)
        (xy 178.441959 79.237044)
        (xy 178.53128 79.296726)
        (xy 178.63664 79.317683)
        (xy 178.742 79.296726)
        (xy 178.831321 79.237044)
        (xy 178.891003 79.147723)
      )
    )
  )
  (zone (net 0) (net_name "") (layer "In3.Cu") (hatch edge 0.508)
    (connect_pads no (clearance 0))
    (min_thickness 0.15) (filled_areas_thickness no)
    (keepout (tracks allowed) (vias allowed) (pads allowed) (copperpour not_allowed) (footprints allowed))
    (fill (thermal_gap 0.3) (thermal_bridge_width 0.2))
    (polygon
      (pts
        (xy 189.90864 84.066)
        (xy 189.887683 83.96064)
        (xy 189.828001 83.871319)
        (xy 189.73868 83.811637)
        (xy 189.63332 83.79068)
        (xy 189.52796 83.811637)
        (xy 189.438639 83.871319)
        (xy 189.378957 83.96064)
        (xy 189.358 84.066)
        (xy 189.378957 84.17136)
        (xy 189.438639 84.260681)
        (xy 189.52796 84.320363)
        (xy 189.63332 84.34132)
        (xy 189.73868 84.320363)
        (xy 189.828001 84.260681)
        (xy 189.887683 84.17136)
      )
    )
  )
  (zone (net 0) (net_name "") (layer "In3.Cu") (hatch edge 0.508)
    (connect_pads no (clearance 0))
    (min_thickness 0.15) (filled_areas_thickness no)
    (keepout (tracks allowed) (vias allowed) (pads allowed) (copperpour not_allowed) (footprints allowed))
    (fill (thermal_gap 0.3) (thermal_bridge_width 0.2))
    (polygon
      (pts
        (xy 169.624957 83.55164)
        (xy 169.604 83.44628)
        (xy 169.544318 83.356959)
        (xy 169.454997 83.297277)
        (xy 169.349637 83.27632)
        (xy 169.244277 83.297277)
        (xy 169.154956 83.356959)
        (xy 169.095274 83.44628)
        (xy 169.074317 83.55164)
        (xy 169.095274 83.657)
        (xy 169.154956 83.746321)
        (xy 169.244277 83.806003)
        (xy 169.349637 83.82696)
        (xy 169.454997 83.806003)
        (xy 169.544318 83.746321)
        (xy 169.604 83.657)
      )
    )
  )
  (zone (net 0) (net_name "") (layer "In3.Cu") (hatch edge 0.508)
    (connect_pads no (clearance 0))
    (min_thickness 0.15) (filled_areas_thickness no)
    (keepout (tracks allowed) (vias allowed) (pads allowed) (copperpour not_allowed) (footprints allowed))
    (fill (thermal_gap 0.3) (thermal_bridge_width 0.2))
    (polygon
      (pts
        (xy 195.794314 80.064181)
        (xy 195.773357 79.958821)
        (xy 195.713675 79.8695)
        (xy 195.624354 79.809818)
        (xy 195.518994 79.788861)
        (xy 195.413634 79.809818)
        (xy 195.324313 79.8695)
        (xy 195.264631 79.958821)
        (xy 195.243674 80.064181)
        (xy 195.264631 80.169541)
        (xy 195.324313 80.258862)
        (xy 195.413634 80.318544)
        (xy 195.518994 80.339501)
        (xy 195.624354 80.318544)
        (xy 195.713675 80.258862)
        (xy 195.773357 80.169541)
      )
    )
  )
  (zone (net 0) (net_name "") (layer "In3.Cu") (hatch edge 0.508)
    (connect_pads no (clearance 0))
    (min_thickness 0.15) (filled_areas_thickness no)
    (keepout (tracks allowed) (vias allowed) (pads allowed) (copperpour not_allowed) (footprints allowed))
    (fill (thermal_gap 0.3) (thermal_bridge_width 0.2))
    (polygon
      (pts
        (xy 185.770957 80.08836)
        (xy 185.75 79.983)
        (xy 185.690318 79.893679)
        (xy 185.600997 79.833997)
        (xy 185.495637 79.81304)
        (xy 185.390277 79.833997)
        (xy 185.300956 79.893679)
        (xy 185.241274 79.983)
        (xy 185.220317 80.08836)
        (xy 185.241274 80.19372)
        (xy 185.300956 80.283041)
        (xy 185.390277 80.342723)
        (xy 185.495637 80.36368)
        (xy 185.600997 80.342723)
        (xy 185.690318 80.283041)
        (xy 185.75 80.19372)
      )
    )
  )
  (zone (net 0) (net_name "") (layer "In3.Cu") (hatch edge 0.508)
    (connect_pads no (clearance 0))
    (min_thickness 0.15) (filled_areas_thickness no)
    (keepout (tracks allowed) (vias allowed) (pads allowed) (copperpour not_allowed) (footprints allowed))
    (fill (thermal_gap 0.3) (thermal_bridge_width 0.2))
    (polygon
      (pts
        (xy 185.767001 80.087319)
        (xy 185.746044 79.981959)
        (xy 185.686362 79.892638)
        (xy 185.597041 79.832956)
        (xy 185.491681 79.811999)
        (xy 185.386321 79.832956)
        (xy 185.297 79.892638)
        (xy 185.237318 79.981959)
        (xy 185.216361 80.087319)
        (xy 185.237318 80.192679)
        (xy 185.297 80.282)
        (xy 185.386321 80.341682)
        (xy 185.491681 80.362639)
        (xy 185.597041 80.341682)
        (xy 185.686362 80.282)
        (xy 185.746044 80.192679)
      )
    )
  )
  (zone (net 0) (net_name "") (layer "In3.Cu") (hatch edge 0.508)
    (connect_pads no (clearance 0))
    (min_thickness 0.15) (filled_areas_thickness no)
    (keepout (tracks allowed) (vias allowed) (pads allowed) (copperpour not_allowed) (footprints allowed))
    (fill (thermal_gap 0.3) (thermal_bridge_width 0.2))
    (polygon
      (pts
        (xy 197.080639 81.068319)
        (xy 197.059682 80.962959)
        (xy 197 80.873638)
        (xy 196.910679 80.813956)
        (xy 196.805319 80.792999)
        (xy 196.699959 80.813956)
        (xy 196.610638 80.873638)
        (xy 196.550956 80.962959)
        (xy 196.529999 81.068319)
        (xy 196.550956 81.173679)
        (xy 196.610638 81.263)
        (xy 196.699959 81.322682)
        (xy 196.805319 81.343639)
        (xy 196.910679 81.322682)
        (xy 197 81.263)
        (xy 197.059682 81.173679)
      )
    )
  )
  (zone (net 0) (net_name "") (layer "In3.Cu") (hatch edge 0.508)
    (connect_pads no (clearance 0))
    (min_thickness 0.15) (filled_areas_thickness no)
    (keepout (tracks allowed) (vias allowed) (pads allowed) (copperpour not_allowed) (footprints allowed))
    (fill (thermal_gap 0.3) (thermal_bridge_width 0.2))
    (polygon
      (pts
        (xy 177.88996 80.085363)
        (xy 177.869003 79.980003)
        (xy 177.809321 79.890682)
        (xy 177.72 79.831)
        (xy 177.61464 79.810043)
        (xy 177.50928 79.831)
        (xy 177.419959 79.890682)
        (xy 177.360277 79.980003)
        (xy 177.33932 80.085363)
        (xy 177.360277 80.190723)
        (xy 177.419959 80.280044)
        (xy 177.50928 80.339726)
        (xy 177.61464 80.360683)
        (xy 177.72 80.339726)
        (xy 177.809321 80.280044)
        (xy 177.869003 80.190723)
      )
    )
  )
  (zone (net 0) (net_name "") (layer "In3.Cu") (hatch edge 0.508)
    (connect_pads no (clearance 0))
    (min_thickness 0.15) (filled_areas_thickness no)
    (keepout (tracks allowed) (vias allowed) (pads allowed) (copperpour not_allowed) (footprints allowed))
    (fill (thermal_gap 0.3) (thermal_bridge_width 0.2))
    (polygon
      (pts
        (xy 191.91232 96.04732)
        (xy 191.891363 95.94196)
        (xy 191.831681 95.852639)
        (xy 191.74236 95.792957)
        (xy 191.637 95.772)
        (xy 191.53164 95.792957)
        (xy 191.442319 95.852639)
        (xy 191.382637 95.94196)
        (xy 191.36168 96.04732)
        (xy 191.382637 96.15268)
        (xy 191.442319 96.242001)
        (xy 191.53164 96.301683)
        (xy 191.637 96.32264)
        (xy 191.74236 96.301683)
        (xy 191.831681 96.242001)
        (xy 191.891363 96.15268)
      )
    )
  )
  (zone (net 0) (net_name "") (layer "In3.Cu") (hatch edge 0.508)
    (connect_pads no (clearance 0))
    (min_thickness 0.15) (filled_areas_thickness no)
    (keepout (tracks allowed) (vias allowed) (pads allowed) (copperpour not_allowed) (footprints allowed))
    (fill (thermal_gap 0.3) (thermal_bridge_width 0.2))
    (polygon
      (pts
        (xy 194.911639 93.061681)
        (xy 194.890682 92.956321)
        (xy 194.831 92.867)
        (xy 194.741679 92.807318)
        (xy 194.636319 92.786361)
        (xy 194.530959 92.807318)
        (xy 194.441638 92.867)
        (xy 194.381956 92.956321)
        (xy 194.360999 93.061681)
        (xy 194.381956 93.167041)
        (xy 194.441638 93.256362)
        (xy 194.530959 93.316044)
        (xy 194.636319 93.337001)
        (xy 194.741679 93.316044)
        (xy 194.831 93.256362)
        (xy 194.890682 93.167041)
      )
    )
  )
  (zone (net 0) (net_name "") (layer "In3.Cu") (hatch edge 0.508)
    (connect_pads no (clearance 0))
    (min_thickness 0.15) (filled_areas_thickness no)
    (keepout (tracks allowed) (vias allowed) (pads allowed) (copperpour not_allowed) (footprints allowed))
    (fill (thermal_gap 0.3) (thermal_bridge_width 0.2))
    (polygon
      (pts
        (xy 192.91032 96.05132)
        (xy 192.889363 95.94596)
        (xy 192.829681 95.856639)
        (xy 192.74036 95.796957)
        (xy 192.635 95.776)
        (xy 192.52964 95.796957)
        (xy 192.440319 95.856639)
        (xy 192.380637 95.94596)
        (xy 192.35968 96.05132)
        (xy 192.380637 96.15668)
        (xy 192.440319 96.246001)
        (xy 192.52964 96.305683)
        (xy 192.635 96.32664)
        (xy 192.74036 96.305683)
        (xy 192.829681 96.246001)
        (xy 192.889363 96.15668)
      )
    )
  )
  (zone (net 306) (net_name "1V2_SYS") (layer "In3.Cu") (hatch edge 0.508)
    (priority 3)
    (connect_pads (clearance 0.12))
    (min_thickness 0.254) (filled_areas_thickness no)
    (fill yes (thermal_gap 0.508) (thermal_bridge_width 0.508))
    (polygon
      (pts
        (xy 199 110.9)
        (xy 186.525 123.4)
        (xy 173.849587 123.34481)
        (xy 172.45 121.9)
        (xy 158.55 121.890191)
        (xy 157.2 123.25)
        (xy 152.075 123.25)
        (xy 152.075 116.05)
        (xy 172.1 116.05)
        (xy 179.775 108.375)
        (xy 188 108.375)
        (xy 190.65 105.7)
        (xy 190.65 104.55)
        (xy 191.8 104.55)
        (xy 199 104.55)
      )
    )
  )
  (zone (net 0) (net_name "") (layer "In3.Cu") (hatch edge 0.508)
    (connect_pads no (clearance 0))
    (min_thickness 0.15) (filled_areas_thickness no)
    (keepout (tracks allowed) (vias allowed) (pads allowed) (copperpour not_allowed) (footprints allowed))
    (fill (thermal_gap 0.3) (thermal_bridge_width 0.2))
    (polygon
      (pts
        (xy 176.911001 78.042681)
        (xy 176.890044 77.937321)
        (xy 176.830362 77.848)
        (xy 176.741041 77.788318)
        (xy 176.635681 77.767361)
        (xy 176.530321 77.788318)
        (xy 176.441 77.848)
        (xy 176.381318 77.937321)
        (xy 176.360361 78.042681)
        (xy 176.381318 78.148041)
        (xy 176.441 78.237362)
        (xy 176.530321 78.297044)
        (xy 176.635681 78.318001)
        (xy 176.741041 78.297044)
        (xy 176.830362 78.237362)
        (xy 176.890044 78.148041)
      )
    )
  )
  (zone (net 0) (net_name "") (layer "In3.Cu") (hatch edge 0.508)
    (connect_pads no (clearance 0))
    (min_thickness 0.15) (filled_areas_thickness no)
    (keepout (tracks allowed) (vias allowed) (pads allowed) (copperpour not_allowed) (footprints allowed))
    (fill (thermal_gap 0.3) (thermal_bridge_width 0.2))
    (polygon
      (pts
        (xy 188.912001 82.059681)
        (xy 188.891044 81.954321)
        (xy 188.831362 81.865)
        (xy 188.742041 81.805318)
        (xy 188.636681 81.784361)
        (xy 188.531321 81.805318)
        (xy 188.442 81.865)
        (xy 188.382318 81.954321)
        (xy 188.361361 82.059681)
        (xy 188.382318 82.165041)
        (xy 188.442 82.254362)
        (xy 188.531321 82.314044)
        (xy 188.636681 82.335001)
        (xy 188.742041 82.314044)
        (xy 188.831362 82.254362)
        (xy 188.891044 82.165041)
      )
    )
  )
  (zone (net 0) (net_name "") (layer "In3.Cu") (hatch edge 0.508)
    (connect_pads no (clearance 0))
    (min_thickness 0.15) (filled_areas_thickness no)
    (keepout (tracks allowed) (vias allowed) (pads allowed) (copperpour not_allowed) (footprints allowed))
    (fill (thermal_gap 0.3) (thermal_bridge_width 0.2))
    (polygon
      (pts
        (xy 182.910001 81.063681)
        (xy 182.889044 80.958321)
        (xy 182.829362 80.869)
        (xy 182.740041 80.809318)
        (xy 182.634681 80.788361)
        (xy 182.529321 80.809318)
        (xy 182.44 80.869)
        (xy 182.380318 80.958321)
        (xy 182.359361 81.063681)
        (xy 182.380318 81.169041)
        (xy 182.44 81.258362)
        (xy 182.529321 81.318044)
        (xy 182.634681 81.339001)
        (xy 182.740041 81.318044)
        (xy 182.829362 81.258362)
        (xy 182.889044 81.169041)
      )
    )
  )
  (zone (net 0) (net_name "") (layer "In3.Cu") (hatch edge 0.508)
    (connect_pads no (clearance 0))
    (min_thickness 0.15) (filled_areas_thickness no)
    (keepout (tracks allowed) (vias allowed) (pads allowed) (copperpour not_allowed) (footprints allowed))
    (fill (thermal_gap 0.3) (thermal_bridge_width 0.2))
    (polygon
      (pts
        (xy 194.91532 99.059735)
        (xy 194.894363 98.954375)
        (xy 194.834681 98.865054)
        (xy 194.74536 98.805372)
        (xy 194.64 98.784415)
        (xy 194.53464 98.805372)
        (xy 194.445319 98.865054)
        (xy 194.385637 98.954375)
        (xy 194.36468 99.059735)
        (xy 194.385637 99.165095)
        (xy 194.445319 99.254416)
        (xy 194.53464 99.314098)
        (xy 194.64 99.335055)
        (xy 194.74536 99.314098)
        (xy 194.834681 99.254416)
        (xy 194.894363 99.165095)
      )
    )
  )
  (zone (net 0) (net_name "") (layer "In3.Cu") (hatch edge 0.508)
    (connect_pads no (clearance 0))
    (min_thickness 0.15) (filled_areas_thickness no)
    (keepout (tracks allowed) (vias allowed) (pads allowed) (copperpour not_allowed) (footprints allowed))
    (fill (thermal_gap 0.3) (thermal_bridge_width 0.2))
    (polygon
      (pts
        (xy 192.90996 102.054363)
        (xy 192.889003 101.949003)
        (xy 192.829321 101.859682)
        (xy 192.74 101.8)
        (xy 192.63464 101.779043)
        (xy 192.52928 101.8)
        (xy 192.439959 101.859682)
        (xy 192.380277 101.949003)
        (xy 192.35932 102.054363)
        (xy 192.380277 102.159723)
        (xy 192.439959 102.249044)
        (xy 192.52928 102.308726)
        (xy 192.63464 102.329683)
        (xy 192.74 102.308726)
        (xy 192.829321 102.249044)
        (xy 192.889003 102.159723)
      )
    )
  )
  (zone (net 9) (net_name "GND") (layer "In4.Cu") (hatch edge 0.508)
    (connect_pads yes (clearance 0.12))
    (min_thickness 0.15) (filled_areas_thickness no)
    (fill yes (thermal_gap 0.508) (thermal_bridge_width 0.15) (smoothing fillet) (radius 0.5))
    (polygon
      (pts
        (xy 259.886328 46.010016)
        (xy 259.886328 136.010016)
        (xy 106.986328 136.010016)
        (xy 106.986328 46.010016)
      )
    )
  )
  (zone (net 0) (net_name "") (layer "In5.Cu") (hatch edge 0.508)
    (connect_pads (clearance 0))
    (min_thickness 0.254) (filled_areas_thickness no)
    (keepout (tracks allowed) (vias allowed) (pads allowed) (copperpour not_allowed) (footprints allowed))
    (fill (thermal_gap 0.508) (thermal_bridge_width 0.508))
    (polygon
      (pts
        (xy 189.636328 93.060008)
        (xy 188.636328 93.060008)
        (xy 187.1 91.55)
        (xy 177 91.55)
        (xy 173.7 94.9)
        (xy 173.7 101.1)
        (xy 172.9 101.9)
        (xy 170.7 101.9)
        (xy 170 102.6)
        (xy 160 102.6)
        (xy 159.204501 103.395499)
        (xy 157.7 103.395499)
        (xy 157.104501 102.8)
        (xy 153.9 102.8)
        (xy 152 104.7)
        (xy 152 110.3)
        (xy 151.6 110.7)
        (xy 149.5 110.7)
        (xy 149.5 103.4)
        (xy 152.4 100.5)
        (xy 167.7 100.5)
        (xy 170.556336 97.643664)
        (xy 170.556336 93.9)
        (xy 175.9 88.6)
        (xy 190.206328 88.630008)
        (xy 190.636328 89.060008)
        (xy 190.636328 90.060008)
        (xy 189.636328 91.060008)
      )
    )
  )
  (zone (net 0) (net_name "") (layer "In5.Cu") (hatch edge 0.508)
    (connect_pads (clearance 0))
    (min_thickness 0.254) (filled_areas_thickness no)
    (keepout (tracks allowed) (vias allowed) (pads allowed) (copperpour not_allowed) (footprints allowed))
    (fill (thermal_gap 0.508) (thermal_bridge_width 0.508))
    (polygon
      (pts
        (xy 197.336328 58.7)
        (xy 208.1 58.7)
        (xy 208.1 54.4)
        (xy 208.7 53.813672)
        (xy 217.7 53.813672)
        (xy 218.336328 54.4)
        (xy 218.336328 63)
        (xy 222.2 63)
        (xy 226.4 58.8)
        (xy 226.4 54.1)
        (xy 226.8 53.7)
        (xy 236.9 53.7)
        (xy 237.4 54.2)
        (xy 237.4 68)
        (xy 217.6 87.8)
        (xy 193.5 87.8)
        (xy 191.9 86.2)
        (xy 187.5 86.2)
        (xy 186.2 84.9)
        (xy 177.9 84.9)
        (xy 176.8 83.8)
        (xy 161.5 83.8)
        (xy 156.7 79.1)
        (xy 143.9 79.1)
        (xy 132.736328 67.9)
        (xy 132.736328 54.3)
        (xy 133.2 53.813672)
        (xy 144 53.813672)
        (xy 144.5 54.3)
        (xy 144.5 58.3)
        (xy 150.3 64.1)
        (xy 151.9 64.1)
        (xy 151.9 54.3)
        (xy 152.4 53.813672)
        (xy 176.3 53.813672)
        (xy 179.886328 57.4)
        (xy 183.7 57.4)
        (xy 187.3 61)
        (xy 190.2 61)
        (xy 193 58.2)
        (xy 193 53.9)
        (xy 193.4 53.5)
        (xy 196.9 53.5)
        (xy 197.336328 53.9)
      )
    )
  )
  (zone (net 0) (net_name "") (layer "In5.Cu") (hatch edge 0.508)
    (connect_pads (clearance 0))
    (min_thickness 0.254) (filled_areas_thickness no)
    (keepout (tracks allowed) (vias allowed) (pads allowed) (copperpour not_allowed) (footprints allowed))
    (fill (thermal_gap 0.508) (thermal_bridge_width 0.508))
    (polygon
      (pts
        (xy 251.9 85.8)
        (xy 251.9 95.7)
        (xy 252.9 96.7)
        (xy 254.4 96.7)
        (xy 256.4 98.7)
        (xy 257.8 98.7)
        (xy 258.2 99.1)
        (xy 258.2 100.7)
        (xy 257.9 101)
        (xy 254.4 101)
        (xy 252.8 99.4)
        (xy 250.8 99.4)
        (xy 250 100.2)
        (xy 250 105.1)
        (xy 248.2 106.9)
        (xy 242 106.9)
        (xy 240.9 105.8)
        (xy 231.8 105.8)
        (xy 230.5 104.5)
        (xy 213.3 104.4)
        (xy 206.6 111.1)
        (xy 181.1 111.1)
        (xy 174.9 104.9)
        (xy 174.9 101.3)
        (xy 175.6 100.6)
        (xy 175.6 94)
        (xy 176.7 92.9)
        (xy 179 92.9)
        (xy 185 92.9)
        (xy 185.8 93.7)
        (xy 190.4 93.7)
        (xy 191.2 92.9)
        (xy 197.9 92.9)
        (xy 201.9 88.9)
        (xy 205.725 88.9)
        (xy 209.75 88.9)
        (xy 209.9 89.05)
        (xy 210.45 89.05)
        (xy 210.6 88.9)
        (xy 236.9 88.9)
        (xy 240.2 85.6)
        (xy 240.9 85.6)
        (xy 242.300942 84.2)
        (xy 250.3 84.2)
      )
    )
  )
  (zone (net 143) (net_name "3V3_SYS") (layer "In5.Cu") (hatch edge 0.508)
    (priority 2)
    (connect_pads no (clearance 0.15))
    (min_thickness 0.1) (filled_areas_thickness no)
    (fill yes (thermal_gap 0.3) (thermal_bridge_width 0.12))
    (polygon
      (pts
        (xy 259.89 135.955)
        (xy 106.963 135.954)
        (xy 106.963 109.85)
        (xy 106.968 107.643)
        (xy 111.25 107.65)
        (xy 130 126.2)
        (xy 199.45 126.25)
        (xy 205.05 120.65)
        (xy 209.4 120.65)
        (xy 216.5 113.65)
        (xy 238.7 113.65)
        (xy 240.35 115.3)
        (xy 240.35 119.6)
        (xy 246.95 126.2)
        (xy 255.4 126.2)
        (xy 256.55 125.05)
        (xy 256.55 100.99)
        (xy 257.9 100.99)
        (xy 258.12 100.77)
        (xy 258.12 99.07)
        (xy 257.78 98.73)
        (xy 256.54 98.72)
        (xy 256.543957 90.9)
        (xy 256.35 90.699997)
        (xy 254.7 90.7)
        (xy 254.593881 90.599035)
        (xy 254.59467 89.2)
        (xy 254.75 89.05)
        (xy 256.35 89.05)
        (xy 256.544869 88.850022)
        (xy 256.55 78.45)
        (xy 253.2 75.1)
        (xy 253.2 71.6)
        (xy 259.897 71.604)
      )
    )
  )
  (zone (net 9) (net_name "GND") (layers "In5.Cu" "In7.Cu" "In9.Cu") (hatch edge 0.508)
    (connect_pads no (clearance 0.12))
    (min_thickness 0.15) (filled_areas_thickness no)
    (fill yes (thermal_gap 0.5) (thermal_bridge_width 0.15) (smoothing fillet) (radius 1))
    (polygon
      (pts
        (xy 259.9 135.95)
        (xy 107 135.95)
        (xy 107 46)
        (xy 152.15 46)
        (xy 192 46)
        (xy 201.6 46)
        (xy 259.9 46)
      )
    )
  )
  (zone (net 0) (net_name "") (layer "In6.Cu") (hatch edge 0.508)
    (connect_pads no (clearance 0))
    (min_thickness 0.15) (filled_areas_thickness no)
    (keepout (tracks allowed) (vias allowed) (pads allowed) (copperpour not_allowed) (footprints allowed))
    (fill (thermal_gap 0.3) (thermal_bridge_width 0.2))
    (polygon
      (pts
        (xy 194.930639 79.060319)
        (xy 194.909682 78.954959)
        (xy 194.85 78.865638)
        (xy 194.760679 78.805956)
        (xy 194.655319 78.784999)
        (xy 194.549959 78.805956)
        (xy 194.460638 78.865638)
        (xy 194.400956 78.954959)
        (xy 194.379999 79.060319)
        (xy 194.400956 79.165679)
        (xy 194.460638 79.255)
        (xy 194.549959 79.314682)
        (xy 194.655319 79.335639)
        (xy 194.760679 79.314682)
        (xy 194.85 79.255)
        (xy 194.909682 79.165679)
      )
    )
  )
  (zone (net 0) (net_name "") (layer "In6.Cu") (hatch edge 0.508)
    (connect_pads no (clearance 0))
    (min_thickness 0.15) (filled_areas_thickness no)
    (keepout (tracks allowed) (vias allowed) (pads allowed) (copperpour not_allowed) (footprints allowed))
    (fill (thermal_gap 0.3) (thermal_bridge_width 0.2))
    (polygon
      (pts
        (xy 192.929 79.064)
        (xy 192.908043 78.95864)
        (xy 192.848361 78.869319)
        (xy 192.75904 78.809637)
        (xy 192.65368 78.78868)
        (xy 192.54832 78.809637)
        (xy 192.458999 78.869319)
        (xy 192.399317 78.95864)
        (xy 192.37836 79.064)
        (xy 192.399317 79.16936)
        (xy 192.458999 79.258681)
        (xy 192.54832 79.318363)
        (xy 192.65368 79.33932)
        (xy 192.75904 79.318363)
        (xy 192.848361 79.258681)
        (xy 192.908043 79.16936)
      )
    )
  )
  (zone (net 0) (net_name "") (layer "In6.Cu") (hatch edge 0.508)
    (connect_pads no (clearance 0))
    (min_thickness 0.15) (filled_areas_thickness no)
    (keepout (tracks allowed) (vias allowed) (pads allowed) (copperpour not_allowed) (footprints allowed))
    (fill (thermal_gap 0.3) (thermal_bridge_width 0.2))
    (polygon
      (pts
        (xy 194.929 77.06)
        (xy 194.908043 76.95464)
        (xy 194.848361 76.865319)
        (xy 194.75904 76.805637)
        (xy 194.65368 76.78468)
        (xy 194.54832 76.805637)
        (xy 194.458999 76.865319)
        (xy 194.399317 76.95464)
        (xy 194.37836 77.06)
        (xy 194.399317 77.16536)
        (xy 194.458999 77.254681)
        (xy 194.54832 77.314363)
        (xy 194.65368 77.33532)
        (xy 194.75904 77.314363)
        (xy 194.848361 77.254681)
        (xy 194.908043 77.16536)
      )
    )
  )
  (zone (net 0) (net_name "") (layer "In6.Cu") (hatch edge 0.508)
    (connect_pads no (clearance 0))
    (min_thickness 0.15) (filled_areas_thickness no)
    (keepout (tracks allowed) (vias allowed) (pads allowed) (copperpour not_allowed) (footprints allowed))
    (fill (thermal_gap 0.3) (thermal_bridge_width 0.2))
    (polygon
      (pts
        (xy 194.930639 82.060319)
        (xy 194.909682 81.954959)
        (xy 194.85 81.865638)
        (xy 194.760679 81.805956)
        (xy 194.655319 81.784999)
        (xy 194.549959 81.805956)
        (xy 194.460638 81.865638)
        (xy 194.400956 81.954959)
        (xy 194.379999 82.060319)
        (xy 194.400956 82.165679)
        (xy 194.460638 82.255)
        (xy 194.549959 82.314682)
        (xy 194.655319 82.335639)
        (xy 194.760679 82.314682)
        (xy 194.85 82.255)
        (xy 194.909682 82.165679)
      )
    )
  )
  (zone (net 0) (net_name "") (layer "In6.Cu") (hatch edge 0.508)
    (connect_pads no (clearance 0))
    (min_thickness 0.15) (filled_areas_thickness no)
    (keepout (tracks allowed) (vias allowed) (pads allowed) (copperpour not_allowed) (footprints allowed))
    (fill (thermal_gap 0.3) (thermal_bridge_width 0.2))
    (polygon
      (pts
        (xy 193.706 76.96)
        (xy 193.685043 76.85464)
        (xy 193.625361 76.765319)
        (xy 193.53604 76.705637)
        (xy 193.43068 76.68468)
        (xy 193.32532 76.705637)
        (xy 193.235999 76.765319)
        (xy 193.176317 76.85464)
        (xy 193.15536 76.96)
        (xy 193.176317 77.06536)
        (xy 193.235999 77.154681)
        (xy 193.32532 77.214363)
        (xy 193.43068 77.23532)
        (xy 193.53604 77.214363)
        (xy 193.625361 77.154681)
        (xy 193.685043 77.06536)
      )
    )
  )
  (zone (net 0) (net_name "") (layer "In6.Cu") (hatch edge 0.508)
    (connect_pads no (clearance 0))
    (min_thickness 0.15) (filled_areas_thickness no)
    (keepout (tracks allowed) (vias allowed) (pads allowed) (copperpour not_allowed) (footprints allowed))
    (fill (thermal_gap 0.3) (thermal_bridge_width 0.2))
    (polygon
      (pts
        (xy 188.935 84.061)
        (xy 188.914043 83.95564)
        (xy 188.854361 83.866319)
        (xy 188.76504 83.806637)
        (xy 188.65968 83.78568)
        (xy 188.55432 83.806637)
        (xy 188.464999 83.866319)
        (xy 188.405317 83.95564)
        (xy 188.38436 84.061)
        (xy 188.405317 84.16636)
        (xy 188.464999 84.255681)
        (xy 188.55432 84.315363)
        (xy 188.65968 84.33632)
        (xy 188.76504 84.315363)
        (xy 188.854361 84.255681)
        (xy 188.914043 84.16636)
      )
    )
  )
  (zone (net 0) (net_name "") (layer "In6.Cu") (hatch edge 0.508)
    (connect_pads no (clearance 0))
    (min_thickness 0.15) (filled_areas_thickness no)
    (keepout (tracks allowed) (vias allowed) (pads allowed) (copperpour not_allowed) (footprints allowed))
    (fill (thermal_gap 0.3) (thermal_bridge_width 0.2))
    (polygon
      (pts
        (xy 194.94 78.062)
        (xy 194.919043 77.95664)
        (xy 194.859361 77.867319)
        (xy 194.77004 77.807637)
        (xy 194.66468 77.78668)
        (xy 194.55932 77.807637)
        (xy 194.469999 77.867319)
        (xy 194.410317 77.95664)
        (xy 194.38936 78.062)
        (xy 194.410317 78.16736)
        (xy 194.469999 78.256681)
        (xy 194.55932 78.316363)
        (xy 194.66468 78.33732)
        (xy 194.77004 78.316363)
        (xy 194.859361 78.256681)
        (xy 194.919043 78.16736)
      )
    )
  )
  (zone (net 0) (net_name "") (layer "In6.Cu") (hatch edge 0.508)
    (connect_pads no (clearance 0))
    (min_thickness 0.15) (filled_areas_thickness no)
    (keepout (tracks allowed) (vias allowed) (pads allowed) (copperpour not_allowed) (footprints allowed))
    (fill (thermal_gap 0.3) (thermal_bridge_width 0.2))
    (polygon
      (pts
        (xy 193.932 81.059)
        (xy 193.911043 80.95364)
        (xy 193.851361 80.864319)
        (xy 193.76204 80.804637)
        (xy 193.65668 80.78368)
        (xy 193.55132 80.804637)
        (xy 193.461999 80.864319)
        (xy 193.402317 80.95364)
        (xy 193.38136 81.059)
        (xy 193.402317 81.16436)
        (xy 193.461999 81.253681)
        (xy 193.55132 81.313363)
        (xy 193.65668 81.33432)
        (xy 193.76204 81.313363)
        (xy 193.851361 81.253681)
        (xy 193.911043 81.16436)
      )
    )
  )
  (zone (net 0) (net_name "") (layer "In6.Cu") (hatch edge 0.508)
    (connect_pads no (clearance 0))
    (min_thickness 0.15) (filled_areas_thickness no)
    (keepout (tracks allowed) (vias allowed) (pads allowed) (copperpour not_allowed) (footprints allowed))
    (fill (thermal_gap 0.3) (thermal_bridge_width 0.2))
    (polygon
      (pts
        (xy 187.929 84.057)
        (xy 187.908043 83.95164)
        (xy 187.848361 83.862319)
        (xy 187.75904 83.802637)
        (xy 187.65368 83.78168)
        (xy 187.54832 83.802637)
        (xy 187.458999 83.862319)
        (xy 187.399317 83.95164)
        (xy 187.37836 84.057)
        (xy 187.399317 84.16236)
        (xy 187.458999 84.251681)
        (xy 187.54832 84.311363)
        (xy 187.65368 84.33232)
        (xy 187.75904 84.311363)
        (xy 187.848361 84.251681)
        (xy 187.908043 84.16236)
      )
    )
  )
  (zone (net 0) (net_name "") (layer "In6.Cu") (hatch edge 0.508)
    (connect_pads no (clearance 0))
    (min_thickness 0.15) (filled_areas_thickness no)
    (keepout (tracks allowed) (vias allowed) (pads allowed) (copperpour not_allowed) (footprints allowed))
    (fill (thermal_gap 0.3) (thermal_bridge_width 0.2))
    (polygon
      (pts
        (xy 192.929 78.059)
        (xy 192.908043 77.95364)
        (xy 192.848361 77.864319)
        (xy 192.75904 77.804637)
        (xy 192.65368 77.78368)
        (xy 192.54832 77.804637)
        (xy 192.458999 77.864319)
        (xy 192.399317 77.95364)
        (xy 192.37836 78.059)
        (xy 192.399317 78.16436)
        (xy 192.458999 78.253681)
        (xy 192.54832 78.313363)
        (xy 192.65368 78.33432)
        (xy 192.75904 78.313363)
        (xy 192.848361 78.253681)
        (xy 192.908043 78.16436)
      )
    )
  )
  (zone (net 0) (net_name "") (layer "In6.Cu") (hatch edge 0.508)
    (connect_pads no (clearance 0))
    (min_thickness 0.15) (filled_areas_thickness no)
    (keepout (tracks allowed) (vias allowed) (pads allowed) (copperpour not_allowed) (footprints allowed))
    (fill (thermal_gap 0.3) (thermal_bridge_width 0.2))
    (polygon
      (pts
        (xy 194.93032 85.06168)
        (xy 194.909363 84.95632)
        (xy 194.849681 84.866999)
        (xy 194.76036 84.807317)
        (xy 194.655 84.78636)
        (xy 194.54964 84.807317)
        (xy 194.460319 84.866999)
        (xy 194.400637 84.95632)
        (xy 194.37968 85.06168)
        (xy 194.400637 85.16704)
        (xy 194.460319 85.256361)
        (xy 194.54964 85.316043)
        (xy 194.655 85.337)
        (xy 194.76036 85.316043)
        (xy 194.849681 85.256361)
        (xy 194.909363 85.16704)
      )
    )
  )
  (zone (net 0) (net_name "") (layer "In6.Cu") (hatch edge 0.508)
    (connect_pads no (clearance 0))
    (min_thickness 0.15) (filled_areas_thickness no)
    (keepout (tracks allowed) (vias allowed) (pads allowed) (copperpour not_allowed) (footprints allowed))
    (fill (thermal_gap 0.3) (thermal_bridge_width 0.2))
    (polygon
      (pts
        (xy 195.929 78.062)
        (xy 195.908043 77.95664)
        (xy 195.848361 77.867319)
        (xy 195.75904 77.807637)
        (xy 195.65368 77.78668)
        (xy 195.54832 77.807637)
        (xy 195.458999 77.867319)
        (xy 195.399317 77.95664)
        (xy 195.37836 78.062)
        (xy 195.399317 78.16736)
        (xy 195.458999 78.256681)
        (xy 195.54832 78.316363)
        (xy 195.65368 78.33732)
        (xy 195.75904 78.316363)
        (xy 195.848361 78.256681)
        (xy 195.908043 78.16736)
      )
    )
  )
  (zone (net 0) (net_name "") (layer "In6.Cu") (hatch edge 0.508)
    (connect_pads no (clearance 0))
    (min_thickness 0.15) (filled_areas_thickness no)
    (keepout (tracks allowed) (vias allowed) (pads allowed) (copperpour not_allowed) (footprints allowed))
    (fill (thermal_gap 0.3) (thermal_bridge_width 0.2))
    (polygon
      (pts
        (xy 188.933 85.061)
        (xy 188.912043 84.95564)
        (xy 188.852361 84.866319)
        (xy 188.76304 84.806637)
        (xy 188.65768 84.78568)
        (xy 188.55232 84.806637)
        (xy 188.462999 84.866319)
        (xy 188.403317 84.95564)
        (xy 188.38236 85.061)
        (xy 188.403317 85.16636)
        (xy 188.462999 85.255681)
        (xy 188.55232 85.315363)
        (xy 188.65768 85.33632)
        (xy 188.76304 85.315363)
        (xy 188.852361 85.255681)
        (xy 188.912043 85.16636)
      )
    )
  )
  (zone (net 0) (net_name "") (layer "In6.Cu") (hatch edge 0.508)
    (connect_pads no (clearance 0))
    (min_thickness 0.15) (filled_areas_thickness no)
    (keepout (tracks allowed) (vias allowed) (pads allowed) (copperpour not_allowed) (footprints allowed))
    (fill (thermal_gap 0.3) (thermal_bridge_width 0.2))
    (polygon
      (pts
        (xy 192.875957 76.96236)
        (xy 192.855 76.857)
        (xy 192.795318 76.767679)
        (xy 192.705997 76.707997)
        (xy 192.600637 76.68704)
        (xy 192.495277 76.707997)
        (xy 192.405956 76.767679)
        (xy 192.346274 76.857)
        (xy 192.325317 76.96236)
        (xy 192.346274 77.06772)
        (xy 192.405956 77.157041)
        (xy 192.495277 77.216723)
        (xy 192.600637 77.23768)
        (xy 192.705997 77.216723)
        (xy 192.795318 77.157041)
        (xy 192.855 77.06772)
      )
    )
  )
  (zone (net 0) (net_name "") (layer "In6.Cu") (hatch edge 0.508)
    (connect_pads no (clearance 0))
    (min_thickness 0.15) (filled_areas_thickness no)
    (keepout (tracks allowed) (vias allowed) (pads allowed) (copperpour not_allowed) (footprints allowed))
    (fill (thermal_gap 0.3) (thermal_bridge_width 0.2))
    (polygon
      (pts
        (xy 193.929 82.062)
        (xy 193.908043 81.95664)
        (xy 193.848361 81.867319)
        (xy 193.75904 81.807637)
        (xy 193.65368 81.78668)
        (xy 193.54832 81.807637)
        (xy 193.458999 81.867319)
        (xy 193.399317 81.95664)
        (xy 193.37836 82.062)
        (xy 193.399317 82.16736)
        (xy 193.458999 82.256681)
        (xy 193.54832 82.316363)
        (xy 193.65368 82.33732)
        (xy 193.75904 82.316363)
        (xy 193.848361 82.256681)
        (xy 193.908043 82.16736)
      )
    )
  )
  (zone (net 0) (net_name "") (layer "In6.Cu") (hatch edge 0.508)
    (connect_pads no (clearance 0))
    (min_thickness 0.15) (filled_areas_thickness no)
    (keepout (tracks allowed) (vias allowed) (pads allowed) (copperpour not_allowed) (footprints allowed))
    (fill (thermal_gap 0.3) (thermal_bridge_width 0.2))
    (polygon
      (pts
        (xy 185.911731 84.04402)
        (xy 185.890774 83.93866)
        (xy 185.831092 83.849339)
        (xy 185.741771 83.789657)
        (xy 185.636411 83.7687)
        (xy 185.531051 83.789657)
        (xy 185.44173 83.849339)
        (xy 185.382048 83.93866)
        (xy 185.361091 84.04402)
        (xy 185.382048 84.14938)
        (xy 185.44173 84.238701)
        (xy 185.531051 84.298383)
        (xy 185.636411 84.31934)
        (xy 185.741771 84.298383)
        (xy 185.831092 84.238701)
        (xy 185.890774 84.14938)
      )
    )
  )
  (zone (net 0) (net_name "") (layer "In6.Cu") (hatch edge 0.508)
    (connect_pads no (clearance 0))
    (min_thickness 0.15) (filled_areas_thickness no)
    (keepout (tracks allowed) (vias allowed) (pads allowed) (copperpour not_allowed) (footprints allowed))
    (fill (thermal_gap 0.3) (thermal_bridge_width 0.2))
    (polygon
      (pts
        (xy 193.928 80.05)
        (xy 193.907043 79.94464)
        (xy 193.847361 79.855319)
        (xy 193.75804 79.795637)
        (xy 193.65268 79.77468)
        (xy 193.54732 79.795637)
        (xy 193.457999 79.855319)
        (xy 193.398317 79.94464)
        (xy 193.37736 80.05)
        (xy 193.398317 80.15536)
        (xy 193.457999 80.244681)
        (xy 193.54732 80.304363)
        (xy 193.65268 80.32532)
        (xy 193.75804 80.304363)
        (xy 193.847361 80.244681)
        (xy 193.907043 80.15536)
      )
    )
  )
  (zone (net 0) (net_name "") (layer "In6.Cu") (hatch edge 0.508)
    (connect_pads no (clearance 0))
    (min_thickness 0.15) (filled_areas_thickness no)
    (keepout (tracks allowed) (vias allowed) (pads allowed) (copperpour not_allowed) (footprints allowed))
    (fill (thermal_gap 0.3) (thermal_bridge_width 0.2))
    (polygon
      (pts
        (xy 186.911001 83.055681)
        (xy 186.890044 82.950321)
        (xy 186.830362 82.861)
        (xy 186.741041 82.801318)
        (xy 186.635681 82.780361)
        (xy 186.530321 82.801318)
        (xy 186.441 82.861)
        (xy 186.381318 82.950321)
        (xy 186.360361 83.055681)
        (xy 186.381318 83.161041)
        (xy 186.441 83.250362)
        (xy 186.530321 83.310044)
        (xy 186.635681 83.331001)
        (xy 186.741041 83.310044)
        (xy 186.830362 83.250362)
        (xy 186.890044 83.161041)
      )
    )
  )
  (zone (net 0) (net_name "") (layer "In6.Cu") (hatch edge 0.508)
    (connect_pads no (clearance 0))
    (min_thickness 0.15) (filled_areas_thickness no)
    (keepout (tracks allowed) (vias allowed) (pads allowed) (copperpour not_allowed) (footprints allowed))
    (fill (thermal_gap 0.3) (thermal_bridge_width 0.2))
    (polygon
      (pts
        (xy 191.928 79.057)
        (xy 191.907043 78.95164)
        (xy 191.847361 78.862319)
        (xy 191.75804 78.802637)
        (xy 191.65268 78.78168)
        (xy 191.54732 78.802637)
        (xy 191.457999 78.862319)
        (xy 191.398317 78.95164)
        (xy 191.37736 79.057)
        (xy 191.398317 79.16236)
        (xy 191.457999 79.251681)
        (xy 191.54732 79.311363)
        (xy 191.65268 79.33232)
        (xy 191.75804 79.311363)
        (xy 191.847361 79.251681)
        (xy 191.907043 79.16236)
      )
    )
  )
  (zone (net 0) (net_name "") (layer "In6.Cu") (hatch edge 0.508)
    (connect_pads no (clearance 0))
    (min_thickness 0.15) (filled_areas_thickness no)
    (keepout (tracks allowed) (vias allowed) (pads allowed) (copperpour not_allowed) (footprints allowed))
    (fill (thermal_gap 0.3) (thermal_bridge_width 0.2))
    (polygon
      (pts
        (xy 191.932 78.059)
        (xy 191.911043 77.95364)
        (xy 191.851361 77.864319)
        (xy 191.76204 77.804637)
        (xy 191.65668 77.78368)
        (xy 191.55132 77.804637)
        (xy 191.461999 77.864319)
        (xy 191.402317 77.95364)
        (xy 191.38136 78.059)
        (xy 191.402317 78.16436)
        (xy 191.461999 78.253681)
        (xy 191.55132 78.313363)
        (xy 191.65668 78.33432)
        (xy 191.76204 78.313363)
        (xy 191.851361 78.253681)
        (xy 191.911043 78.16436)
      )
    )
  )
  (zone (net 0) (net_name "") (layer "In6.Cu") (hatch edge 0.508)
    (connect_pads no (clearance 0))
    (min_thickness 0.15) (filled_areas_thickness no)
    (keepout (tracks allowed) (vias allowed) (pads allowed) (copperpour not_allowed) (footprints allowed))
    (fill (thermal_gap 0.3) (thermal_bridge_width 0.2))
    (polygon
      (pts
        (xy 193.931 84.059)
        (xy 193.910043 83.95364)
        (xy 193.850361 83.864319)
        (xy 193.76104 83.804637)
        (xy 193.65568 83.78368)
        (xy 193.55032 83.804637)
        (xy 193.460999 83.864319)
        (xy 193.401317 83.95364)
        (xy 193.38036 84.059)
        (xy 193.401317 84.16436)
        (xy 193.460999 84.253681)
        (xy 193.55032 84.313363)
        (xy 193.65568 84.33432)
        (xy 193.76104 84.313363)
        (xy 193.850361 84.253681)
        (xy 193.910043 84.16436)
      )
    )
  )
  (zone (net 0) (net_name "") (layer "In6.Cu") (hatch edge 0.508)
    (connect_pads no (clearance 0))
    (min_thickness 0.15) (filled_areas_thickness no)
    (keepout (tracks allowed) (vias allowed) (pads allowed) (copperpour not_allowed) (footprints allowed))
    (fill (thermal_gap 0.3) (thermal_bridge_width 0.2))
    (polygon
      (pts
        (xy 194.925 80.06)
        (xy 194.904043 79.95464)
        (xy 194.844361 79.865319)
        (xy 194.75504 79.805637)
        (xy 194.64968 79.78468)
        (xy 194.54432 79.805637)
        (xy 194.454999 79.865319)
        (xy 194.395317 79.95464)
        (xy 194.37436 80.06)
        (xy 194.395317 80.16536)
        (xy 194.454999 80.254681)
        (xy 194.54432 80.314363)
        (xy 194.64968 80.33532)
        (xy 194.75504 80.314363)
        (xy 194.844361 80.254681)
        (xy 194.904043 80.16536)
      )
    )
  )
  (zone (net 0) (net_name "") (layer "In6.Cu") (hatch edge 0.508)
    (connect_pads no (clearance 0))
    (min_thickness 0.15) (filled_areas_thickness no)
    (keepout (tracks allowed) (vias allowed) (pads allowed) (copperpour not_allowed) (footprints allowed))
    (fill (thermal_gap 0.3) (thermal_bridge_width 0.2))
    (polygon
      (pts
        (xy 189.932 83.062)
        (xy 189.911043 82.95664)
        (xy 189.851361 82.867319)
        (xy 189.76204 82.807637)
        (xy 189.65668 82.78668)
        (xy 189.55132 82.807637)
        (xy 189.461999 82.867319)
        (xy 189.402317 82.95664)
        (xy 189.38136 83.062)
        (xy 189.402317 83.16736)
        (xy 189.461999 83.256681)
        (xy 189.55132 83.316363)
        (xy 189.65668 83.33732)
        (xy 189.76204 83.316363)
        (xy 189.851361 83.256681)
        (xy 189.911043 83.16736)
      )
    )
  )
  (zone (net 0) (net_name "") (layer "In6.Cu") (hatch edge 0.508)
    (connect_pads no (clearance 0))
    (min_thickness 0.15) (filled_areas_thickness no)
    (keepout (tracks allowed) (vias allowed) (pads allowed) (copperpour not_allowed) (footprints allowed))
    (fill (thermal_gap 0.3) (thermal_bridge_width 0.2))
    (polygon
      (pts
        (xy 193.92896 79.062637)
        (xy 193.908003 78.957277)
        (xy 193.848321 78.867956)
        (xy 193.759 78.808274)
        (xy 193.65364 78.787317)
        (xy 193.54828 78.808274)
        (xy 193.458959 78.867956)
        (xy 193.399277 78.957277)
        (xy 193.37832 79.062637)
        (xy 193.399277 79.167997)
        (xy 193.458959 79.257318)
        (xy 193.54828 79.317)
        (xy 193.65364 79.337957)
        (xy 193.759 79.317)
        (xy 193.848321 79.257318)
        (xy 193.908003 79.167997)
      )
    )
  )
  (zone (net 0) (net_name "") (layer "In6.Cu") (hatch edge 0.508)
    (connect_pads no (clearance 0))
    (min_thickness 0.15) (filled_areas_thickness no)
    (keepout (tracks allowed) (vias allowed) (pads allowed) (copperpour not_allowed) (footprints allowed))
    (fill (thermal_gap 0.3) (thermal_bridge_width 0.2))
    (polygon
      (pts
        (xy 193.931 85.059)
        (xy 193.910043 84.95364)
        (xy 193.850361 84.864319)
        (xy 193.76104 84.804637)
        (xy 193.65568 84.78368)
        (xy 193.55032 84.804637)
        (xy 193.460999 84.864319)
        (xy 193.401317 84.95364)
        (xy 193.38036 85.059)
        (xy 193.401317 85.16436)
        (xy 193.460999 85.253681)
        (xy 193.55032 85.313363)
        (xy 193.65568 85.33432)
        (xy 193.76104 85.313363)
        (xy 193.850361 85.253681)
        (xy 193.910043 85.16436)
      )
    )
  )
  (zone (net 0) (net_name "") (layer "In6.Cu") (hatch edge 0.508)
    (connect_pads no (clearance 0))
    (min_thickness 0.15) (filled_areas_thickness no)
    (keepout (tracks allowed) (vias allowed) (pads allowed) (copperpour not_allowed) (footprints allowed))
    (fill (thermal_gap 0.3) (thermal_bridge_width 0.2))
    (polygon
      (pts
        (xy 194.93032 84.05968)
        (xy 194.909363 83.95432)
        (xy 194.849681 83.864999)
        (xy 194.76036 83.805317)
        (xy 194.655 83.78436)
        (xy 194.54964 83.805317)
        (xy 194.460319 83.864999)
        (xy 194.400637 83.95432)
        (xy 194.37968 84.05968)
        (xy 194.400637 84.16504)
        (xy 194.460319 84.254361)
        (xy 194.54964 84.314043)
        (xy 194.655 84.335)
        (xy 194.76036 84.314043)
        (xy 194.849681 84.254361)
        (xy 194.909363 84.16504)
      )
    )
  )
  (zone (net 0) (net_name "") (layer "In6.Cu") (hatch edge 0.508)
    (connect_pads no (clearance 0))
    (min_thickness 0.15) (filled_areas_thickness no)
    (keepout (tracks allowed) (vias allowed) (pads allowed) (copperpour not_allowed) (footprints allowed))
    (fill (thermal_gap 0.3) (thermal_bridge_width 0.2))
    (polygon
      (pts
        (xy 195.928 86.063)
        (xy 195.907043 85.95764)
        (xy 195.847361 85.868319)
        (xy 195.75804 85.808637)
        (xy 195.65268 85.78768)
        (xy 195.54732 85.808637)
        (xy 195.457999 85.868319)
        (xy 195.398317 85.95764)
        (xy 195.37736 86.063)
        (xy 195.398317 86.16836)
        (xy 195.457999 86.257681)
        (xy 195.54732 86.317363)
        (xy 195.65268 86.33832)
        (xy 195.75804 86.317363)
        (xy 195.847361 86.257681)
        (xy 195.907043 86.16836)
      )
    )
  )
  (zone (net 0) (net_name "") (layer "In6.Cu") (hatch edge 0.508)
    (connect_pads no (clearance 0))
    (min_thickness 0.15) (filled_areas_thickness no)
    (keepout (tracks allowed) (vias allowed) (pads allowed) (copperpour not_allowed) (footprints allowed))
    (fill (thermal_gap 0.3) (thermal_bridge_width 0.2))
    (polygon
      (pts
        (xy 194.932 83.06)
        (xy 194.911043 82.95464)
        (xy 194.851361 82.865319)
        (xy 194.76204 82.805637)
        (xy 194.65668 82.78468)
        (xy 194.55132 82.805637)
        (xy 194.461999 82.865319)
        (xy 194.402317 82.95464)
        (xy 194.38136 83.06)
        (xy 194.402317 83.16536)
        (xy 194.461999 83.254681)
        (xy 194.55132 83.314363)
        (xy 194.65668 83.33532)
        (xy 194.76204 83.314363)
        (xy 194.851361 83.254681)
        (xy 194.911043 83.16536)
      )
    )
  )
  (zone (net 0) (net_name "") (layer "In6.Cu") (hatch edge 0.508)
    (connect_pads no (clearance 0))
    (min_thickness 0.15) (filled_areas_thickness no)
    (keepout (tracks allowed) (vias allowed) (pads allowed) (copperpour not_allowed) (footprints allowed))
    (fill (thermal_gap 0.3) (thermal_bridge_width 0.2))
    (polygon
      (pts
        (xy 195.934 77.06)
        (xy 195.913043 76.95464)
        (xy 195.853361 76.865319)
        (xy 195.76404 76.805637)
        (xy 195.65868 76.78468)
        (xy 195.55332 76.805637)
        (xy 195.463999 76.865319)
        (xy 195.404317 76.95464)
        (xy 195.38336 77.06)
        (xy 195.404317 77.16536)
        (xy 195.463999 77.254681)
        (xy 195.55332 77.314363)
        (xy 195.65868 77.33532)
        (xy 195.76404 77.314363)
        (xy 195.853361 77.254681)
        (xy 195.913043 77.16536)
      )
    )
  )
  (zone (net 0) (net_name "") (layer "In6.Cu") (hatch edge 0.508)
    (connect_pads no (clearance 0))
    (min_thickness 0.15) (filled_areas_thickness no)
    (keepout (tracks allowed) (vias allowed) (pads allowed) (copperpour not_allowed) (footprints allowed))
    (fill (thermal_gap 0.3) (thermal_bridge_width 0.2))
    (polygon
      (pts
        (xy 195.930957 82.06164)
        (xy 195.91 81.95628)
        (xy 195.850318 81.866959)
        (xy 195.760997 81.807277)
        (xy 195.655637 81.78632)
        (xy 195.550277 81.807277)
        (xy 195.460956 81.866959)
        (xy 195.401274 81.95628)
        (xy 195.380317 82.06164)
        (xy 195.401274 82.167)
        (xy 195.460956 82.256321)
        (xy 195.550277 82.316003)
        (xy 195.655637 82.33696)
        (xy 195.760997 82.316003)
        (xy 195.850318 82.256321)
        (xy 195.91 82.167)
      )
    )
  )
  (zone (net 9) (net_name "GND") (layers "In6.Cu" "In8.Cu") (hatch edge 0.508)
    (connect_pads yes (clearance 0.12))
    (min_thickness 0.15) (filled_areas_thickness no)
    (fill yes (thermal_gap 0.508) (thermal_bridge_width 0.15) (smoothing fillet) (radius 0.5))
    (polygon
      (pts
        (xy 259.886328 46.010016)
        (xy 259.886328 136.010016)
        (xy 106.986328 136.010016)
        (xy 106.986328 46.010016)
      )
    )
  )
  (zone (net 145) (net_name "1V8_FT") (layer "In7.Cu") (hatch edge 0.508)
    (priority 3)
    (connect_pads yes (clearance 0.15))
    (min_thickness 0.15) (filled_areas_thickness no)
    (fill yes (thermal_gap 0.508) (thermal_bridge_width 0.508) (smoothing fillet) (radius 0.5))
    (polygon
      (pts
        (xy 145.436328 113.660008)
        (xy 133.736328 113.760008)
        (xy 133.736328 109.260008)
        (xy 136.336328 109.260008)
        (xy 136.336328 104.360008)
        (xy 134.636328 104.360008)
        (xy 134.636328 102.560008)
        (xy 143.136328 102.560008)
        (xy 143.136328 99.260008)
        (xy 145.336328 99.260008)
      )
    )
  )
  (zone (net 0) (net_name "") (layer "In7.Cu") (hatch edge 0.508)
    (connect_pads (clearance 0))
    (min_thickness 0.254) (filled_areas_thickness no)
    (keepout (tracks allowed) (vias allowed) (pads allowed) (copperpour not_allowed) (footprints allowed))
    (fill (thermal_gap 0.508) (thermal_bridge_width 0.508))
    (polygon
      (pts
        (xy 244.4 109.680525)
        (xy 246.689874 109.680525)
        (xy 247.669874 108.700525)
        (xy 248.569874 108.700525)
        (xy 249.749874 109.880525)
        (xy 249.749874 119.030525)
        (xy 249.389874 119.390525)
        (xy 241.219874 119.390525)
        (xy 236.079874 114.250525)
        (xy 204.159874 114.250525)
        (xy 203.079874 115.330525)
        (xy 201.049874 115.330525)
        (xy 199.379874 117.000525)
        (xy 197.489874 117.000525)
        (xy 193 121.5)
        (xy 175.8 121.5)
        (xy 171.3 117.000525)
        (xy 157.049874 117.000525)
        (xy 154.199874 114.150525)
        (xy 154.199874 110.500525)
        (xy 164.969874 110.500525)
        (xy 165.299874 110.170525)
        (xy 172.139874 110.170525)
        (xy 174.509874 107.800525)
        (xy 189.719874 107.800525)
        (xy 189.999874 108.080525)
        (xy 200.489874 108.080525)
        (xy 201.019874 107.550525)
        (xy 208.16 107.56)
        (xy 208.31 107.41)
        (xy 238.205209 107.401153)
        (xy 242.1 107.4)
      )
    )
  )
  (zone (net 0) (net_name "") (layer "In7.Cu") (hatch edge 0.508)
    (connect_pads no (clearance 0))
    (min_thickness 0.5) (filled_areas_thickness no)
    (keepout (tracks allowed) (vias allowed) (pads allowed) (copperpour not_allowed) (footprints allowed))
    (fill (thermal_gap 1) (thermal_bridge_width 1))
    (polygon
      (pts
        (xy 247.838194 105.3)
        (xy 246.588194 106.6)
        (xy 233.238194 106.6)
        (xy 231.388194 104.75)
        (xy 209.538194 104.75)
        (xy 207.338194 106.95)
        (xy 200.748194 106.95)
        (xy 200.248194 107.45)
        (xy 190.888194 107.45)
        (xy 190.388194 106.95)
        (xy 179.738194 106.95)
        (xy 176.638194 103.85)
        (xy 176.638194 97.5)
        (xy 176 97.5)
        (xy 172.4 101.060008)
        (xy 170.636328 101.060008)
        (xy 170.636328 98.8)
        (xy 172.1 97.4)
        (xy 172.1 93.2)
        (xy 174.6 90.8)
        (xy 176.638194 90.8)
        (xy 176.638194 90.7)
        (xy 176.938194 90.5)
        (xy 179.788194 90.5)
        (xy 180.4 90.5)
        (xy 181.1 89.8)
        (xy 185.888194 89.8)
        (xy 188.7 89.8)
        (xy 188.7 87.9)
        (xy 190.655836 85.9)
        (xy 199.4 85.9)
        (xy 200.1 86.6)
        (xy 214.5 86.6)
        (xy 217.9 83.2)
        (xy 222.5 83.2)
        (xy 223.2 82.5)
        (xy 225.3 82.5)
        (xy 225.288194 81.6)
        (xy 227.488194 79.4)
        (xy 231.388194 79.4)
        (xy 231.388194 82.9)
        (xy 228.988194 82.9)
        (xy 228.288194 83.6)
        (xy 228.288194 88.4)
        (xy 225.788194 90.9)
        (xy 236.688194 90.9)
        (xy 241.588194 86.04)
        (xy 245.588194 86.04)
        (xy 246.688194 84.9)
        (xy 251.188194 84.9)
        (xy 251.188194 86.5)
        (xy 247.838194 86.5)
        (xy 247.838194 89.8)
      )
    )
  )
  (zone (net 0) (net_name "") (layer "In7.Cu") (hatch edge 0.508)
    (connect_pads no (clearance 0))
    (min_thickness 0.5) (filled_areas_thickness no)
    (keepout (tracks allowed) (vias allowed) (pads allowed) (copperpour not_allowed) (footprints allowed))
    (fill (thermal_gap 1) (thermal_bridge_width 1))
    (polygon
      (pts
        (xy 209.956021 69.550144)
        (xy 203.356021 76.200144)
        (xy 185.256021 76.200144)
        (xy 184.456021 77.000144)
        (xy 184.406021 86.050144)
        (xy 180.856021 89.600144)
        (xy 179.656021 89.600144)
        (xy 178.906021 90.350144)
        (xy 176.906021 90.350144)
        (xy 176.306021 89.750144)
        (xy 174.756021 89.750144)
        (xy 174.006021 89.000144)
        (xy 174.006021 87.500144)
        (xy 172.506021 86.000144)
        (xy 172.506021 82.650144)
        (xy 174.106021 81.050144)
        (xy 174.656021 81.050144)
        (xy 174.656021 80.800144)
        (xy 174.456021 80.600144)
        (xy 174.456021 79.850144)
        (xy 173.956021 79.850144)
        (xy 173.306021 80.500144)
        (xy 173.306021 80.750144)
        (xy 172.056021 82.000144)
        (xy 171.256021 81.950144)
        (xy 167.806021 85.400144)
        (xy 155.906021 85.400144)
        (xy 152.606021 82.100144)
        (xy 152.606021 79.450144)
        (xy 154.006021 78.050144)
        (xy 156.056021 78.050144)
        (xy 157.006021 77.100144)
        (xy 160.456021 77.100144)
        (xy 161.206021 77.850144)
        (xy 163.906021 77.900144)
        (xy 166.756021 75.050144)
        (xy 173.306021 75.050144)
        (xy 173.756021 75.500144)
        (xy 174.206021 75.500144)
        (xy 174.206021 74.900144)
        (xy 173.656021 74.350144)
        (xy 173.656021 65.250144)
        (xy 178.256021 60.650144)
        (xy 196.106021 60.650144)
        (xy 198.006021 58.750144)
        (xy 198.006021 54.750144)
        (xy 198.706021 54.050144)
        (xy 209.306021 54.050144)
        (xy 209.956021 54.700144)
      )
    )
  )
  (zone (net 308) (net_name "NC") (layer "In8.Cu") (hatch edge 0.508)
    (priority 2)
    (connect_pads yes (clearance 0.12))
    (min_thickness 0.15) (filled_areas_thickness no)
    (fill yes (thermal_gap 0.508) (thermal_bridge_width 0.508) (smoothing fillet) (radius 0.5))
    (polygon
      (pts
        (xy 259.802328 135.960008)
        (xy 107.002328 135.960008)
        (xy 107.002328 110.160008)
        (xy 109.602328 110.160008)
        (xy 109.602328 130.060008)
        (xy 254.252328 130.060008)
        (xy 254.3 66.6)
        (xy 252.625 64.9)
        (xy 247.325627 64.899637)
        (xy 247.350627 46.024637)
        (xy 259.852328 46.060008)
      )
    )
  )
  (zone (net 184) (net_name "VPP") (layer "In8.Cu") (hatch edge 0.508)
    (priority 3)
    (connect_pads yes (clearance 0.12))
    (min_thickness 0.15) (filled_areas_thickness no)
    (fill yes (thermal_gap 0.508) (thermal_bridge_width 0.508) (smoothing fillet) (radius 0.5))
    (polygon
      (pts
        (xy 122.086328 57.560008)
        (xy 122.086328 69.510008)
        (xy 125.986328 73.410008)
        (xy 125.986328 86.560008)
        (xy 122.386328 86.560008)
        (xy 122.386328 74.160008)
        (xy 119.336328 71.110008)
        (xy 119.336328 55.610008)
        (xy 119.336328 53.710008)
        (xy 120.386328 53.710008)
        (xy 122.086328 53.710008)
      )
    )
  )
  (zone (net 103) (net_name "VIN") (layer "In8.Cu") (hatch edge 0.508)
    (priority 1)
    (connect_pads yes (clearance 0.12))
    (min_thickness 0.15) (filled_areas_thickness no)
    (fill yes (thermal_gap 0.508) (thermal_bridge_width 0.508) (smoothing fillet) (radius 0.5))
    (polygon
      (pts
        (xy 121.5 103.860008)
        (xy 121.5 135.960008)
        (xy 107.036328 135.960008)
        (xy 107.036328 111.060008)
        (xy 113.75 111.060008)
        (xy 113.75 107.875)
        (xy 111.036328 107.910008)
        (xy 111.036328 106.25)
        (xy 116.75 106.25)
        (xy 116.75 102)
        (xy 119.236328 102)
        (xy 119.236328 103.860008)
      )
    )
  )
  (zone (net 144) (net_name "1V8_SYS") (layer "In8.Cu") (hatch edge 0.508)
    (priority 2)
    (connect_pads yes (clearance 0.15))
    (min_thickness 0.15) (filled_areas_thickness no)
    (fill yes (thermal_gap 0.508) (thermal_bridge_width 0.508) (smoothing fillet) (radius 0.5))
    (polygon
      (pts
        (xy 155.9 85.4)
        (xy 168.8 85.4)
        (xy 173.65 90.25)
        (xy 179.1 90.25)
        (xy 179.65 89.7)
        (xy 180.9 89.7)
        (xy 184.9 85.7)
        (xy 187.7 85.7)
        (xy 189.75 87.75)
        (xy 191.85 87.75)
        (xy 192 87.9)
        (xy 192 88.5)
        (xy 192 91.25)
        (xy 191.85 91.4)
        (xy 189.85 91.4)
        (xy 186.94 94.33)
        (xy 185.5 94.33)
        (xy 185.37 94.2)
        (xy 183.8 94.2)
        (xy 183.1 93.5)
        (xy 183.1 92.9)
        (xy 181.9 91.7)
        (xy 180.5 91.7)
        (xy 180.3 91.9)
        (xy 179.5 91.9)
        (xy 178.8 92.6)
        (xy 176.7 92.6)
        (xy 173.1 96.2)
        (xy 164.8 96.2)
        (xy 157.6 96.2)
        (xy 154.8 99)
        (xy 143.2 99)
        (xy 143.2 86.5)
        (xy 126.1 86.509)
        (xy 126.1 77.85)
        (xy 148.3 77.85)
      )
    )
  )
  (zone (net 0) (net_name "") (layer "In9.Cu") (hatch edge 0.508)
    (connect_pads yes (clearance 0))
    (min_thickness 0.15) (filled_areas_thickness no)
    (keepout (tracks allowed) (vias allowed) (pads allowed) (copperpour not_allowed) (footprints allowed))
    (fill (thermal_gap 0.508) (thermal_bridge_width 0.15))
    (polygon
      (pts
        (xy 237 90.7)
        (xy 236.3 91.4)
        (xy 236.3 94)
        (xy 238.2 94)
        (xy 244.8 100.6)
        (xy 244.8 103.8)
        (xy 248.8 107.8)
        (xy 248.8 115.3)
        (xy 246.4 117.7)
        (xy 244.9 117.7)
        (xy 244.4 118.2)
        (xy 244.4 122.9)
        (xy 243.1 124.2)
        (xy 241.1 124.2)
        (xy 239.9 123)
        (xy 239.9 118.5)
        (xy 233.3 111.9)
        (xy 233.3 108.4)
        (xy 230 105.1)
        (xy 211.1 105.1)
        (xy 210.9 104.9)
        (xy 194.6 104.9)
        (xy 189.1 99.4)
        (xy 173.1 99.4)
        (xy 173.1 95.859992)
        (xy 172.140008 94.9)
        (xy 172.140008 92.6)
        (xy 176.3 88.440008)
        (xy 191.640008 88.440008)
        (xy 192.6 89.4)
        (xy 196.846985 89.4)
        (xy 198.3 90.853015)
        (xy 232.1 90.853015)
        (xy 233.353015 89.6)
        (xy 233.353015 88.146985)
        (xy 234.7 86.8)
        (xy 237 86.8)
      )
    )
  )
  (zone (net 0) (net_name "") (layer "In9.Cu") (hatch edge 0.508)
    (connect_pads (clearance 0))
    (min_thickness 0.254) (filled_areas_thickness no)
    (keepout (tracks allowed) (vias allowed) (pads allowed) (copperpour not_allowed) (footprints allowed))
    (fill (thermal_gap 0.508) (thermal_bridge_width 0.508))
    (polygon
      (pts
        (xy 135.2 58.55)
        (xy 140.75 64.1)
        (xy 163.05 64.1)
        (xy 164.15 63)
        (xy 164.15 59.7)
        (xy 170.136328 53.710008)
        (xy 178.4 53.710008)
        (xy 179.15 54.45)
        (xy 179.15 58.45)
        (xy 183.55 58.45)
        (xy 183.55 54.35)
        (xy 184.35 53.55)
        (xy 194.85 53.55)
        (xy 196.1 54.8)
        (xy 196.1 57.5)
        (xy 201.6 63)
        (xy 201.6 71.95)
        (xy 203.05 71.95)
        (xy 214.2 60.7)
        (xy 232.9 60.75)
        (xy 234.7 58.95)
        (xy 234.7 54.55)
        (xy 235.45 53.8)
        (xy 247.3 53.8)
        (xy 248.05 54.55)
        (xy 248.05 71.25)
        (xy 239.45 79.85)
        (xy 224.55 79.85)
        (xy 215.3 89.1)
        (xy 210.55 89.1)
        (xy 210.4 88.95)
        (xy 209.95 88.95)
        (xy 209.8 89.1)
        (xy 201.7 89.1)
        (xy 200.15 87.55)
        (xy 190.325 87.55)
        (xy 189.9 87.125)
        (xy 189.9 82.9)
        (xy 189.6 82.6)
        (xy 187.5 82.6)
        (xy 183.5 86.6)
        (xy 177.35 86.6)
        (xy 175.4 84.65)
        (xy 175.4 83.15)
        (xy 173.65 81.4)
        (xy 173.65 79.35)
        (xy 172.5 78.2)
        (xy 133.15 78.2)
        (xy 122.9 67.95)
        (xy 122.9 54.45)
        (xy 123.55 53.8)
        (xy 134.45 53.8)
        (xy 135.2 54.55)
      )
    )
  )
  (zone (net 0) (net_name "") (layer "In9.Cu") (hatch edge 0.508)
    (connect_pads (clearance 0))
    (min_thickness 0.254) (filled_areas_thickness no)
    (keepout (tracks allowed) (vias allowed) (pads allowed) (copperpour not_allowed) (footprints allowed))
    (fill (thermal_gap 0.508) (thermal_bridge_width 0.508))
    (polygon
      (pts
        (xy 192.15 106.35)
        (xy 217.8 106.35)
        (xy 218.35 105.8)
        (xy 221.55 105.8)
        (xy 229.65 113.9)
        (xy 235.8 113.9)
        (xy 238 116.1)
        (xy 238 120.75)
        (xy 223.9 120.75)
        (xy 218.1 114.95)
        (xy 218.1 111.313672)
        (xy 217.5 110.713672)
        (xy 190.5 110.713672)
        (xy 186.5 106.713672)
        (xy 173.05 106.713672)
        (xy 170.636328 104.3)
        (xy 170.15 104.3)
        (xy 168.15 106.3)
        (xy 163.15 106.3)
        (xy 162.8 105.95)
        (xy 155.1 105.95)
        (xy 154.6 106.45)
        (xy 154.6 109.3)
        (xy 153.55 110.35)
        (xy 151.35 110.35)
        (xy 148.95 107.95)
        (xy 148.95 102)
        (xy 149.5 101.45)
        (xy 166.65 101.5)
        (xy 168.75 99.4)
        (xy 170.636328 99.404)
        (xy 176.406 99.384)
        (xy 176.414552 102.51899)
        (xy 176.95 103.05)
        (xy 188.85 103.05)
      )
    )
  )
  (zone (net 103) (net_name "VIN") (layer "In9.Cu") (hatch edge 0.508)
    (priority 1)
    (connect_pads yes (clearance 0.125))
    (min_thickness 0.125) (filled_areas_thickness no)
    (fill yes (thermal_gap 0.15) (thermal_bridge_width 0.151))
    (polygon
      (pts
        (xy 194.45 124.65)
        (xy 219.5 124.6)
        (xy 220.3 123.8)
        (xy 220.3 121.5)
        (xy 221.75 121.45)
        (xy 225.9 125.6)
        (xy 225.9 127.5)
        (xy 218.7 127.5)
        (xy 218.4 127.8)
        (xy 218.4 135.95)
        (xy 107.125 135.95)
        (xy 107.125 116.6)
        (xy 115.559689 116.594658)
        (xy 115.550682 124.774973)
        (xy 116.2 125.4)
        (xy 174.750049 125.496143)
        (xy 177 123.25)
        (xy 177 116.65)
        (xy 179.225 114.425)
        (xy 184.25 114.45)
      )
    )
  )
  (zone (net 535) (net_name "12P0V") (layer "In9.Cu") (hatch edge 0.508)
    (priority 1)
    (connect_pads (clearance 0.125))
    (min_thickness 0.1) (filled_areas_thickness no)
    (fill yes (thermal_gap 0.2) (thermal_bridge_width 0.12))
    (polygon
      (pts
        (xy 259.75 135.9)
        (xy 218.65 135.9)
        (xy 218.65 130.75)
        (xy 245.4 130.75)
        (xy 256.35 119.8)
        (xy 256.4 85.3)
        (xy 252.3 81.2)
        (xy 252.3 78.45)
        (xy 259.75 78.45)
      )
    )
  )
  (zone (net 9) (net_name "GND") (layer "In10.Cu") (hatch edge 0.508)
    (connect_pads yes (clearance 0.12))
    (min_thickness 0.15) (filled_areas_thickness no)
    (fill yes (thermal_gap 0.508) (thermal_bridge_width 0.15) (smoothing fillet) (radius 0.5))
    (polygon
      (pts
        (xy 259.886328 46.010016)
        (xy 259.886328 136.010016)
        (xy 106.986328 136.010016)
        (xy 106.986328 46.010016)
      )
    )
  )
  (zone (net 306) (net_name "1V2_SYS") (layer "In10.Cu") (hatch edge 0.508)
    (priority 3)
    (connect_pads yes (clearance 0.12))
    (min_thickness 0.15) (filled_areas_thickness no)
    (fill yes (thermal_gap 0.508) (thermal_bridge_width 0.508) (smoothing fillet) (radius 0.5))
    (polygon
      (pts
        (xy 163.786328 99.360008)
        (xy 148.89838 99.350991)
        (xy 148.85 109.25)
        (xy 156.4 116.8)
        (xy 156.386328 122.310008)
        (xy 145.636328 122.310008)
        (xy 145.636328 109.160008)
        (xy 145.636328 92.95)
        (xy 146.300009 92.309385)
        (xy 156.3 92.3)
        (xy 157.886328 91.260008)
        (xy 163.786328 91.260008)
      )
    )
  )
  (zone (net 184) (net_name "VPP") (layer "B.Cu") (hatch edge 0.508)
    (connect_pads yes (clearance 0.15))
    (min_thickness 0.15) (filled_areas_thickness no)
    (fill yes (thermal_gap 0.508) (thermal_bridge_width 0.508) (smoothing fillet) (radius 0.5))
    (polygon
      (pts
        (xy 122.126328 56.780008)
        (xy 119.336328 56.780008)
        (xy 119.336328 54.640008)
        (xy 122.126328 54.640008)
      )
    )
  )
  (zone (net 184) (net_name "VPP") (layer "B.Cu") (hatch edge 0.508)
    (connect_pads yes (clearance 0.15))
    (min_thickness 0.15) (filled_areas_thickness no)
    (fill yes (thermal_gap 0.508) (thermal_bridge_width 0.508) (smoothing fillet) (radius 0.5))
    (polygon
      (pts
        (xy 122.206328 59.720008)
        (xy 119.306328 59.740008)
        (xy 119.306328 57.930008)
        (xy 122.206328 57.930008)
      )
    )
  )
  (zone (net 186) (net_name "VTT") (layer "B.Cu") (hatch edge 0.508)
    (priority 1)
    (connect_pads yes (clearance 0.15))
    (min_thickness 0.15) (filled_areas_thickness no)
    (fill yes (thermal_gap 0.508) (thermal_bridge_width 0.508) (smoothing fillet) (radius 0.5))
    (polygon
      (pts
        (xy 182.386328 54.1)
        (xy 182.386328 60.610008)
        (xy 181.136328 60.610008)
        (xy 181.136328 54.1)
      )
    )
  )
  (zone (net 360) (net_name "/Ethernet/VDD") (layer "B.Cu") (hatch edge 0.508)
    (connect_pads yes (clearance 0.15))
    (min_thickness 0.254) (filled_areas_thickness no)
    (fill yes (thermal_gap 0.508) (thermal_bridge_width 0.508))
    (polygon
      (pts
        (xy 193.8 134.6)
        (xy 193.7 134.7)
        (xy 188.6 134.7)
        (xy 188.5 134.6)
        (xy 188.5 125.95)
        (xy 188.5 117.4)
        (xy 188.6 117.3)
        (xy 193.7 117.3)
        (xy 193.8 117.4)
      )
    )
  )
  (zone (net 604) (net_name "GNDD") (layer "B.Cu") (hatch edge 0.508)
    (connect_pads yes (clearance 0.15))
    (min_thickness 0.254) (filled_areas_thickness no)
    (fill yes (thermal_gap 0.508) (thermal_bridge_width 0.508))
    (polygon
      (pts
        (xy 186 134.3)
        (xy 185.9 134.4)
        (xy 183.8 134.4)
        (xy 181.6 134.4)
        (xy 181.46 134.3)
        (xy 181.46 130.4)
        (xy 182.7 130.4)
        (xy 182.8 130.3)
        (xy 184.1 130.3)
        (xy 184.1 131.9)
        (xy 185.9 131.9)
        (xy 186 132)
      )
    )
  )
  (zone (net 143) (net_name "3V3_SYS") (layer "B.Cu") (hatch edge 0.508)
    (connect_pads (clearance 0.125))
    (min_thickness 0.1) (filled_areas_thickness no)
    (fill yes (thermal_gap 0.2) (thermal_bridge_width 0.12))
    (polygon
      (pts
        (xy 257.9 72.9)
        (xy 254.3 72.9)
        (xy 253.9 73.3)
        (xy 253.9 74.25)
        (xy 254.95 75.3)
        (xy 254.95 77.2)
        (xy 253.3 78.85)
        (xy 253.3 80.65)
        (xy 251.9 80.65)
        (xy 251.9 77.95)
        (xy 253.25 76.6)
        (xy 253.25 76.25)
        (xy 251.9 74.9)
        (xy 251.9 72.9)
        (xy 253.2 71.6)
        (xy 257.9 71.6)
      )
    )
  )
  (zone (net 77) (net_name "VDDQ") (layer "B.Cu") (hatch edge 0.508)
    (connect_pads no (clearance 0.15))
    (min_thickness 0.15) (filled_areas_thickness no)
    (fill yes (thermal_gap 0.3) (thermal_bridge_width 0.2) (smoothing fillet) (radius 0.5))
    (polygon
      (pts
        (xy 247.900378 47.174985)
        (xy 247.9 58.1)
        (xy 217.2 88.725)
        (xy 199.95 88.7)
        (xy 197.55 86.3)
        (xy 188.1 86.3)
        (xy 187.5 85.7)
        (xy 180.2 85.7)
        (xy 180.2 87.5)
        (xy 181 87.5)
        (xy 181 91.4)
        (xy 177.1 91.4)
        (xy 173.2 95.3)
        (xy 171.3 95.3)
        (xy 162.7 86.7)
        (xy 162.7 79.1)
        (xy 159.1 75.5)
        (xy 134.9 75.5)
        (xy 128.9 81.5)
        (xy 115.9 81.5)
        (xy 115.9 71.1)
        (xy 120.4 66.6)
        (xy 123.8 66.6)
        (xy 125.1 65.3)
        (xy 125.1 53.075)
        (xy 160.5 53.1)
        (xy 162.425 55.025)
        (xy 162.4 57.425)
        (xy 161.7 58.125)
        (xy 161.7 58.825)
        (xy 161.875 59)
        (xy 162.725 59)
        (xy 163.6 58.125)
        (xy 163.6 48.7)
        (xy 165.100378 47.199985)
      )
    )
  )
  (zone (net 103) (net_name "VIN") (layer "B.Cu") (hatch edge 0.508)
    (connect_pads yes (clearance 0.125))
    (min_thickness 0.125) (filled_areas_thickness no)
    (fill yes (thermal_gap 0.15) (thermal_bridge_width 0.151))
    (polygon
      (pts
        (xy 183.6 114.5)
        (xy 184.2 115.1)
        (xy 184.2 116.1)
        (xy 178.6 116.1)
        (xy 178.6 111)
        (xy 183.6 111)
      )
    )
  )
  (zone (net 360) (net_name "/Ethernet/VDD") (layer "B.Cu") (hatch edge 0.508)
    (connect_pads yes (clearance 0.15))
    (min_thickness 0.254) (filled_areas_thickness no)
    (fill yes (thermal_gap 0.508) (thermal_bridge_width 0.508))
    (polygon
      (pts
        (xy 180 123.8)
        (xy 179.4 124.4)
        (xy 179.4 125.2)
        (xy 179.9 125.7)
        (xy 179.9 126.67)
        (xy 179.5 126.67)
        (xy 179.43 126.6)
        (xy 175.5 126.6)
        (xy 175.4 126.5)
        (xy 175.4 125.1)
        (xy 176.6 123.9)
        (xy 178.3 123.9)
        (xy 178.9 123.3)
        (xy 178.9 122)
        (xy 180 122)
      )
    )
  )
  (zone (net 9) (net_name "GND") (layer "B.Cu") (hatch edge 0.508)
    (connect_pads yes (clearance 0.2))
    (min_thickness 0.5) (filled_areas_thickness no)
    (fill yes (thermal_gap 0.508) (thermal_bridge_width 0.508))
    (polygon
      (pts
        (xy 234.75 98.9)
        (xy 241.35 105.5)
        (xy 241.35 120.3)
        (xy 227.7 120.3)
        (xy 227.7 116.2)
        (xy 222.7 111.2)
        (xy 215.6 111.2)
        (xy 212.675 108.275)
        (xy 212.675 107.225)
        (xy 230.8 89.1)
        (xy 231.4 88.5)
        (xy 234.75 88.5)
      )
    )
  )
  (zone (net 604) (net_name "GNDD") (layer "B.Cu") (hatch edge 0.508)
    (connect_pads yes (clearance 0.15))
    (min_thickness 0.254) (filled_areas_thickness no)
    (fill yes (thermal_gap 0.508) (thermal_bridge_width 0.508))
    (polygon
      (pts
        (xy 198.6 134.7)
        (xy 196.4 134.7)
        (xy 196.3 134.6)
        (xy 196.3 131.7)
        (xy 196.2 131.6)
        (xy 195.5 131.6)
        (xy 195.4 131.5)
        (xy 195.4 130.4)
        (xy 195.4 129.3)
        (xy 195.5 129.2)
        (xy 196.2 129.2)
        (xy 196.3 129.1)
        (xy 196.3 117.4)
        (xy 196.4 117.3)
        (xy 198.5 117.3)
        (xy 198.6 117.4)
      )
    )
  )
  (zone (net 9) (net_name "GND") (layer "B.Cu") (hatch edge 0.508)
    (connect_pads yes (clearance 0.15))
    (min_thickness 0.254) (filled_areas_thickness no)
    (fill yes (thermal_gap 0.508) (thermal_bridge_width 0.508))
    (polygon
      (pts
        (xy 192.5 110.8)
        (xy 192.5 115)
        (xy 192.4 115.1)
        (xy 189.5 115.1)
        (xy 189.4 115)
        (xy 189.4 110.8)
        (xy 189.5 110.7)
        (xy 192.4 110.7)
      )
    )
  )
  (zone (net 864) (net_name "VIN_POE") (layer "B.Cu") (hatch edge 0.508)
    (connect_pads yes (clearance 0.15))
    (min_thickness 0.254) (filled_areas_thickness no)
    (fill yes (thermal_gap 0.508) (thermal_bridge_width 0.508))
    (polygon
      (pts
        (xy 198.692177 114.8)
        (xy 198.492177 115)
        (xy 194.492177 115)
        (xy 194.392177 114.9)
        (xy 194.392177 110.7)
        (xy 194.192177 110.5)
        (xy 186.1 110.5)
        (xy 185.9 110.7)
        (xy 185.9 114.40558)
        (xy 185.7 114.6)
        (xy 184.3 114.6)
        (xy 184.2 114.5)
        (xy 184.2 109.4)
        (xy 184.4 109.2)
        (xy 198.6 109.2)
        (xy 198.7 109.3)
      )
    )
  )
  (zone (net 103) (net_name "VIN") (layer "B.Cu") (hatch edge 0.508)
    (connect_pads yes (clearance 0.125))
    (min_thickness 0.125) (filled_areas_thickness no)
    (fill yes (thermal_gap 0.15) (thermal_bridge_width 0.151))
    (polygon
      (pts
        (xy 211 135.2)
        (xy 203.3 135.2)
        (xy 203.3 130.1)
        (xy 211 130.1)
      )
    )
  )
  (zone (net 381) (net_name "/Ethernet/VSS") (layer "B.Cu") (hatch edge 0.508)
    (connect_pads yes (clearance 0.15))
    (min_thickness 0.254) (filled_areas_thickness no)
    (fill yes (thermal_gap 0.508) (thermal_bridge_width 0.508))
    (polygon
      (pts
        (xy 183.2 122.1)
        (xy 183.2 123.7)
        (xy 183.3 123.8)
        (xy 187.6 123.8)
        (xy 187.7 123.9)
        (xy 187.7 125.5)
        (xy 187.6 125.6)
        (xy 182.61 125.6)
        (xy 182.44 125.77)
        (xy 182.44 130.04)
        (xy 179.58 130.04)
        (xy 179.58 127.18)
        (xy 181.3 127.18)
        (xy 181.4 127.08)
        (xy 181.4 125.7)
        (xy 182 125.1)
        (xy 182 123.9)
        (xy 181.8 123.7)
        (xy 181.8 122.1)
        (xy 181.9 122)
        (xy 183.1 122)
      )
    )
  )
  (zone (net 306) (net_name "1V2_SYS") (layer "B.Cu") (hatch edge 0.508)
    (connect_pads no (clearance 0.15))
    (min_thickness 0.1) (filled_areas_thickness no)
    (fill yes (thermal_gap 0.3) (thermal_bridge_width 0.12))
    (polygon
      (pts
        (xy 197.575 91.8)
        (xy 197.6 91.8)
        (xy 200 89.4)
        (xy 217.1 89.4)
        (xy 217.1 95.55)
        (xy 209.875 102.8)
        (xy 208.65 102.8)
        (xy 205.95 105.5)
        (xy 198.796735 105.503269)
        (xy 194.8 105.5)
        (xy 194.1 104.8)
        (xy 194.1 94.985)
        (xy 192.915 93.8)
        (xy 192.915 92.3)
        (xy 194.1 92.3)
        (xy 194.4 92)
        (xy 194.4 91.8)
        (xy 195.3 91.8)
        (xy 195.4 91.8)
      )
    )
  )
  (zone (net 535) (net_name "12P0V") (layer "B.Cu") (hatch edge 0.508)
    (connect_pads (clearance 0.125))
    (min_thickness 0.1) (filled_areas_thickness no)
    (fill yes (thermal_gap 0.2) (thermal_bridge_width 0.12))
    (polygon
      (pts
        (xy 221.2 135.197157)
        (xy 211.55 135.197157)
        (xy 211.55 130.05)
        (xy 218.7 130.05)
        (xy 221.2 132.55)
      )
    )
  )
  (zone (net 0) (net_name "") (layer "F.SilkS") (hatch edge 0.508)
    (connect_pads yes (clearance 0.15))
    (min_thickness 0.15) (filled_areas_thickness no)
    (fill yes (thermal_gap 0.508) (thermal_bridge_width 0.508) (smoothing fillet) (radius 0.5))
    (polygon
      (pts
        (xy 112.736328 67.26054)
        (xy 112.736328 80.56054)
        (xy 108.836328 80.56054)
        (xy 108.836328 67.26054)
      )
    )
  )
)
